G04 ================== begin FILE IDENTIFICATION RECORD ==================*
G04 Layout Name:  9127_F0T_Expander_BD_F_v02_0110_1240.brd*
G04 Film Name:    gnd*
G04 File Format:  Gerber RS274X*
G04 File Origin:  Cadence Allegro 17.2-S081*
G04 Origin Date:  Wed Jan 11 16:06:14 2023*
G04 *
G04 Layer:  DRAWING FORMAT/TITLE_BLOCK_A*
G04 Layer:  PIN/SPECIAL_DRILL*
G04 Layer:  DRAWING FORMAT/TITLE_BLOCK*
G04 Layer:  VIA CLASS/GND*
G04 Layer:  PIN/GND*
G04 Layer:  MANUFACTURING/PHOTOPLOT_OUTLINE*
G04 Layer:  ETCH/GND*
G04 Layer:  DRAWING FORMAT/TITLE_DATA_GND*
G04 *
G04 Offset:    (0.00 0.00)*
G04 Mirror:    No*
G04 Mode:      Negative*
G04 Rotation:  0*
G04 FullContactRelief:  No*
G04 UndefLineWidth:     6.00*
G04 ================== end FILE IDENTIFICATION RECORD ====================*
%FSLAX25Y25*MOIN*%
%IR0*IPPOS*OFA0.00000B0.00000*MIA0B0*SFA1.00000B1.00000*%
%ADD15C,.03*%
%ADD50C,.06*%
%ADD22C,.024*%
%ADD52C,.061*%
%ADD32C,.0322*%
%ADD42C,.071*%
%AMMACRO28*
4,1,36,0.0,.01,
-.001736,.009848,
-.00342,.009397,
-.005,.00866,
-.006428,.00766,
-.00766,.006428,
-.00866,.005,
-.009397,.00342,
-.009848,.001736,
-.01,0.0,
-.009848,-.001736,
-.009397,-.00342,
-.00866,-.005,
-.00766,-.006428,
-.006428,-.00766,
-.005,-.00866,
-.00342,-.009397,
-.001736,-.009848,
0.0,-.01,
.001736,-.009848,
.00342,-.009397,
.005,-.00866,
.006428,-.00766,
.00766,-.006428,
.00866,-.005,
.009397,-.00342,
.009848,-.001736,
.01,0.0,
.009848,.001736,
.009397,.00342,
.00866,.005,
.00766,.006428,
.006428,.00766,
.005,.00866,
.00342,.009397,
.001736,.009848,
0.0,.01,
0.0*
%
%ADD28MACRO28*%
%ADD27C,.026*%
%ADD48C,.082*%
%ADD40C,.028*%
%AMMACRO36*
4,1,20,-.0075,-.05555,
-.0075,-.06273,
-.013677,-.060878,
-.019439,-.057981,
-.024611,-.054127,
-.029034,-.049434,
-.032576,-.044045,
-.035127,-.038122,
-.036612,-.031846,
-.037,-.0265,
-.037,-.0075,
-.03,-.0075,
-.03,-.0265,
-.029544,-.03171,
-.028191,-.036762,
-.02598,-.041502,
-.022981,-.045786,
-.019282,-.049484,
-.014998,-.052484,
-.010258,-.054694,
-.0075,-.05555,
270.*
4,1,20,.0075,-.06273,
.0075,-.05555,
.01243,-.053806,
.016983,-.051232,
.02102,-.047906,
.024418,-.043931,
.027073,-.039425,
.028906,-.034527,
.029861,-.029385,
.03,-.0265,
.03,-.0075,
.037,-.0075,
.037,-.0265,
.036438,-.032925,
.034769,-.039154,
.032043,-.044999,
.028344,-.050282,
.023784,-.054842,
.018501,-.058541,
.012656,-.061266,
.0075,-.06273,
270.*
4,1,20,-.0075,.06273,
-.0075,.05555,
-.01243,.053806,
-.016983,.051232,
-.02102,.047906,
-.024418,.043931,
-.027073,.039425,
-.028906,.034527,
-.029861,.029385,
-.03,.0265,
-.03,.0075,
-.037,.0075,
-.037,.0265,
-.036438,.032925,
-.034769,.039154,
-.032043,.044999,
-.028344,.050282,
-.023784,.054842,
-.018501,.058541,
-.012656,.061266,
-.0075,.06273,
270.*
4,1,20,.0075,.05555,
.0075,.06273,
.013677,.060878,
.019439,.057981,
.024611,.054127,
.029034,.049434,
.032576,.044045,
.035127,.038122,
.036612,.031846,
.037,.0265,
.037,.0075,
.03,.0075,
.03,.0265,
.029544,.03171,
.028191,.036762,
.02598,.041502,
.022981,.045786,
.019282,.049484,
.014998,.052484,
.010258,.054694,
.0075,.05555,
270.*
%
%ADD36MACRO36*%
%AMMACRO30*
4,1,36,.0025,0.0,
.002462,.000434,
.002349,.000855,
.002165,.00125,
.001915,.001607,
.001607,.001915,
.00125,.002165,
.000855,.002349,
.000434,.002462,
0.0,.0025,
-.000434,.002462,
-.000855,.002349,
-.00125,.002165,
-.001607,.001915,
-.001915,.001607,
-.002165,.00125,
-.002349,.000855,
-.002462,.000434,
-.0025,0.0,
-.002462,-.000434,
-.002349,-.000855,
-.002165,-.00125,
-.001915,-.001607,
-.001607,-.001915,
-.00125,-.002165,
-.000855,-.002349,
-.000434,-.002462,
0.0,-.0025,
.000434,-.002462,
.000855,-.002349,
.00125,-.002165,
.001607,-.001915,
.001915,-.001607,
.002165,-.00125,
.002349,-.000855,
.002462,-.000434,
.0025,0.0,
315.*
%
%ADD30MACRO30*%
%AMMACRO14*
4,1,36,.0025,0.0,
.002462,.000434,
.002349,.000855,
.002165,.00125,
.001915,.001607,
.001607,.001915,
.00125,.002165,
.000855,.002349,
.000434,.002462,
0.0,.0025,
-.000434,.002462,
-.000855,.002349,
-.00125,.002165,
-.001607,.001915,
-.001915,.001607,
-.002165,.00125,
-.002349,.000855,
-.002462,.000434,
-.0025,0.0,
-.002462,-.000434,
-.002349,-.000855,
-.002165,-.00125,
-.001915,-.001607,
-.001607,-.001915,
-.00125,-.002165,
-.000855,-.002349,
-.000434,-.002462,
0.0,-.0025,
.000434,-.002462,
.000855,-.002349,
.00125,-.002165,
.001607,-.001915,
.001915,-.001607,
.002165,-.00125,
.002349,-.000855,
.002462,-.000434,
.0025,0.0,
180.*
%
%ADD14MACRO14*%
%AMMACRO10*
4,1,36,.0025,0.0,
.002462,.000434,
.002349,.000855,
.002165,.00125,
.001915,.001607,
.001607,.001915,
.00125,.002165,
.000855,.002349,
.000434,.002462,
0.0,.0025,
-.000434,.002462,
-.000855,.002349,
-.00125,.002165,
-.001607,.001915,
-.001915,.001607,
-.002165,.00125,
-.002349,.000855,
-.002462,.000434,
-.0025,0.0,
-.002462,-.000434,
-.002349,-.000855,
-.002165,-.00125,
-.001915,-.001607,
-.001607,-.001915,
-.00125,-.002165,
-.000855,-.002349,
-.000434,-.002462,
0.0,-.0025,
.000434,-.002462,
.000855,-.002349,
.00125,-.002165,
.001607,-.001915,
.001915,-.001607,
.002165,-.00125,
.002349,-.000855,
.002462,-.000434,
.0025,0.0,
270.*
%
%ADD10MACRO10*%
%AMMACRO43*
4,1,36,-.0025,0.0,
-.002462,.000434,
-.002349,.000855,
-.002165,.00125,
-.001915,.001607,
-.001607,.001915,
-.00125,.002165,
-.000855,.002349,
-.000434,.002462,
0.0,.0025,
.000434,.002462,
.000855,.002349,
.00125,.002165,
.001607,.001915,
.001915,.001607,
.002165,.00125,
.002349,.000855,
.002462,.000434,
.0025,0.0,
.002462,-.000434,
.002349,-.000855,
.002165,-.00125,
.001915,-.001607,
.001607,-.001915,
.00125,-.002165,
.000855,-.002349,
.000434,-.002462,
0.0,-.0025,
-.000434,-.002462,
-.000855,-.002349,
-.00125,-.002165,
-.001607,-.001915,
-.001915,-.001607,
-.002165,-.00125,
-.002349,-.000855,
-.002462,-.000434,
-.0025,0.0,
180.*
%
%ADD43MACRO43*%
%AMMACRO34*
4,1,36,.003,0.0,
.002954,.000521,
.002819,.001026,
.002598,.0015,
.002298,.001928,
.001928,.002298,
.0015,.002598,
.001026,.002819,
.000521,.002954,
0.0,.003,
-.000521,.002954,
-.001026,.002819,
-.0015,.002598,
-.001928,.002298,
-.002298,.001928,
-.002598,.0015,
-.002819,.001026,
-.002954,.000521,
-.003,0.0,
-.002954,-.000521,
-.002819,-.001026,
-.002598,-.0015,
-.002298,-.001928,
-.001928,-.002298,
-.0015,-.002598,
-.001026,-.002819,
-.000521,-.002954,
0.0,-.003,
.000521,-.002954,
.001026,-.002819,
.0015,-.002598,
.001928,-.002298,
.002298,-.001928,
.002598,-.0015,
.002819,-.001026,
.002954,-.000521,
.003,0.0,
270.*
%
%ADD34MACRO34*%
%AMMACRO24*
4,1,36,.003,0.0,
.002954,.000521,
.002819,.001026,
.002598,.0015,
.002298,.001928,
.001928,.002298,
.0015,.002598,
.001026,.002819,
.000521,.002954,
0.0,.003,
-.000521,.002954,
-.001026,.002819,
-.0015,.002598,
-.001928,.002298,
-.002298,.001928,
-.002598,.0015,
-.002819,.001026,
-.002954,.000521,
-.003,0.0,
-.002954,-.000521,
-.002819,-.001026,
-.002598,-.0015,
-.002298,-.001928,
-.001928,-.002298,
-.0015,-.002598,
-.001026,-.002819,
-.000521,-.002954,
0.0,-.003,
.000521,-.002954,
.001026,-.002819,
.0015,-.002598,
.001928,-.002298,
.002298,-.001928,
.002598,-.0015,
.002819,-.001026,
.002954,-.000521,
.003,0.0,
180.*
%
%ADD24MACRO24*%
%ADD21C,.074*%
%AMMACRO39*
4,1,36,-.003,0.0,
-.002954,.000521,
-.002819,.001026,
-.002598,.0015,
-.002298,.001928,
-.001928,.002298,
-.0015,.002598,
-.001026,.002819,
-.000521,.002954,
0.0,.003,
.000521,.002954,
.001026,.002819,
.0015,.002598,
.001928,.002298,
.002298,.001928,
.002598,.0015,
.002819,.001026,
.002954,.000521,
.003,0.0,
.002954,-.000521,
.002819,-.001026,
.002598,-.0015,
.002298,-.001928,
.001928,-.002298,
.0015,-.002598,
.001026,-.002819,
.000521,-.002954,
0.0,-.003,
-.000521,-.002954,
-.001026,-.002819,
-.0015,-.002598,
-.001928,-.002298,
-.002298,-.001928,
-.002598,-.0015,
-.002819,-.001026,
-.002954,-.000521,
-.003,0.0,
180.*
%
%ADD39MACRO39*%
%ADD25C,.0435*%
%ADD56C,.087*%
%ADD51C,.0277*%
%AMMACRO41*
4,1,18,.09673,.06845,
.107147,.050613,
.114308,.031238,
.117996,.010914,
.118098,-.009741,
.114613,-.030101,
.107644,-.049546,
.097406,-.067485,
.09673,-.06845,
.10175,-.07347,
.112962,-.054685,
.120742,-.034239,
.124853,-.012752,
.125171,.009122,
.121685,.030719,
.114502,.051383,
.10384,.070486,
.10175,.07347,
.09673,.06845,
90.*
4,1,18,.06845,-.09673,
.050613,-.107147,
.031238,-.114308,
.010914,-.117996,
-.009741,-.118098,
-.030101,-.114613,
-.049546,-.107644,
-.067485,-.097406,
-.06845,-.09673,
-.07347,-.10175,
-.054685,-.112962,
-.034239,-.120742,
-.012752,-.124853,
.009122,-.125171,
.030719,-.121685,
.051383,-.114502,
.070486,-.10384,
.07347,-.10175,
.06845,-.09673,
90.*
4,1,18,-.09673,-.06845,
-.107147,-.050613,
-.114308,-.031238,
-.117996,-.010914,
-.118098,.009741,
-.114613,.030101,
-.107644,.049546,
-.097406,.067485,
-.09673,.06845,
-.10175,.07347,
-.112962,.054685,
-.120742,.034239,
-.124853,.012752,
-.125171,-.009122,
-.121685,-.030719,
-.114502,-.051383,
-.10384,-.070486,
-.10175,-.07347,
-.09673,-.06845,
90.*
4,1,18,-.06845,.09673,
-.050613,.107147,
-.031238,.114308,
-.010914,.117996,
.009741,.118098,
.030101,.114613,
.049546,.107644,
.067485,.097406,
.06845,.09673,
.07347,.10175,
.054685,.112962,
.034239,.120742,
.012752,.124853,
-.009122,.125171,
-.030719,.121685,
-.051383,.114502,
-.070486,.10384,
-.07347,.10175,
-.06845,.09673,
90.*
%
%ADD41MACRO41*%
%AMMACRO11*
4,1,15,.06231,.03403,
.067273,.022693,
.070191,.010666,
.070977,-.001684,
.069606,-.013984,
.066121,-.025858,
.06231,-.03403,
.06745,-.03917,
.073227,-.026862,
.076779,-.013739,
.077998,-.000197,
.076848,.01335,
.073362,.026492,
.067647,.038828,
.06745,.03917,
.06231,.03403,
0.0*
4,1,15,.03403,-.06231,
.022693,-.067273,
.010666,-.070191,
-.001684,-.070977,
-.013984,-.069606,
-.025858,-.066121,
-.03403,-.06231,
-.03917,-.06745,
-.026862,-.073227,
-.013739,-.076779,
-.000197,-.077998,
.01335,-.076848,
.026492,-.073362,
.038828,-.067647,
.03917,-.06745,
.03403,-.06231,
0.0*
4,1,15,-.06231,-.03403,
-.067273,-.022693,
-.070191,-.010666,
-.070977,.001684,
-.069606,.013984,
-.066121,.025858,
-.06231,.03403,
-.06745,.03917,
-.073227,.026862,
-.076779,.013739,
-.077998,.000197,
-.076848,-.01335,
-.073362,-.026492,
-.067647,-.038828,
-.06745,-.03917,
-.06231,-.03403,
0.0*
4,1,15,-.03403,.06231,
-.022693,.067273,
-.010666,.070191,
.001684,.070977,
.013984,.069606,
.025858,.066121,
.03403,.06231,
.03917,.06745,
.026862,.073227,
.013739,.076779,
.000197,.077998,
-.01335,.076848,
-.026492,.073362,
-.038828,.067647,
-.03917,.06745,
-.03403,.06231,
0.0*
%
%ADD11MACRO11*%
%ADD19C,.099*%
%AMMACRO18*
4,1,18,.09673,.06845,
.107147,.050613,
.114308,.031238,
.117996,.010914,
.118098,-.009741,
.114613,-.030101,
.107644,-.049546,
.097406,-.067485,
.09673,-.06845,
.10175,-.07347,
.112962,-.054685,
.120742,-.034239,
.124853,-.012752,
.125171,.009122,
.121685,.030719,
.114502,.051383,
.10384,.070486,
.10175,.07347,
.09673,.06845,
0.0*
4,1,18,.06845,-.09673,
.050613,-.107147,
.031238,-.114308,
.010914,-.117996,
-.009741,-.118098,
-.030101,-.114613,
-.049546,-.107644,
-.067485,-.097406,
-.06845,-.09673,
-.07347,-.10175,
-.054685,-.112962,
-.034239,-.120742,
-.012752,-.124853,
.009122,-.125171,
.030719,-.121685,
.051383,-.114502,
.070486,-.10384,
.07347,-.10175,
.06845,-.09673,
0.0*
4,1,18,-.09673,-.06845,
-.107147,-.050613,
-.114308,-.031238,
-.117996,-.010914,
-.118098,.009741,
-.114613,.030101,
-.107644,.049546,
-.097406,.067485,
-.09673,.06845,
-.10175,.07347,
-.112962,.054685,
-.120742,.034239,
-.124853,.012752,
-.125171,-.009122,
-.121685,-.030719,
-.114502,-.051383,
-.10384,-.070486,
-.10175,-.07347,
-.09673,-.06845,
0.0*
4,1,18,-.06845,.09673,
-.050613,.107147,
-.031238,.114308,
-.010914,.117996,
.009741,.118098,
.030101,.114613,
.049546,.107644,
.067485,.097406,
.06845,.09673,
.07347,.10175,
.054685,.112962,
.034239,.120742,
.012752,.124853,
-.009122,.125171,
-.030719,.121685,
-.051383,.114502,
-.070486,.10384,
-.07347,.10175,
-.06845,.09673,
0.0*
%
%ADD18MACRO18*%
%AMMACRO59*
4,1,19,-.0075,-.03785,
-.011528,-.036185,
-.015205,-.033846,
-.01842,-.030904,
-.021075,-.027448,
-.02309,-.023584,
-.024404,-.019428,
-.024975,-.015108,
-.025,-.014,
-.025,-.0075,
-.018,-.0075,
-.018,-.014,
-.017727,-.017125,
-.016915,-.020155,
-.015589,-.022998,
-.01379,-.025567,
-.011572,-.027785,
-.009002,-.029584,
-.0075,-.03036,
-.0075,-.03785,
180.*
4,1,19,.0075,-.03785,
.0075,-.03036,
.010227,-.02881,
.012643,-.02681,
.014676,-.024421,
.016262,-.021715,
.017355,-.018774,
.017921,-.015689,
.018,-.014,
.018,-.0075,
.025,-.0075,
.025,-.014,
.02462,-.018342,
.023492,-.022551,
.02165,-.026501,
.019151,-.030071,
.016069,-.033153,
.012499,-.035652,
.008549,-.037494,
.0075,-.03785,
180.*
4,1,19,-.025,.0075,
-.025,.014,
-.02462,.018342,
-.023492,.022551,
-.02165,.026501,
-.019151,.030071,
-.016069,.033153,
-.012499,.035652,
-.008549,.037494,
-.0075,.03785,
-.0075,.03036,
-.010227,.02881,
-.012643,.02681,
-.014676,.024421,
-.016262,.021715,
-.017355,.018774,
-.017921,.015689,
-.018,.014,
-.018,.0075,
-.025,.0075,
180.*
4,1,19,.018,.0075,
.018,.014,
.017727,.017125,
.016915,.020155,
.015589,.022998,
.01379,.025567,
.011572,.027785,
.009002,.029584,
.0075,.03036,
.0075,.03785,
.011528,.036185,
.015205,.033846,
.01842,.030904,
.021075,.027448,
.02309,.023584,
.024404,.019428,
.024975,.015108,
.025,.014,
.025,.0075,
.018,.0075,
180.*
%
%ADD59MACRO59*%
%AMMACRO35*
4,1,16,.02584,.01524,
.028094,.010521,
.029494,.005483,
.029998,.000278,
.029591,-.004935,
.028284,-.009999,
.026118,-.014758,
.02584,-.01524,
.03092,-.02032,
.033979,-.014642,
.036005,-.008519,
.036938,-.002138,
.036748,.004309,
.035441,.010625,
.033058,.016618,
.03092,.02032,
.02584,.01524,
0.0*
4,1,16,.01524,-.02584,
.010521,-.028094,
.005483,-.029494,
.000278,-.029998,
-.004935,-.029591,
-.009999,-.028284,
-.014758,-.026118,
-.01524,-.02584,
-.02032,-.03092,
-.014642,-.033979,
-.008519,-.036005,
-.002138,-.036938,
.004309,-.036748,
.010625,-.035441,
.016618,-.033058,
.02032,-.03092,
.01524,-.02584,
0.0*
4,1,16,-.02584,-.01524,
-.028094,-.010521,
-.029494,-.005483,
-.029998,-.000278,
-.029591,.004935,
-.028284,.009999,
-.026118,.014758,
-.02584,.01524,
-.03092,.02032,
-.033979,.014642,
-.036005,.008519,
-.036938,.002138,
-.036748,-.004309,
-.035441,-.010625,
-.033058,-.016618,
-.03092,-.02032,
-.02584,-.01524,
0.0*
4,1,16,-.01524,.02584,
-.010521,.028094,
-.005483,.029494,
-.000278,.029998,
.004935,.029591,
.009999,.028284,
.014758,.026118,
.01524,.02584,
.02032,.03092,
.014642,.033979,
.008519,.036005,
.002138,.036938,
-.004309,.036748,
-.010625,.035441,
-.016618,.033058,
-.02032,.03092,
-.01524,.02584,
0.0*
%
%ADD35MACRO35*%
%AMMACRO47*
4,1,15,.02142,.01082,
.022973,.006936,
.023829,.002841,
.02396,-.00134,
.023364,-.00548,
.022057,-.009454,
.02142,-.01082,
.02657,-.01597,
.02894,-.011114,
.03043,-.005919,
.030995,-.000545,
.030619,.004845,
.029313,.010088,
.027115,.015025,
.02657,.01597,
.02142,.01082,
90.*
4,1,15,.01082,-.02142,
.006936,-.022973,
.002841,-.023829,
-.00134,-.02396,
-.00548,-.023364,
-.009454,-.022057,
-.01082,-.02142,
-.01597,-.02657,
-.011114,-.02894,
-.005919,-.03043,
-.000545,-.030995,
.004845,-.030619,
.010088,-.029313,
.015025,-.027115,
.01597,-.02657,
.01082,-.02142,
90.*
4,1,15,-.02142,-.01082,
-.022973,-.006936,
-.023829,-.002841,
-.02396,.00134,
-.023364,.00548,
-.022057,.009454,
-.02142,.01082,
-.02657,.01597,
-.02894,.011114,
-.03043,.005919,
-.030995,.000545,
-.030619,-.004845,
-.029313,-.010088,
-.027115,-.015025,
-.02657,-.01597,
-.02142,-.01082,
90.*
4,1,15,-.01082,.02142,
-.006936,.022973,
-.002841,.023829,
.00134,.02396,
.00548,.023364,
.009454,.022057,
.01082,.02142,
.01597,.02657,
.011114,.02894,
.005919,.03043,
.000545,.030995,
-.004845,.030619,
-.010088,.029313,
-.015025,.027115,
-.01597,.02657,
-.01082,.02142,
90.*
%
%ADD47MACRO47*%
%AMMACRO45*
4,1,18,.07103,.05689,
.07983,.043691,
.086204,.029165,
.089959,.013753,
.09098,-.002077,
.089237,-.017844,
.084783,-.033069,
.077753,-.047289,
.07103,-.05689,
.07601,-.06186,
.085597,-.047721,
.092583,-.032132,
.096757,-.015567,
.09799,.001471,
.096246,.018464,
.091577,.034897,
.084126,.050269,
.07601,.06186,
.07103,.05689,
90.*
4,1,18,.05689,-.07103,
.043691,-.07983,
.029165,-.086204,
.013753,-.089959,
-.002077,-.09098,
-.017844,-.089237,
-.033069,-.084783,
-.047289,-.077753,
-.05689,-.07103,
-.06186,-.07601,
-.047721,-.085597,
-.032132,-.092583,
-.015567,-.096757,
.001471,-.09799,
.018464,-.096246,
.034897,-.091577,
.050269,-.084126,
.06186,-.07601,
.05689,-.07103,
90.*
4,1,18,-.07103,-.05689,
-.07983,-.043691,
-.086204,-.029165,
-.089959,-.013753,
-.09098,.002077,
-.089237,.017844,
-.084783,.033069,
-.077753,.047289,
-.07103,.05689,
-.07601,.06186,
-.085597,.047721,
-.092583,.032132,
-.096757,.015567,
-.09799,-.001471,
-.096246,-.018464,
-.091577,-.034897,
-.084126,-.050269,
-.07601,-.06186,
-.07103,-.05689,
90.*
4,1,18,-.05689,.07103,
-.043691,.07983,
-.029165,.086204,
-.013753,.089959,
.002077,.09098,
.017844,.089237,
.033069,.084783,
.047289,.077753,
.05689,.07103,
.06186,.07601,
.047721,.085597,
.032132,.092583,
.015567,.096757,
-.001471,.09799,
-.018464,.096246,
-.034897,.091577,
-.050269,.084126,
-.06186,.07601,
-.05689,.07103,
90.*
%
%ADD45MACRO45*%
%AMMACRO60*
4,1,19,-.0075,-.04535,
-.011528,-.043685,
-.015205,-.041346,
-.01842,-.038404,
-.021075,-.034948,
-.02309,-.031084,
-.024404,-.026928,
-.024975,-.022608,
-.025,-.0215,
-.025,-.0075,
-.018,-.0075,
-.018,-.0215,
-.017727,-.024625,
-.016915,-.027655,
-.015589,-.030498,
-.01379,-.033067,
-.011572,-.035285,
-.009002,-.037084,
-.0075,-.03786,
-.0075,-.04535,
180.*
4,1,19,.0075,-.04535,
.0075,-.03786,
.010227,-.03631,
.012643,-.03431,
.014676,-.031921,
.016262,-.029215,
.017355,-.026274,
.017921,-.023189,
.018,-.0215,
.018,-.0075,
.025,-.0075,
.025,-.0215,
.02462,-.025842,
.023492,-.030051,
.02165,-.034001,
.019151,-.037571,
.016069,-.040653,
.012499,-.043152,
.008549,-.044994,
.0075,-.04535,
180.*
4,1,19,-.025,.0075,
-.025,.0215,
-.02462,.025842,
-.023492,.030051,
-.02165,.034001,
-.019151,.037571,
-.016069,.040653,
-.012499,.043152,
-.008549,.044994,
-.0075,.04535,
-.0075,.03786,
-.010227,.03631,
-.012643,.03431,
-.014676,.031921,
-.016262,.029215,
-.017355,.026274,
-.017921,.023189,
-.018,.0215,
-.018,.0075,
-.025,.0075,
180.*
4,1,19,.018,.0075,
.018,.0215,
.017727,.024625,
.016915,.027655,
.015589,.030498,
.01379,.033067,
.011572,.035285,
.009002,.037084,
.0075,.03786,
.0075,.04535,
.011528,.043685,
.015205,.041346,
.01842,.038404,
.021075,.034948,
.02309,.031084,
.024404,.026928,
.024975,.022608,
.025,.0215,
.025,.0075,
.018,.0075,
180.*
%
%ADD60MACRO60*%
%AMMACRO53*
4,1,15,.02475,.01414,
.026829,.009627,
.028094,.004822,
.028504,-.000129,
.028049,-.005077,
.026741,-.009871,
.02475,-.01414,
.02984,-.01923,
.032726,-.013756,
.034617,-.007864,
.035457,-.001734,
.03522,.00445,
.033912,.010498,
.031574,.016227,
.02984,.01923,
.02475,.01414,
0.0*
4,1,15,.01414,-.02475,
.009627,-.026829,
.004822,-.028094,
-.000129,-.028504,
-.005077,-.028049,
-.009871,-.026741,
-.01414,-.02475,
-.01923,-.02984,
-.013756,-.032726,
-.007864,-.034617,
-.001734,-.035457,
.00445,-.03522,
.010498,-.033912,
.016227,-.031574,
.01923,-.02984,
.01414,-.02475,
0.0*
4,1,15,-.02475,-.01414,
-.026829,-.009627,
-.028094,-.004822,
-.028504,.000129,
-.028049,.005077,
-.026741,.009871,
-.02475,.01414,
-.02984,.01923,
-.032726,.013756,
-.034617,.007864,
-.035457,.001734,
-.03522,-.00445,
-.033912,-.010498,
-.031574,-.016227,
-.02984,-.01923,
-.02475,-.01414,
0.0*
4,1,15,-.01414,.02475,
-.009627,.026829,
-.004822,.028094,
.000129,.028504,
.005077,.028049,
.009871,.026741,
.01414,.02475,
.01923,.02984,
.013756,.032726,
.007864,.034617,
.001734,.035457,
-.00445,.03522,
-.010498,.033912,
-.016227,.031574,
-.01923,.02984,
-.01414,.02475,
0.0*
%
%ADD53MACRO53*%
%AMMACRO57*
4,1,15,.03682,.01914,
.039584,.012455,
.041146,.005393,
.041457,-.001834,
.040509,-.009005,
.03833,-.015903,
.03682,-.01914,
.04197,-.0243,
.045552,-.016643,
.04775,-.00848,
.048497,-.000059,
.047771,.008363,
.045593,.016531,
.042029,.024197,
.04197,.0243,
.03682,.01914,
90.*
4,1,15,.01914,-.03682,
.012455,-.039584,
.005393,-.041146,
-.001834,-.041457,
-.009005,-.040509,
-.015903,-.03833,
-.01914,-.03682,
-.0243,-.04197,
-.016643,-.045552,
-.00848,-.04775,
-.000059,-.048497,
.008363,-.047771,
.016531,-.045593,
.024197,-.042029,
.0243,-.04197,
.01914,-.03682,
90.*
4,1,15,-.03682,-.01914,
-.039584,-.012455,
-.041146,-.005393,
-.041457,.001834,
-.040509,.009005,
-.03833,.015903,
-.03682,.01914,
-.04197,.0243,
-.045552,.016643,
-.04775,.00848,
-.048497,.000059,
-.047771,-.008363,
-.045593,-.016531,
-.042029,-.024197,
-.04197,-.0243,
-.03682,-.01914,
90.*
4,1,15,-.01914,.03682,
-.012455,.039584,
-.005393,.041146,
.001834,.041457,
.009005,.040509,
.015903,.03833,
.01914,.03682,
.0243,.04197,
.016643,.045552,
.00848,.04775,
.000059,.048497,
-.008363,.047771,
-.016531,.045593,
-.024197,.042029,
-.0243,.04197,
-.01914,.03682,
90.*
%
%ADD57MACRO57*%
%AMMACRO58*
4,1,15,-.03682,.01914,
-.039584,.012455,
-.041146,.005393,
-.041457,-.001834,
-.040509,-.009005,
-.03833,-.015903,
-.03682,-.01914,
-.04197,-.0243,
-.045552,-.016643,
-.04775,-.00848,
-.048497,-.000059,
-.047771,.008363,
-.045593,.016531,
-.042029,.024197,
-.04197,.0243,
-.03682,.01914,
90.*
4,1,15,-.01914,-.03682,
-.012455,-.039584,
-.005393,-.041146,
.001834,-.041457,
.009005,-.040509,
.015903,-.03833,
.01914,-.03682,
.0243,-.04197,
.016643,-.045552,
.00848,-.04775,
.000059,-.048497,
-.008363,-.047771,
-.016531,-.045593,
-.024197,-.042029,
-.0243,-.04197,
-.01914,-.03682,
90.*
4,1,15,.03682,-.01914,
.039584,-.012455,
.041146,-.005393,
.041457,.001834,
.040509,.009005,
.03833,.015903,
.03682,.01914,
.04197,.0243,
.045552,.016643,
.04775,.00848,
.048497,.000059,
.047771,-.008363,
.045593,-.016531,
.042029,-.024197,
.04197,-.0243,
.03682,-.01914,
90.*
4,1,15,.01914,.03682,
.012455,.039584,
.005393,.041146,
-.001834,.041457,
-.009005,.040509,
-.015903,.03833,
-.01914,.03682,
-.0243,.04197,
-.016643,.045552,
-.00848,.04775,
-.000059,.048497,
.008363,.047771,
.016531,.045593,
.024197,.042029,
.0243,.04197,
.01914,.03682,
90.*
%
%ADD58MACRO58*%
%ADD61C,.142*%
%ADD13C,.125*%
%ADD29C,.208*%
%ADD44C,.164*%
%ADD17C,.155*%
%ADD37C,.256*%
%AMMACRO31*
4,1,36,0.0,.0085,
.001476,.008371,
.002907,.007987,
.00425,.007361,
.005464,.006511,
.006511,.005464,
.007361,.00425,
.007987,.002907,
.008371,.001476,
.0085,0.0,
.008371,-.001476,
.007987,-.002907,
.007361,-.00425,
.006511,-.005464,
.005464,-.006511,
.00425,-.007361,
.002907,-.007987,
.001476,-.008371,
0.0,-.0085,
-.001476,-.008371,
-.002907,-.007987,
-.00425,-.007361,
-.005464,-.006511,
-.006511,-.005464,
-.007361,-.00425,
-.007987,-.002907,
-.008371,-.001476,
-.0085,0.0,
-.008371,.001476,
-.007987,.002907,
-.007361,.00425,
-.006511,.005464,
-.005464,.006511,
-.00425,.007361,
-.002907,.007987,
-.001476,.008371,
0.0,.0085,
180.*
%
%ADD31MACRO31*%
%AMMACRO46*
4,1,36,0.0,.0185,
-.003212,.018219,
-.006327,.017384,
-.00925,.016021,
-.011892,.014172,
-.014172,.011892,
-.016021,.00925,
-.017384,.006327,
-.018219,.003212,
-.0185,0.0,
-.018219,-.003212,
-.017384,-.006327,
-.016021,-.00925,
-.014172,-.011892,
-.011892,-.014172,
-.00925,-.016021,
-.006327,-.017384,
-.003212,-.018219,
0.0,-.0185,
.003212,-.018219,
.006327,-.017384,
.00925,-.016021,
.011892,-.014172,
.014172,-.011892,
.016021,-.00925,
.017384,-.006327,
.018219,-.003212,
.0185,0.0,
.018219,.003212,
.017384,.006327,
.016021,.00925,
.014172,.011892,
.011892,.014172,
.00925,.016021,
.006327,.017384,
.003212,.018219,
0.0,.0185,
270.*
%
%ADD46MACRO46*%
%AMMACRO20*
4,1,20,-.0075,-.05555,
-.0075,-.06273,
-.013677,-.060878,
-.019439,-.057981,
-.024611,-.054127,
-.029034,-.049434,
-.032576,-.044045,
-.035127,-.038122,
-.036612,-.031846,
-.037,-.0265,
-.037,-.0075,
-.03,-.0075,
-.03,-.0265,
-.029544,-.03171,
-.028191,-.036762,
-.02598,-.041502,
-.022981,-.045786,
-.019282,-.049484,
-.014998,-.052484,
-.010258,-.054694,
-.0075,-.05555,
90.*
4,1,20,.0075,-.06273,
.0075,-.05555,
.01243,-.053806,
.016983,-.051232,
.02102,-.047906,
.024418,-.043931,
.027073,-.039425,
.028906,-.034527,
.029861,-.029385,
.03,-.0265,
.03,-.0075,
.037,-.0075,
.037,-.0265,
.036438,-.032925,
.034769,-.039154,
.032043,-.044999,
.028344,-.050282,
.023784,-.054842,
.018501,-.058541,
.012656,-.061266,
.0075,-.06273,
90.*
4,1,20,-.0075,.06273,
-.0075,.05555,
-.01243,.053806,
-.016983,.051232,
-.02102,.047906,
-.024418,.043931,
-.027073,.039425,
-.028906,.034527,
-.029861,.029385,
-.03,.0265,
-.03,.0075,
-.037,.0075,
-.037,.0265,
-.036438,.032925,
-.034769,.039154,
-.032043,.044999,
-.028344,.050282,
-.023784,.054842,
-.018501,.058541,
-.012656,.061266,
-.0075,.06273,
90.*
4,1,20,.0075,.05555,
.0075,.06273,
.013677,.060878,
.019439,.057981,
.024611,.054127,
.029034,.049434,
.032576,.044045,
.035127,.038122,
.036612,.031846,
.037,.0265,
.037,.0075,
.03,.0075,
.03,.0265,
.029544,.03171,
.028191,.036762,
.02598,.041502,
.022981,.045786,
.019282,.049484,
.014998,.052484,
.010258,.054694,
.0075,.05555,
90.*
%
%ADD20MACRO20*%
%AMMACRO16*
4,1,36,.0025,0.0,
.002462,.000434,
.002349,.000855,
.002165,.00125,
.001915,.001607,
.001607,.001915,
.00125,.002165,
.000855,.002349,
.000434,.002462,
0.0,.0025,
-.000434,.002462,
-.000855,.002349,
-.00125,.002165,
-.001607,.001915,
-.001915,.001607,
-.002165,.00125,
-.002349,.000855,
-.002462,.000434,
-.0025,0.0,
-.002462,-.000434,
-.002349,-.000855,
-.002165,-.00125,
-.001915,-.001607,
-.001607,-.001915,
-.00125,-.002165,
-.000855,-.002349,
-.000434,-.002462,
0.0,-.0025,
.000434,-.002462,
.000855,-.002349,
.00125,-.002165,
.001607,-.001915,
.001915,-.001607,
.002165,-.00125,
.002349,-.000855,
.002462,-.000434,
.0025,0.0,
90.*
%
%ADD16MACRO16*%
%AMMACRO33*
4,1,36,.003,0.0,
.002954,.000521,
.002819,.001026,
.002598,.0015,
.002298,.001928,
.001928,.002298,
.0015,.002598,
.001026,.002819,
.000521,.002954,
0.0,.003,
-.000521,.002954,
-.001026,.002819,
-.0015,.002598,
-.001928,.002298,
-.002298,.001928,
-.002598,.0015,
-.002819,.001026,
-.002954,.000521,
-.003,0.0,
-.002954,-.000521,
-.002819,-.001026,
-.002598,-.0015,
-.002298,-.001928,
-.001928,-.002298,
-.0015,-.002598,
-.001026,-.002819,
-.000521,-.002954,
0.0,-.003,
.000521,-.002954,
.001026,-.002819,
.0015,-.002598,
.001928,-.002298,
.002298,-.001928,
.002598,-.0015,
.002819,-.001026,
.002954,-.000521,
.003,0.0,
90.*
%
%ADD33MACRO33*%
%AMMACRO12*
4,1,36,.0025,0.0,
.002462,.000434,
.002349,.000855,
.002165,.00125,
.001915,.001607,
.001607,.001915,
.00125,.002165,
.000855,.002349,
.000434,.002462,
0.0,.0025,
-.000434,.002462,
-.000855,.002349,
-.00125,.002165,
-.001607,.001915,
-.001915,.001607,
-.002165,.00125,
-.002349,.000855,
-.002462,.000434,
-.0025,0.0,
-.002462,-.000434,
-.002349,-.000855,
-.002165,-.00125,
-.001915,-.001607,
-.001607,-.001915,
-.00125,-.002165,
-.000855,-.002349,
-.000434,-.002462,
0.0,-.0025,
.000434,-.002462,
.000855,-.002349,
.00125,-.002165,
.001607,-.001915,
.001915,-.001607,
.002165,-.00125,
.002349,-.000855,
.002462,-.000434,
.0025,0.0,
0.0*
%
%ADD12MACRO12*%
%AMMACRO49*
4,1,36,-.0025,0.0,
-.002462,.000434,
-.002349,.000855,
-.002165,.00125,
-.001915,.001607,
-.001607,.001915,
-.00125,.002165,
-.000855,.002349,
-.000434,.002462,
0.0,.0025,
.000434,.002462,
.000855,.002349,
.00125,.002165,
.001607,.001915,
.001915,.001607,
.002165,.00125,
.002349,.000855,
.002462,.000434,
.0025,0.0,
.002462,-.000434,
.002349,-.000855,
.002165,-.00125,
.001915,-.001607,
.001607,-.001915,
.00125,-.002165,
.000855,-.002349,
.000434,-.002462,
0.0,-.0025,
-.000434,-.002462,
-.000855,-.002349,
-.00125,-.002165,
-.001607,-.001915,
-.001915,-.001607,
-.002165,-.00125,
-.002349,-.000855,
-.002462,-.000434,
-.0025,0.0,
0.0*
%
%ADD49MACRO49*%
%AMMACRO26*
4,1,36,.003,0.0,
.002954,.000521,
.002819,.001026,
.002598,.0015,
.002298,.001928,
.001928,.002298,
.0015,.002598,
.001026,.002819,
.000521,.002954,
0.0,.003,
-.000521,.002954,
-.001026,.002819,
-.0015,.002598,
-.001928,.002298,
-.002298,.001928,
-.002598,.0015,
-.002819,.001026,
-.002954,.000521,
-.003,0.0,
-.002954,-.000521,
-.002819,-.001026,
-.002598,-.0015,
-.002298,-.001928,
-.001928,-.002298,
-.0015,-.002598,
-.001026,-.002819,
-.000521,-.002954,
0.0,-.003,
.000521,-.002954,
.001026,-.002819,
.0015,-.002598,
.001928,-.002298,
.002298,-.001928,
.002598,-.0015,
.002819,-.001026,
.002954,-.000521,
.003,0.0,
0.0*
%
%ADD26MACRO26*%
%AMMACRO23*
4,1,36,-.003,0.0,
-.002954,.000521,
-.002819,.001026,
-.002598,.0015,
-.002298,.001928,
-.001928,.002298,
-.0015,.002598,
-.001026,.002819,
-.000521,.002954,
0.0,.003,
.000521,.002954,
.001026,.002819,
.0015,.002598,
.001928,.002298,
.002298,.001928,
.002598,.0015,
.002819,.001026,
.002954,.000521,
.003,0.0,
.002954,-.000521,
.002819,-.001026,
.002598,-.0015,
.002298,-.001928,
.001928,-.002298,
.0015,-.002598,
.001026,-.002819,
.000521,-.002954,
0.0,-.003,
-.000521,-.002954,
-.001026,-.002819,
-.0015,-.002598,
-.001928,-.002298,
-.002298,-.001928,
-.002598,-.0015,
-.002819,-.001026,
-.002954,-.000521,
-.003,0.0,
0.0*
%
%ADD23MACRO23*%
%AMMACRO38*
4,1,16,.02584,.01524,
.028094,.010521,
.029494,.005483,
.029998,.000278,
.029591,-.004935,
.028284,-.009999,
.026118,-.014758,
.02584,-.01524,
.03092,-.02032,
.033979,-.014642,
.036005,-.008519,
.036938,-.002138,
.036748,.004309,
.035441,.010625,
.033058,.016618,
.03092,.02032,
.02584,.01524,
180.*
4,1,16,.01524,-.02584,
.010521,-.028094,
.005483,-.029494,
.000278,-.029998,
-.004935,-.029591,
-.009999,-.028284,
-.014758,-.026118,
-.01524,-.02584,
-.02032,-.03092,
-.014642,-.033979,
-.008519,-.036005,
-.002138,-.036938,
.004309,-.036748,
.010625,-.035441,
.016618,-.033058,
.02032,-.03092,
.01524,-.02584,
180.*
4,1,16,-.02584,-.01524,
-.028094,-.010521,
-.029494,-.005483,
-.029998,-.000278,
-.029591,.004935,
-.028284,.009999,
-.026118,.014758,
-.02584,.01524,
-.03092,.02032,
-.033979,.014642,
-.036005,.008519,
-.036938,.002138,
-.036748,-.004309,
-.035441,-.010625,
-.033058,-.016618,
-.03092,-.02032,
-.02584,-.01524,
180.*
4,1,16,-.01524,.02584,
-.010521,.028094,
-.005483,.029494,
-.000278,.029998,
.004935,.029591,
.009999,.028284,
.014758,.026118,
.01524,.02584,
.02032,.03092,
.014642,.033979,
.008519,.036005,
.002138,.036938,
-.004309,.036748,
-.010625,.035441,
-.016618,.033058,
-.02032,.03092,
-.01524,.02584,
180.*
%
%ADD38MACRO38*%
%AMMACRO54*
4,1,15,.03682,.01914,
.039584,.012455,
.041146,.005393,
.041457,-.001834,
.040509,-.009005,
.03833,-.015903,
.03682,-.01914,
.04197,-.0243,
.045552,-.016643,
.04775,-.00848,
.048497,-.000059,
.047771,.008363,
.045593,.016531,
.042029,.024197,
.04197,.0243,
.03682,.01914,
270.*
4,1,15,.01914,-.03682,
.012455,-.039584,
.005393,-.041146,
-.001834,-.041457,
-.009005,-.040509,
-.015903,-.03833,
-.01914,-.03682,
-.0243,-.04197,
-.016643,-.045552,
-.00848,-.04775,
-.000059,-.048497,
.008363,-.047771,
.016531,-.045593,
.024197,-.042029,
.0243,-.04197,
.01914,-.03682,
270.*
4,1,15,-.03682,-.01914,
-.039584,-.012455,
-.041146,-.005393,
-.041457,.001834,
-.040509,.009005,
-.03833,.015903,
-.03682,.01914,
-.04197,.0243,
-.045552,.016643,
-.04775,.00848,
-.048497,.000059,
-.047771,-.008363,
-.045593,-.016531,
-.042029,-.024197,
-.04197,-.0243,
-.03682,-.01914,
270.*
4,1,15,-.01914,.03682,
-.012455,.039584,
-.005393,.041146,
.001834,.041457,
.009005,.040509,
.015903,.03833,
.01914,.03682,
.0243,.04197,
.016643,.045552,
.00848,.04775,
.000059,.048497,
-.008363,.047771,
-.016531,.045593,
-.024197,.042029,
-.0243,.04197,
-.01914,.03682,
270.*
%
%ADD54MACRO54*%
%AMMACRO55*
4,1,15,-.03682,.01914,
-.039584,.012455,
-.041146,.005393,
-.041457,-.001834,
-.040509,-.009005,
-.03833,-.015903,
-.03682,-.01914,
-.04197,-.0243,
-.045552,-.016643,
-.04775,-.00848,
-.048497,-.000059,
-.047771,.008363,
-.045593,.016531,
-.042029,.024197,
-.04197,.0243,
-.03682,.01914,
270.*
4,1,15,-.01914,-.03682,
-.012455,-.039584,
-.005393,-.041146,
.001834,-.041457,
.009005,-.040509,
.015903,-.03833,
.01914,-.03682,
.0243,-.04197,
.016643,-.045552,
.00848,-.04775,
.000059,-.048497,
-.008363,-.047771,
-.016531,-.045593,
-.024197,-.042029,
-.0243,-.04197,
-.01914,-.03682,
270.*
4,1,15,.03682,-.01914,
.039584,-.012455,
.041146,-.005393,
.041457,.001834,
.040509,.009005,
.03833,.015903,
.03682,.01914,
.04197,.0243,
.045552,.016643,
.04775,.00848,
.048497,.000059,
.047771,-.008363,
.045593,-.016531,
.042029,-.024197,
.04197,-.0243,
.03682,-.01914,
270.*
4,1,15,.01914,.03682,
.012455,.039584,
.005393,.041146,
-.001834,.041457,
-.009005,.040509,
-.015903,.03833,
-.01914,.03682,
-.0243,.04197,
-.016643,.045552,
-.00848,.04775,
-.000059,.048497,
.008363,.047771,
.016531,.045593,
.024197,.042029,
.0243,.04197,
.01914,.03682,
270.*
%
%ADD55MACRO55*%
%ADD62C,.006*%
%ADD74C,.03006*%
%ADD80C,.02404*%
%ADD78C,.07005*%
%ADD71C,.08404*%
%ADD64C,.07306*%
%ADD77C,.09208*%
%ADD72C,.07606*%
%ADD70C,.08408*%
%ADD76C,.07608*%
%ADD69C,.08409*%
%ADD68O,.1621X.2251*%
%ADD67O,.03604X.07004*%
%ADD65O,.03006X.06406*%
%ADD79C,.16206*%
%ADD66O,.03606X.07006*%
%ADD75C,.17406*%
%ADD63C,.16506*%
%ADD73C,.21786*%
G75*
%LPD*%
G75*
G36*
G01X-1490433Y-1677216D02*
X4496476D01*
Y3837819D01*
X-1490433D01*
Y-1677216D01*
G37*
%LPC*%
G75*
G36*
G01X1725453Y40717D02*
X1733327D01*
G02X1739201Y34843I0J-5874D01*
G01Y0D01*
G03X1749075Y-9874I9874J0D01*
G01X1833071D01*
G02X1838945Y-15748I0J-5874D01*
G01Y-95109D01*
G02X1833071Y-100983I-5874J0D01*
G01X630370D01*
G02X624496Y-95109I0J5874D01*
G01Y-32983D01*
G03X614622Y-23109I-9874J0D01*
G01X68874D01*
G03X59000Y-32983I0J-9874D01*
G01Y-95109D01*
G02X53126Y-100983I-5874J0D01*
G01X7874D01*
G02X2000Y-95109I0J5874D01*
G01Y-15748D01*
G02X7874Y-9874I5874J0D01*
G01X31358D01*
G03X41232Y0I0J9874D01*
G01Y34843D01*
G02X47106Y40717I5874J0D01*
G01X54980D01*
G02X60854Y34843I0J-5874D01*
G01Y0D01*
G03X70728Y-9874I9874J0D01*
G01X133720D01*
G03X143594Y0I0J9874D01*
G01Y34843D01*
G02X149468Y40717I5874J0D01*
G01X157343D01*
G02X163217Y34843I0J-5874D01*
G01Y0D01*
G03X173091Y-9874I9874J0D01*
G01X236083D01*
G03X245957Y0I0J9874D01*
G01Y34843D01*
G02X251831Y40717I5874J0D01*
G01X259705D01*
G02X265579Y34843I0J-5874D01*
G01Y0D01*
G03X275453Y-9874I9874J0D01*
G01X338445D01*
G03X348319Y0I0J9874D01*
G01Y34843D01*
G02X354193Y40717I5874J0D01*
G01X362067D01*
G02X367941Y34843I0J-5874D01*
G01Y0D01*
G03X377815Y-9874I9874J0D01*
G01X488445D01*
G03X498319Y0I0J9874D01*
G01Y34843D01*
G02X504193Y40717I5874J0D01*
G01X512067D01*
G02X517941Y34843I0J-5874D01*
G01Y0D01*
G03X527815Y-9874I9874J0D01*
G01X590807D01*
G03X600681Y0I0J9874D01*
G01Y34843D01*
G02X606555Y40717I5874J0D01*
G01X614429D01*
G02X620303Y34843I0J-5874D01*
G01Y0D01*
G03X630177Y-9874I9874J0D01*
G01X693169D01*
G03X703043Y0I0J9874D01*
G01Y34843D01*
G02X708917Y40717I5874J0D01*
G01X716791D01*
G02X722665Y34843I0J-5874D01*
G01Y0D01*
G03X732539Y-9874I9874J0D01*
G01X795531D01*
G03X805405Y0I0J9874D01*
G01Y34843D01*
G02X811279Y40717I5874J0D01*
G01X819154D01*
G02X825028Y34843I0J-5874D01*
G01Y0D01*
G03X834902Y-9874I9874J0D01*
G01X945531D01*
G03X955405Y0I0J9874D01*
G01Y34843D01*
G02X961279Y40717I5874J0D01*
G01X969154D01*
G02X975028Y34843I0J-5874D01*
G01Y0D01*
G03X984902Y-9874I9874J0D01*
G01X1047894D01*
G03X1057768Y0I0J9874D01*
G01Y34843D01*
G02X1063642Y40717I5874J0D01*
G01X1071516D01*
G02X1077390Y34843I0J-5874D01*
G01Y0D01*
G03X1087264Y-9874I9874J0D01*
G01X1150256D01*
G03X1160130Y0I0J9874D01*
G01Y34843D01*
G02X1166004Y40717I5874J0D01*
G01X1173878D01*
G02X1179752Y34843I0J-5874D01*
G01Y0D01*
G03X1189626Y-9874I9874J0D01*
G01X1252618D01*
G03X1262492Y0I0J9874D01*
G01Y34843D01*
G02X1268366Y40717I5874J0D01*
G01X1276240D01*
G02X1282114Y34843I0J-5874D01*
G01Y0D01*
G03X1291988Y-9874I9874J0D01*
G01X1402618D01*
G03X1412492Y0I0J9874D01*
G01Y34843D01*
G02X1418366Y40717I5874J0D01*
G01X1426240D01*
G02X1432114Y34843I0J-5874D01*
G01Y0D01*
G03X1441988Y-9874I9874J0D01*
G01X1504980D01*
G03X1514854Y0I0J9874D01*
G01Y34843D01*
G02X1520728Y40717I5874J0D01*
G01X1528602D01*
G02X1534476Y34843I0J-5874D01*
G01Y0D01*
G03X1544350Y-9874I9874J0D01*
G01X1607343D01*
G03X1617217Y0I0J9874D01*
G01Y34843D01*
G02X1623091Y40717I5874J0D01*
G01X1630965D01*
G02X1636839Y34843I0J-5874D01*
G01Y0D01*
G03X1646713Y-9874I9874J0D01*
G01X1709705D01*
G03X1719579Y0I0J9874D01*
G01Y34843D01*
G02X1725453Y40717I5874J0D01*
G37*
G36*
G01X26775Y1645992D02*
X31442D01*
X31446Y1645988D01*
X789296D01*
G02X793646Y1644059I0J-5870D01*
G03X800964Y1640815I7319J6634D01*
G01X1070059D01*
G03X1077377Y1644059I-1J9878D01*
G02X1081727Y1645988I4350J-3941D01*
G01X1833071D01*
G02X1838941Y1640118I0J-5870D01*
G01X1838945Y1528497D01*
Y970427D01*
G02X1838260Y967674I-5874J0D01*
G02X1837222Y966276I-5247J2812D01*
G01X1826874Y955928D01*
G03X1823980Y948943I6985J-6986D01*
G01Y344836D01*
G03X1826874Y337852I9877J1D01*
G01X1837222Y327503D01*
G02X1838941Y323354I-4150J-4150D01*
G01Y7874D01*
G02X1833071Y2004I-5870J0D01*
G01X1756949D01*
G02X1751079Y7874I0J5870D01*
G01Y46654D01*
G03X1745138Y52595I-5941J0D01*
G01X1713642D01*
G03X1707701Y46654I0J-5941D01*
G01Y7874D01*
G02X1701831Y2004I-5870J0D01*
G01X1654587D01*
G02X1648717Y7874I0J5870D01*
G01Y46654D01*
G03X1642776Y52595I-5941J0D01*
G01X1611280D01*
G03X1605339Y46654I0J-5941D01*
G01Y7874D01*
G02X1599469Y2004I-5870J0D01*
G01X1552224D01*
G02X1546354Y7874I0J5870D01*
G01Y46654D01*
G03X1540413Y52595I-5941J0D01*
G01X1508917D01*
G03X1502976Y46654I0J-5941D01*
G01Y7874D01*
G02X1497106Y2004I-5870J0D01*
G01X1449862D01*
G02X1443992Y7874I0J5870D01*
G01Y46654D01*
G03X1438051Y52595I-5941J0D01*
G01X1406555D01*
G03X1400614Y46654I0J-5941D01*
G01Y7874D01*
G02X1394744Y2004I-5870J0D01*
G01X1299862D01*
G02X1293992Y7874I0J5870D01*
G01Y46654D01*
G03X1288051Y52595I-5941J0D01*
G01X1256555D01*
G03X1250614Y46654I0J-5941D01*
G01Y7874D01*
G02X1244744Y2004I-5870J0D01*
G01X1197500D01*
G02X1191630Y7874I0J5870D01*
G01Y46654D01*
G03X1185689Y52595I-5941J0D01*
G01X1154193D01*
G03X1148252Y46654I0J-5941D01*
G01Y7874D01*
G02X1142382Y2004I-5870J0D01*
G01X1095138D01*
G02X1089268Y7874I0J5870D01*
G01Y46654D01*
G03X1083327Y52595I-5941J0D01*
G01X1051831D01*
G03X1045890Y46654I0J-5941D01*
G01Y7874D01*
G02X1040020Y2004I-5870J0D01*
G01X992776D01*
G02X986906Y7874I0J5870D01*
G01Y46654D01*
G03X980965Y52595I-5941J0D01*
G01X949468D01*
G03X943527Y46654I0J-5942D01*
G01Y7874D01*
G02X937657Y2004I-5870J0D01*
G01X842776D01*
G02X836906Y7874I0J5870D01*
G01Y46654D01*
G03X830965Y52595I-5941J0D01*
G01X799468D01*
G03X793527Y46654I0J-5942D01*
G01Y7874D01*
G02X787657Y2004I-5870J0D01*
G01X740413D01*
G02X734543Y7874I0J5870D01*
G01Y46654D01*
G03X728602Y52595I-5941J0D01*
G01X697106D01*
G03X691165Y46654I0J-5941D01*
G01Y7874D01*
G02X685295Y2004I-5870J0D01*
G01X638051D01*
G02X632181Y7874I0J5870D01*
G01Y46654D01*
G03X626240Y52595I-5941J0D01*
G01X594744D01*
G03X588803Y46654I0J-5941D01*
G01Y7874D01*
G02X582933Y2004I-5870J0D01*
G01X535689D01*
G02X529819Y7874I0J5870D01*
G01Y46654D01*
G03X523878Y52595I-5941J0D01*
G01X492382D01*
G03X486441Y46654I0J-5941D01*
G01Y7874D01*
G02X480571Y2004I-5870J0D01*
G01X385689D01*
G02X379819Y7874I0J5870D01*
G01Y46654D01*
G03X373878Y52595I-5941J0D01*
G01X342382D01*
G03X336441Y46654I0J-5941D01*
G01Y7874D01*
G02X330571Y2004I-5870J0D01*
G01X283327D01*
G02X277457Y7874I0J5870D01*
G01Y46654D01*
G03X271516Y52595I-5941J0D01*
G01X240020D01*
G03X234079Y46654I0J-5941D01*
G01Y7874D01*
G02X228209Y2004I-5870J0D01*
G01X180965D01*
G02X175095Y7874I0J5870D01*
G01Y46654D01*
G03X169154Y52595I-5941J0D01*
G01X137657D01*
G03X131716Y46654I0J-5941D01*
G01Y7874D01*
G02X125846Y2004I-5870J0D01*
G01X78602D01*
G02X72732Y7874I0J5870D01*
G01Y46654D01*
G03X66791Y52595I-5941J0D01*
G01X35295D01*
G03X29354Y46654I0J-5941D01*
G01Y7874D01*
G02X23484Y2004I-5870J0D01*
G01X18462D01*
X18458Y2000D01*
X12364D01*
X12360Y2004D01*
X7874D01*
G02X2004Y7874I0J5870D01*
G01Y323354D01*
G02X3723Y327503I5869J-1D01*
G01X14071Y337852D01*
G03X16965Y344836I-6983J6985D01*
G01Y948943D01*
G03X14071Y955928I-9879J-1D01*
G01X3723Y966276D01*
G02X2004Y970426I4151J4151D01*
G01Y1640118D01*
G02X7874Y1645988I5870J0D01*
G01X26771D01*
X26775Y1645992D01*
G37*
G36*
G01X1833071Y1818880D02*
G02X1838945Y1813006I0J-5874D01*
G01Y1663740D01*
G02X1833071Y1657866I-5874J0D01*
G01X1763543D01*
G02X1757669Y1663740I0J5874D01*
G01Y1689331D01*
G03X1747795Y1699205I-9874J0D01*
G01X1461575D01*
G03X1451701Y1689331I0J-9874D01*
G01Y1663740D01*
G02X1445827Y1657866I-5874J0D01*
G01X1417087D01*
G02X1411213Y1663740I0J5874D01*
G01Y1689331D01*
G03X1401339Y1699205I-9874J0D01*
G01X1115118D01*
G03X1105244Y1689331I0J-9874D01*
G01Y1663740D01*
G02X1099370Y1657866I-5874J0D01*
G01X1090079D01*
G02X1084205Y1663740I0J5874D01*
G01Y1695110D01*
G03X1074331Y1704984I-9874J0D01*
G01X796693D01*
G03X786819Y1695110I0J-9874D01*
G01Y1663740D01*
G02X780945Y1657866I-5874J0D01*
G01X741575D01*
G02X735701Y1663740I0J5874D01*
G01Y1689331D01*
G03X725827Y1699205I-9874J0D01*
G01X439607D01*
G03X429733Y1689331I0J-9874D01*
G01Y1663740D01*
G02X423859Y1657866I-5874J0D01*
G01X395118D01*
G02X389244Y1663740I0J5874D01*
G01Y1689331D01*
G03X379370Y1699205I-9874J0D01*
G01X93150D01*
G03X83276Y1689331I0J-9874D01*
G01Y1663740D01*
G02X77402Y1657866I-5874J0D01*
G01X7874D01*
G02X2000Y1663740I0J5874D01*
G01Y1813006D01*
G02X7874Y1818880I5874J0D01*
G01X1833071D01*
G37*
%LPD*%
G75*
G36*
G01X976664Y-68818D02*
Y-73138D01*
G02X976362Y-73440I-302J0D01*
G01X973952D01*
G02X973650Y-73138I0J302D01*
G01Y-68818D01*
G02X973952Y-68516I302J0D01*
G01X976362D01*
G02X976664Y-68818I0J-302D01*
G37*
G36*
G01X951820Y-29638D02*
Y-33958D01*
G02X951518Y-34260I-302J0D01*
G01X949108D01*
G02X948806Y-33958I0J302D01*
G01Y-29638D01*
G02X949108Y-29336I302J0D01*
G01X951518D01*
G02X951820Y-29638I0J-302D01*
G37*
G36*
G01X843128Y-73166D02*
Y-68846D01*
G02X843430Y-68544I302J0D01*
G01X845840D01*
G02X846142Y-68846I0J-302D01*
G01Y-73166D01*
G02X845840Y-73468I-302J0D01*
G01X843430D01*
G02X843128Y-73166I0J302D01*
G37*
G36*
G01X723128Y-33986D02*
Y-29666D01*
G02X723430Y-29364I302J0D01*
G01X725840D01*
G02X726142Y-29666I0J-302D01*
G01Y-33986D01*
G02X725840Y-34288I-302J0D01*
G01X723430D01*
G02X723128Y-33986I0J302D01*
G37*
G36*
G01X1079340Y-68544D02*
G02X1079466Y-68571I1J-302D01*
G01X1079498Y-68586D01*
X1079568Y-68592D01*
X1079883Y-68507D01*
X1079940Y-68467D01*
X1079960Y-68439D01*
G02X1081187Y-67804I1227J-868D01*
G02X1082690Y-69306I1J-1502D01*
G01Y-72706D01*
G02X1081187Y-74208I-1503J1D01*
G02X1079960Y-73573I0J1503D01*
G01X1079940Y-73545D01*
X1079883Y-73505D01*
X1079568Y-73420D01*
X1079498Y-73426D01*
X1079466Y-73441D01*
G02X1079340Y-73468I-125J275D01*
G01X1076930D01*
G02X1076628Y-73166I0J302D01*
G01Y-68846D01*
G02X1076930Y-68544I302J0D01*
G01X1079340D01*
G37*
G36*
G01X1335840D02*
G02X1335966Y-68571I1J-302D01*
G01X1335998Y-68586D01*
X1336068Y-68592D01*
X1336383Y-68507D01*
X1336440Y-68467D01*
X1336460Y-68439D01*
G02X1337687Y-67804I1227J-868D01*
G02X1339190Y-69306I1J-1502D01*
G01Y-72706D01*
G02X1337687Y-74208I-1503J1D01*
G02X1336460Y-73573I0J1503D01*
G01X1336440Y-73545D01*
X1336383Y-73505D01*
X1336068Y-73420D01*
X1335998Y-73426D01*
X1335966Y-73441D01*
G02X1335840Y-73468I-125J275D01*
G01X1333430D01*
G02X1333128Y-73166I0J302D01*
G01Y-68846D01*
G02X1333430Y-68544I302J0D01*
G01X1335840D01*
G37*
G36*
G01X1590340D02*
G02X1590466Y-68571I1J-302D01*
G01X1590498Y-68586D01*
X1590568Y-68592D01*
X1590883Y-68507D01*
X1590940Y-68467D01*
X1590960Y-68439D01*
G02X1592187Y-67804I1227J-868D01*
G02X1593690Y-69306I1J-1502D01*
G01Y-72706D01*
G02X1592187Y-74208I-1503J1D01*
G02X1590960Y-73573I0J1503D01*
G01X1590940Y-73545D01*
X1590883Y-73505D01*
X1590568Y-73420D01*
X1590498Y-73426D01*
X1590466Y-73441D01*
G02X1590340Y-73468I-125J275D01*
G01X1587930D01*
G02X1587628Y-73166I0J302D01*
G01Y-68846D01*
G02X1587930Y-68544I302J0D01*
G01X1590340D01*
G37*
G36*
G01X1223902Y-72678D02*
Y-69278D01*
G02X1225405Y-67776I1503J-1D01*
G02X1226632Y-68411I0J-1503D01*
G01X1226652Y-68439D01*
X1226709Y-68479D01*
X1227024Y-68564D01*
X1227094Y-68558D01*
X1227126Y-68543D01*
G02X1227252Y-68516I125J-275D01*
G01X1229662D01*
G02X1229964Y-68818I0J-302D01*
G01Y-73138D01*
G02X1229662Y-73440I-302J0D01*
G01X1227252D01*
G02X1227126Y-73413I-1J302D01*
G01X1227094Y-73398D01*
X1227024Y-73392D01*
X1226709Y-73477D01*
X1226652Y-73517D01*
X1226632Y-73545D01*
G02X1225405Y-74180I-1227J868D01*
G02X1223902Y-72678I-1J1502D01*
G37*
G36*
G01X1480402D02*
Y-69278D01*
G02X1481905Y-67776I1503J-1D01*
G02X1483132Y-68411I0J-1503D01*
G01X1483152Y-68439D01*
X1483209Y-68479D01*
X1483524Y-68564D01*
X1483594Y-68558D01*
X1483626Y-68543D01*
G02X1483752Y-68516I125J-275D01*
G01X1486162D01*
G02X1486464Y-68818I0J-302D01*
G01Y-73138D01*
G02X1486162Y-73440I-302J0D01*
G01X1483752D01*
G02X1483626Y-73413I-1J302D01*
G01X1483594Y-73398D01*
X1483524Y-73392D01*
X1483209Y-73477D01*
X1483152Y-73517D01*
X1483132Y-73545D01*
G02X1481905Y-74180I-1227J868D01*
G02X1480402Y-72678I-1J1502D01*
G37*
G36*
G01X1734902D02*
Y-69278D01*
G02X1736405Y-67776I1503J-1D01*
G02X1737632Y-68411I0J-1503D01*
G01X1737652Y-68439D01*
X1737709Y-68479D01*
X1738024Y-68564D01*
X1738094Y-68558D01*
X1738126Y-68543D01*
G02X1738252Y-68516I125J-275D01*
G01X1740662D01*
G02X1740964Y-68818I0J-302D01*
G01Y-73138D01*
G02X1740662Y-73440I-302J0D01*
G01X1738252D01*
G02X1738126Y-73413I-1J302D01*
G01X1738094Y-73398D01*
X1738024Y-73392D01*
X1737709Y-73477D01*
X1737652Y-73517D01*
X1737632Y-73545D01*
G02X1736405Y-74180I-1227J868D01*
G02X1734902Y-72678I-1J1502D01*
G37*
G36*
G01X1800258Y-33888D02*
Y-30488D01*
G02X1801761Y-28986I1503J-1D01*
G02X1802988Y-29621I0J-1503D01*
G01X1803008Y-29649D01*
X1803065Y-29689D01*
X1803380Y-29774D01*
X1803450Y-29768D01*
X1803482Y-29753D01*
G02X1803608Y-29726I125J-275D01*
G01X1806018D01*
G02X1806320Y-30028I0J-302D01*
G01Y-34348D01*
G02X1806018Y-34650I-302J0D01*
G01X1803608D01*
G02X1803482Y-34623I-1J302D01*
G01X1803450Y-34608D01*
X1803380Y-34602D01*
X1803065Y-34687D01*
X1803008Y-34727D01*
X1802988Y-34755D01*
G02X1801761Y-35390I-1227J868D01*
G02X1800258Y-33888I-1J1502D01*
G37*
G36*
G01X1580340Y-29624D02*
G02X1580466Y-29651I1J-302D01*
G01X1580498Y-29666D01*
X1580568Y-29672D01*
X1580883Y-29587D01*
X1580940Y-29547D01*
X1580960Y-29519D01*
G02X1582187Y-28884I1227J-868D01*
G02X1583690Y-30386I1J-1502D01*
G01Y-33786D01*
G02X1582187Y-35288I-1503J1D01*
G02X1580960Y-34653I0J1503D01*
G01X1580940Y-34625D01*
X1580883Y-34585D01*
X1580568Y-34500D01*
X1580498Y-34506D01*
X1580466Y-34521D01*
G02X1580340Y-34548I-125J275D01*
G01X1577930D01*
G02X1577628Y-34246I0J302D01*
G01Y-29926D01*
G02X1577930Y-29624I302J0D01*
G01X1580340D01*
G37*
G36*
G01X1515758Y-33758D02*
Y-30358D01*
G02X1517261Y-28856I1503J-1D01*
G02X1518488Y-29491I0J-1503D01*
G01X1518508Y-29519D01*
X1518565Y-29559D01*
X1518880Y-29644D01*
X1518950Y-29638D01*
X1518982Y-29623D01*
G02X1519108Y-29596I125J-275D01*
G01X1521518D01*
G02X1521820Y-29898I0J-302D01*
G01Y-34218D01*
G02X1521518Y-34520I-302J0D01*
G01X1519108D01*
G02X1518982Y-34493I-1J302D01*
G01X1518950Y-34478D01*
X1518880Y-34472D01*
X1518565Y-34557D01*
X1518508Y-34597D01*
X1518488Y-34625D01*
G02X1517261Y-35260I-1227J868D01*
G02X1515758Y-33758I-1J1502D01*
G37*
G36*
G01X1295840Y-29494D02*
G02X1295966Y-29521I1J-302D01*
G01X1295998Y-29536D01*
X1296068Y-29542D01*
X1296383Y-29457D01*
X1296440Y-29417D01*
X1296460Y-29389D01*
G02X1297687Y-28754I1227J-868D01*
G02X1299190Y-30256I1J-1502D01*
G01Y-33656D01*
G02X1297687Y-35158I-1503J1D01*
G02X1296460Y-34523I0J1503D01*
G01X1296440Y-34495D01*
X1296383Y-34455D01*
X1296068Y-34370D01*
X1295998Y-34376D01*
X1295966Y-34391D01*
G02X1295840Y-34418I-125J275D01*
G01X1293430D01*
G02X1293128Y-34116I0J302D01*
G01Y-29796D01*
G02X1293430Y-29494I302J0D01*
G01X1295840D01*
G37*
G36*
G01X1229258Y-33628D02*
Y-30228D01*
G02X1230761Y-28726I1503J-1D01*
G02X1231988Y-29361I0J-1503D01*
G01X1232008Y-29389D01*
X1232065Y-29429D01*
X1232380Y-29514D01*
X1232450Y-29508D01*
X1232482Y-29493D01*
G02X1232608Y-29466I125J-275D01*
G01X1235018D01*
G02X1235320Y-29768I0J-302D01*
G01Y-34088D01*
G02X1235018Y-34390I-302J0D01*
G01X1232608D01*
G02X1232482Y-34363I-1J302D01*
G01X1232450Y-34348D01*
X1232380Y-34342D01*
X1232065Y-34427D01*
X1232008Y-34467D01*
X1231988Y-34495D01*
G02X1230761Y-35130I-1227J868D01*
G02X1229258Y-33628I-1J1502D01*
G37*
G36*
G01X1009340Y-29364D02*
G02X1009466Y-29391I1J-302D01*
G01X1009498Y-29406D01*
X1009568Y-29412D01*
X1009883Y-29327D01*
X1009940Y-29287D01*
X1009960Y-29259D01*
G02X1011187Y-28624I1227J-868D01*
G02X1012690Y-30126I1J-1502D01*
G01Y-33526D01*
G02X1011187Y-35028I-1503J1D01*
G02X1009960Y-34393I0J1503D01*
G01X1009940Y-34365D01*
X1009883Y-34325D01*
X1009568Y-34240D01*
X1009498Y-34246D01*
X1009466Y-34261D01*
G02X1009340Y-34288I-125J275D01*
G01X1006930D01*
G02X1006628Y-33986I0J302D01*
G01Y-29666D01*
G02X1006930Y-29364I302J0D01*
G01X1009340D01*
G37*
G36*
G01X607977Y1552080D02*
X555513D01*
G02X555210Y1552383I0J303D01*
G01Y1643194D01*
G02X555513Y1643498I303J1D01*
G01X608266D01*
G02X608570Y1643194I0J-304D01*
G01Y1552672D01*
X607977Y1552080D01*
G37*
G36*
G01X77909Y1354943D02*
X79215Y1355796D01*
X80171D01*
G02X80374Y1355593I0J-203D01*
G01Y1352693D01*
G02X80171Y1352490I-203J0D01*
G01X79215D01*
X79167Y1352520D01*
G02X79165Y1352522I137J139D01*
G01X79140Y1352538D01*
X77900Y1353346D01*
G03X77715Y1353341I-88J-180D01*
G01X76417Y1352490D01*
X75461D01*
G02X75258Y1352693I0J203D01*
G01Y1355593D01*
G02X75461Y1355796I203J0D01*
G01X76422D01*
X77725Y1354942D01*
G03X77909Y1354943I91J178D01*
G37*
G36*
G01X90149D02*
X91455Y1355796D01*
X92411D01*
G02X92614Y1355593I0J-203D01*
G01Y1352693D01*
G02X92411Y1352490I-203J0D01*
G01X91455D01*
X91407Y1352520D01*
G02X91405Y1352522I137J139D01*
G01X91380Y1352538D01*
X90140Y1353346D01*
G03X89955Y1353341I-88J-180D01*
G01X88657Y1352490D01*
X87701D01*
G02X87498Y1352693I0J203D01*
G01Y1355593D01*
G02X87701Y1355796I203J0D01*
G01X88662D01*
X89965Y1354942D01*
G03X90149Y1354943I91J178D01*
G37*
G36*
G01X102389D02*
X103695Y1355796D01*
X104651D01*
G02X104854Y1355593I0J-203D01*
G01Y1352693D01*
G02X104651Y1352490I-203J0D01*
G01X103695D01*
X103647Y1352520D01*
G02X103645Y1352522I137J139D01*
G01X103620Y1352538D01*
X102380Y1353346D01*
G03X102195Y1353341I-88J-180D01*
G01X100897Y1352490D01*
X99941D01*
G02X99738Y1352693I0J203D01*
G01Y1355593D01*
G02X99941Y1355796I203J0D01*
G01X100902D01*
X102205Y1354942D01*
G03X102389Y1354943I91J178D01*
G37*
G36*
G01X114629D02*
X115935Y1355796D01*
X116891D01*
G02X117094Y1355593I0J-203D01*
G01Y1352693D01*
G02X116891Y1352490I-203J0D01*
G01X115935D01*
X115887Y1352520D01*
G02X115885Y1352522I137J139D01*
G01X115860Y1352538D01*
X114620Y1353346D01*
G03X114435Y1353341I-88J-180D01*
G01X113137Y1352490D01*
X112181D01*
G02X111978Y1352693I0J203D01*
G01Y1355593D01*
G02X112181Y1355796I203J0D01*
G01X113142D01*
X114445Y1354942D01*
G03X114629Y1354943I91J178D01*
G37*
G36*
G01X126869D02*
X128175Y1355796D01*
X129131D01*
G02X129334Y1355593I0J-203D01*
G01Y1352693D01*
G02X129131Y1352490I-203J0D01*
G01X128175D01*
X128127Y1352520D01*
G02X128125Y1352522I137J139D01*
G01X128100Y1352538D01*
X126860Y1353346D01*
G03X126675Y1353341I-88J-180D01*
G01X125377Y1352490D01*
X124421D01*
G02X124218Y1352693I0J203D01*
G01Y1355593D01*
G02X124421Y1355796I203J0D01*
G01X125382D01*
X126685Y1354942D01*
G03X126869Y1354943I91J178D01*
G37*
G36*
G01X139109D02*
X140415Y1355796D01*
X141371D01*
G02X141574Y1355593I0J-203D01*
G01Y1352693D01*
G02X141371Y1352490I-203J0D01*
G01X140415D01*
X140367Y1352520D01*
G02X140365Y1352522I137J139D01*
G01X140340Y1352538D01*
X139100Y1353346D01*
G03X138915Y1353341I-88J-180D01*
G01X137617Y1352490D01*
X136661D01*
G02X136458Y1352693I0J203D01*
G01Y1355593D01*
G02X136661Y1355796I203J0D01*
G01X137622D01*
X138925Y1354942D01*
G03X139109Y1354943I91J178D01*
G37*
G36*
G01X151349D02*
X152655Y1355796D01*
X153611D01*
G02X153814Y1355593I0J-203D01*
G01Y1352693D01*
G02X153611Y1352490I-203J0D01*
G01X152655D01*
X152607Y1352520D01*
G02X152605Y1352522I137J139D01*
G01X152580Y1352538D01*
X151340Y1353346D01*
G03X151155Y1353341I-88J-180D01*
G01X149857Y1352490D01*
X148901D01*
G02X148698Y1352693I0J203D01*
G01Y1355593D01*
G02X148901Y1355796I203J0D01*
G01X149862D01*
X151165Y1354942D01*
G03X151349Y1354943I91J178D01*
G37*
G36*
G01X163589D02*
X164895Y1355796D01*
X165851D01*
G02X166054Y1355593I0J-203D01*
G01Y1352693D01*
G02X165851Y1352490I-203J0D01*
G01X164895D01*
X164847Y1352520D01*
G02X164845Y1352522I137J139D01*
G01X164820Y1352538D01*
X163580Y1353346D01*
G03X163395Y1353341I-88J-180D01*
G01X162097Y1352490D01*
X161141D01*
G02X160938Y1352693I0J203D01*
G01Y1355593D01*
G02X161141Y1355796I203J0D01*
G01X162102D01*
X163405Y1354942D01*
G03X163589Y1354943I91J178D01*
G37*
G36*
G01X175829D02*
X177135Y1355796D01*
X178091D01*
G02X178294Y1355593I0J-203D01*
G01Y1352693D01*
G02X178091Y1352490I-203J0D01*
G01X177135D01*
X177087Y1352520D01*
G02X177085Y1352522I137J139D01*
G01X177060Y1352538D01*
X175820Y1353346D01*
G03X175635Y1353341I-88J-180D01*
G01X174337Y1352490D01*
X173381D01*
G02X173178Y1352693I0J203D01*
G01Y1355593D01*
G02X173381Y1355796I203J0D01*
G01X174342D01*
X175645Y1354942D01*
G03X175829Y1354943I91J178D01*
G37*
G36*
G01X188069D02*
X189375Y1355796D01*
X190331D01*
G02X190534Y1355593I0J-203D01*
G01Y1352693D01*
G02X190331Y1352490I-203J0D01*
G01X189375D01*
X189327Y1352520D01*
G02X189325Y1352522I137J139D01*
G01X189300Y1352538D01*
X188060Y1353346D01*
G03X187875Y1353341I-88J-180D01*
G01X186577Y1352490D01*
X185621D01*
G02X185418Y1352693I0J203D01*
G01Y1355593D01*
G02X185621Y1355796I203J0D01*
G01X186582D01*
X187885Y1354942D01*
G03X188069Y1354943I91J178D01*
G37*
G36*
G01X200309D02*
X201615Y1355796D01*
X202571D01*
G02X202774Y1355593I0J-203D01*
G01Y1352693D01*
G02X202571Y1352490I-203J0D01*
G01X201615D01*
X201567Y1352520D01*
G02X201565Y1352522I137J139D01*
G01X201540Y1352538D01*
X200300Y1353346D01*
G03X200115Y1353341I-88J-180D01*
G01X198817Y1352490D01*
X197861D01*
G02X197658Y1352693I0J203D01*
G01Y1355593D01*
G02X197861Y1355796I203J0D01*
G01X198822D01*
X200125Y1354942D01*
G03X200309Y1354943I91J178D01*
G37*
G36*
G01X243420D02*
X244726Y1355796D01*
X245682D01*
G02X245886Y1355593I1J-203D01*
G01Y1352693D01*
G02X245682Y1352490I-204J1D01*
G01X244726D01*
X244678Y1352520D01*
G02X244676Y1352522I137J139D01*
G01X244651Y1352538D01*
X243411Y1353346D01*
G03X243226Y1353341I-88J-180D01*
G01X241928Y1352490D01*
X240972D01*
G02X240768Y1352693I-1J203D01*
G01Y1355593D01*
G02X240972Y1355796I204J-1D01*
G01X241933D01*
X243236Y1354942D01*
G03X243420Y1354943I91J178D01*
G37*
G36*
G01X255660D02*
X256966Y1355796D01*
X257922D01*
G02X258126Y1355593I1J-203D01*
G01Y1352693D01*
G02X257922Y1352490I-204J1D01*
G01X256966D01*
X256918Y1352520D01*
G02X256916Y1352522I137J139D01*
G01X256891Y1352538D01*
X255651Y1353346D01*
G03X255466Y1353341I-88J-180D01*
G01X254168Y1352490D01*
X253212D01*
G02X253008Y1352693I-1J203D01*
G01Y1355593D01*
G02X253212Y1355796I204J-1D01*
G01X254173D01*
X255476Y1354942D01*
G03X255660Y1354943I91J178D01*
G37*
G36*
G01X267900D02*
X269206Y1355796D01*
X270162D01*
G02X270366Y1355593I1J-203D01*
G01Y1352693D01*
G02X270162Y1352490I-204J1D01*
G01X269206D01*
X269158Y1352520D01*
G02X269156Y1352522I137J139D01*
G01X269131Y1352538D01*
X267891Y1353346D01*
G03X267706Y1353341I-88J-180D01*
G01X266408Y1352490D01*
X265452D01*
G02X265248Y1352693I-1J203D01*
G01Y1355593D01*
G02X265452Y1355796I204J-1D01*
G01X266413D01*
X267716Y1354942D01*
G03X267900Y1354943I91J178D01*
G37*
G36*
G01X280140D02*
X281446Y1355796D01*
X282402D01*
G02X282606Y1355593I1J-203D01*
G01Y1352693D01*
G02X282402Y1352490I-204J1D01*
G01X281446D01*
X281398Y1352520D01*
G02X281396Y1352522I137J139D01*
G01X281371Y1352538D01*
X280131Y1353346D01*
G03X279946Y1353341I-88J-180D01*
G01X278648Y1352490D01*
X277692D01*
G02X277488Y1352693I-1J203D01*
G01Y1355593D01*
G02X277692Y1355796I204J-1D01*
G01X278653D01*
X279956Y1354942D01*
G03X280140Y1354943I91J178D01*
G37*
G36*
G01X292380D02*
X293686Y1355796D01*
X294642D01*
G02X294846Y1355593I1J-203D01*
G01Y1352693D01*
G02X294642Y1352490I-204J1D01*
G01X293686D01*
X293638Y1352520D01*
G02X293636Y1352522I137J139D01*
G01X293611Y1352538D01*
X292371Y1353346D01*
G03X292186Y1353341I-88J-180D01*
G01X290888Y1352490D01*
X289932D01*
G02X289728Y1352693I-1J203D01*
G01Y1355593D01*
G02X289932Y1355796I204J-1D01*
G01X290893D01*
X292196Y1354942D01*
G03X292380Y1354943I91J178D01*
G37*
G36*
G01X304620D02*
X305926Y1355796D01*
X306882D01*
G02X307086Y1355593I1J-203D01*
G01Y1352693D01*
G02X306882Y1352490I-204J1D01*
G01X305926D01*
X305878Y1352520D01*
G02X305876Y1352522I137J139D01*
G01X305851Y1352538D01*
X304611Y1353346D01*
G03X304426Y1353341I-88J-180D01*
G01X303128Y1352490D01*
X302172D01*
G02X301968Y1352693I-1J203D01*
G01Y1355593D01*
G02X302172Y1355796I204J-1D01*
G01X303133D01*
X304436Y1354942D01*
G03X304620Y1354943I91J178D01*
G37*
G36*
G01X316860D02*
X318166Y1355796D01*
X319122D01*
G02X319326Y1355593I1J-203D01*
G01Y1352693D01*
G02X319122Y1352490I-204J1D01*
G01X318166D01*
X318118Y1352520D01*
G02X318116Y1352522I137J139D01*
G01X318091Y1352538D01*
X316851Y1353346D01*
G03X316666Y1353341I-88J-180D01*
G01X315368Y1352490D01*
X314412D01*
G02X314208Y1352693I-1J203D01*
G01Y1355593D01*
G02X314412Y1355796I204J-1D01*
G01X315373D01*
X316676Y1354942D01*
G03X316860Y1354943I91J178D01*
G37*
G36*
G01X329100D02*
X330406Y1355796D01*
X331362D01*
G02X331566Y1355593I1J-203D01*
G01Y1352693D01*
G02X331362Y1352490I-204J1D01*
G01X330406D01*
X330358Y1352520D01*
G02X330356Y1352522I137J139D01*
G01X330331Y1352538D01*
X329091Y1353346D01*
G03X328906Y1353341I-88J-180D01*
G01X327608Y1352490D01*
X326652D01*
G02X326448Y1352693I-1J203D01*
G01Y1355593D01*
G02X326652Y1355796I204J-1D01*
G01X327613D01*
X328916Y1354942D01*
G03X329100Y1354943I91J178D01*
G37*
G36*
G01X341340D02*
X342646Y1355796D01*
X343602D01*
G02X343806Y1355593I1J-203D01*
G01Y1352693D01*
G02X343602Y1352490I-204J1D01*
G01X342646D01*
X342598Y1352520D01*
G02X342596Y1352522I137J139D01*
G01X342571Y1352538D01*
X341331Y1353346D01*
G03X341146Y1353341I-88J-180D01*
G01X339848Y1352490D01*
X338892D01*
G02X338688Y1352693I-1J203D01*
G01Y1355593D01*
G02X338892Y1355796I204J-1D01*
G01X339853D01*
X341156Y1354942D01*
G03X341340Y1354943I91J178D01*
G37*
G36*
G01X353580D02*
X354886Y1355796D01*
X355842D01*
G02X356046Y1355593I1J-203D01*
G01Y1352693D01*
G02X355842Y1352490I-204J1D01*
G01X354886D01*
X354838Y1352520D01*
G02X354836Y1352522I137J139D01*
G01X354811Y1352538D01*
X353571Y1353346D01*
G03X353386Y1353341I-88J-180D01*
G01X352088Y1352490D01*
X351132D01*
G02X350928Y1352693I-1J203D01*
G01Y1355593D01*
G02X351132Y1355796I204J-1D01*
G01X352093D01*
X353396Y1354942D01*
G03X353580Y1354943I91J178D01*
G37*
G36*
G01X365820D02*
X367126Y1355796D01*
X368082D01*
G02X368286Y1355593I1J-203D01*
G01Y1352693D01*
G02X368082Y1352490I-204J1D01*
G01X367126D01*
X367078Y1352520D01*
G02X367076Y1352522I137J139D01*
G01X367051Y1352538D01*
X365811Y1353346D01*
G03X365626Y1353341I-88J-180D01*
G01X364328Y1352490D01*
X363372D01*
G02X363168Y1352693I-1J203D01*
G01Y1355593D01*
G02X363372Y1355796I204J-1D01*
G01X364333D01*
X365636Y1354942D01*
G03X365820Y1354943I91J178D01*
G37*
G36*
G01X442199D02*
X443505Y1355796D01*
X444461D01*
G02X444664Y1355593I0J-203D01*
G01Y1352693D01*
G02X444461Y1352490I-203J0D01*
G01X443505D01*
X443457Y1352520D01*
G02X443455Y1352522I137J139D01*
G01X443430Y1352538D01*
X442190Y1353346D01*
G03X442005Y1353341I-88J-180D01*
G01X440707Y1352490D01*
X439751D01*
G02X439548Y1352693I0J203D01*
G01Y1355593D01*
G02X439751Y1355796I203J0D01*
G01X440712D01*
X442015Y1354942D01*
G03X442199Y1354943I91J178D01*
G37*
G36*
G01X454439D02*
X455745Y1355796D01*
X456701D01*
G02X456904Y1355593I0J-203D01*
G01Y1352693D01*
G02X456701Y1352490I-203J0D01*
G01X455745D01*
X455697Y1352520D01*
G02X455695Y1352522I137J139D01*
G01X455670Y1352538D01*
X454430Y1353346D01*
G03X454245Y1353341I-88J-180D01*
G01X452947Y1352490D01*
X451991D01*
G02X451788Y1352693I0J203D01*
G01Y1355593D01*
G02X451991Y1355796I203J0D01*
G01X452952D01*
X454255Y1354942D01*
G03X454439Y1354943I91J178D01*
G37*
G36*
G01X466679D02*
X467985Y1355796D01*
X468941D01*
G02X469144Y1355593I0J-203D01*
G01Y1352693D01*
G02X468941Y1352490I-203J0D01*
G01X467985D01*
X467937Y1352520D01*
G02X467935Y1352522I137J139D01*
G01X467910Y1352538D01*
X466670Y1353346D01*
G03X466485Y1353341I-88J-180D01*
G01X465187Y1352490D01*
X464231D01*
G02X464028Y1352693I0J203D01*
G01Y1355593D01*
G02X464231Y1355796I203J0D01*
G01X465192D01*
X466495Y1354942D01*
G03X466679Y1354943I91J178D01*
G37*
G36*
G01X478919D02*
X480225Y1355796D01*
X481181D01*
G02X481384Y1355593I0J-203D01*
G01Y1352693D01*
G02X481181Y1352490I-203J0D01*
G01X480225D01*
X480177Y1352520D01*
G02X480175Y1352522I137J139D01*
G01X480150Y1352538D01*
X478910Y1353346D01*
G03X478725Y1353341I-88J-180D01*
G01X477427Y1352490D01*
X476471D01*
G02X476268Y1352693I0J203D01*
G01Y1355593D01*
G02X476471Y1355796I203J0D01*
G01X477432D01*
X478735Y1354942D01*
G03X478919Y1354943I91J178D01*
G37*
G36*
G01X491159D02*
X492465Y1355796D01*
X493421D01*
G02X493624Y1355593I0J-203D01*
G01Y1352693D01*
G02X493421Y1352490I-203J0D01*
G01X492465D01*
X492417Y1352520D01*
G02X492415Y1352522I137J139D01*
G01X492390Y1352538D01*
X491150Y1353346D01*
G03X490965Y1353341I-88J-180D01*
G01X489667Y1352490D01*
X488711D01*
G02X488508Y1352693I0J203D01*
G01Y1355593D01*
G02X488711Y1355796I203J0D01*
G01X489672D01*
X490975Y1354942D01*
G03X491159Y1354943I91J178D01*
G37*
G36*
G01X503399D02*
X504705Y1355796D01*
X505661D01*
G02X505864Y1355593I0J-203D01*
G01Y1352693D01*
G02X505661Y1352490I-203J0D01*
G01X504705D01*
X504657Y1352520D01*
G02X504655Y1352522I137J139D01*
G01X504630Y1352538D01*
X503390Y1353346D01*
G03X503205Y1353341I-88J-180D01*
G01X501907Y1352490D01*
X500951D01*
G02X500748Y1352693I0J203D01*
G01Y1355593D01*
G02X500951Y1355796I203J0D01*
G01X501912D01*
X503215Y1354942D01*
G03X503399Y1354943I91J178D01*
G37*
G36*
G01X515639D02*
X516945Y1355796D01*
X517901D01*
G02X518104Y1355593I0J-203D01*
G01Y1352693D01*
G02X517901Y1352490I-203J0D01*
G01X516945D01*
X516897Y1352520D01*
G02X516895Y1352522I137J139D01*
G01X516870Y1352538D01*
X515630Y1353346D01*
G03X515445Y1353341I-88J-180D01*
G01X514147Y1352490D01*
X513191D01*
G02X512988Y1352693I0J203D01*
G01Y1355593D01*
G02X513191Y1355796I203J0D01*
G01X514152D01*
X515455Y1354942D01*
G03X515639Y1354943I91J178D01*
G37*
G36*
G01X527879D02*
X529185Y1355796D01*
X530141D01*
G02X530344Y1355593I0J-203D01*
G01Y1352693D01*
G02X530141Y1352490I-203J0D01*
G01X529185D01*
X529137Y1352520D01*
G02X529135Y1352522I137J139D01*
G01X529110Y1352538D01*
X527870Y1353346D01*
G03X527685Y1353341I-88J-180D01*
G01X526387Y1352490D01*
X525431D01*
G02X525228Y1352693I0J203D01*
G01Y1355593D01*
G02X525431Y1355796I203J0D01*
G01X526392D01*
X527695Y1354942D01*
G03X527879Y1354943I91J178D01*
G37*
G36*
G01X540119D02*
X541425Y1355796D01*
X542381D01*
G02X542584Y1355593I0J-203D01*
G01Y1352693D01*
G02X542381Y1352490I-203J0D01*
G01X541425D01*
X541377Y1352520D01*
G02X541375Y1352522I137J139D01*
G01X541350Y1352538D01*
X540110Y1353346D01*
G03X539925Y1353341I-88J-180D01*
G01X538627Y1352490D01*
X537671D01*
G02X537468Y1352693I0J203D01*
G01Y1355593D01*
G02X537671Y1355796I203J0D01*
G01X538632D01*
X539935Y1354942D01*
G03X540119Y1354943I91J178D01*
G37*
G36*
G01X552359D02*
X553665Y1355796D01*
X554621D01*
G02X554824Y1355593I0J-203D01*
G01Y1352693D01*
G02X554621Y1352490I-203J0D01*
G01X553665D01*
X553617Y1352520D01*
G02X553615Y1352522I137J139D01*
G01X553590Y1352538D01*
X552350Y1353346D01*
G03X552165Y1353341I-88J-180D01*
G01X550867Y1352490D01*
X549911D01*
G02X549708Y1352693I0J203D01*
G01Y1355593D01*
G02X549911Y1355796I203J0D01*
G01X550872D01*
X552175Y1354942D01*
G03X552359Y1354943I91J178D01*
G37*
G36*
G01X564599D02*
X565905Y1355796D01*
X566861D01*
G02X567064Y1355593I0J-203D01*
G01Y1352693D01*
G02X566861Y1352490I-203J0D01*
G01X565905D01*
X565857Y1352520D01*
G02X565855Y1352522I137J139D01*
G01X565830Y1352538D01*
X564590Y1353346D01*
G03X564405Y1353341I-88J-180D01*
G01X563107Y1352490D01*
X562151D01*
G02X561948Y1352693I0J203D01*
G01Y1355593D01*
G02X562151Y1355796I203J0D01*
G01X563112D01*
X564415Y1354942D01*
G03X564599Y1354943I91J178D01*
G37*
G36*
G01X652565D02*
X653871Y1355796D01*
X654827D01*
G02X655030Y1355593I0J-203D01*
G01Y1352693D01*
G02X654827Y1352490I-203J0D01*
G01X653871D01*
X653823Y1352520D01*
G02X653821Y1352522I137J139D01*
G01X653796Y1352538D01*
X652556Y1353346D01*
G03X652371Y1353341I-88J-180D01*
G01X651073Y1352490D01*
X650117D01*
G02X649914Y1352693I0J203D01*
G01Y1355593D01*
G02X650117Y1355796I203J0D01*
G01X651078D01*
X652381Y1354942D01*
G03X652565Y1354943I91J178D01*
G37*
G36*
G01X664805D02*
X666111Y1355796D01*
X667067D01*
G02X667270Y1355593I0J-203D01*
G01Y1352693D01*
G02X667067Y1352490I-203J0D01*
G01X666111D01*
X666063Y1352520D01*
G02X666061Y1352522I137J139D01*
G01X666036Y1352538D01*
X664796Y1353346D01*
G03X664611Y1353341I-88J-180D01*
G01X663313Y1352490D01*
X662357D01*
G02X662154Y1352693I0J203D01*
G01Y1355593D01*
G02X662357Y1355796I203J0D01*
G01X663318D01*
X664621Y1354942D01*
G03X664805Y1354943I91J178D01*
G37*
G36*
G01X677045D02*
X678351Y1355796D01*
X679307D01*
G02X679510Y1355593I0J-203D01*
G01Y1352693D01*
G02X679307Y1352490I-203J0D01*
G01X678351D01*
X678303Y1352520D01*
G02X678301Y1352522I137J139D01*
G01X678276Y1352538D01*
X677036Y1353346D01*
G03X676851Y1353341I-88J-180D01*
G01X675553Y1352490D01*
X674597D01*
G02X674394Y1352693I0J203D01*
G01Y1355593D01*
G02X674597Y1355796I203J0D01*
G01X675558D01*
X676861Y1354942D01*
G03X677045Y1354943I91J178D01*
G37*
G36*
G01X689285D02*
X690591Y1355796D01*
X691547D01*
G02X691750Y1355593I0J-203D01*
G01Y1352693D01*
G02X691547Y1352490I-203J0D01*
G01X690591D01*
X690543Y1352520D01*
G02X690541Y1352522I137J139D01*
G01X690516Y1352538D01*
X689276Y1353346D01*
G03X689091Y1353341I-88J-180D01*
G01X687793Y1352490D01*
X686837D01*
G02X686634Y1352693I0J203D01*
G01Y1355593D01*
G02X686837Y1355796I203J0D01*
G01X687798D01*
X689101Y1354942D01*
G03X689285Y1354943I91J178D01*
G37*
G36*
G01X701525D02*
X702831Y1355796D01*
X703787D01*
G02X703990Y1355593I0J-203D01*
G01Y1352693D01*
G02X703787Y1352490I-203J0D01*
G01X702831D01*
X702783Y1352520D01*
G02X702781Y1352522I137J139D01*
G01X702756Y1352538D01*
X701516Y1353346D01*
G03X701331Y1353341I-88J-180D01*
G01X700033Y1352490D01*
X699077D01*
G02X698874Y1352693I0J203D01*
G01Y1355593D01*
G02X699077Y1355796I203J0D01*
G01X700038D01*
X701341Y1354942D01*
G03X701525Y1354943I91J178D01*
G37*
G36*
G01X713765D02*
X715071Y1355796D01*
X716027D01*
G02X716230Y1355593I0J-203D01*
G01Y1352693D01*
G02X716027Y1352490I-203J0D01*
G01X715071D01*
X715023Y1352520D01*
G02X715021Y1352522I137J139D01*
G01X714996Y1352538D01*
X713756Y1353346D01*
G03X713571Y1353341I-88J-180D01*
G01X712273Y1352490D01*
X711317D01*
G02X711114Y1352693I0J203D01*
G01Y1355593D01*
G02X711317Y1355796I203J0D01*
G01X712278D01*
X713581Y1354942D01*
G03X713765Y1354943I91J178D01*
G37*
G36*
G01X726005D02*
X727311Y1355796D01*
X728267D01*
G02X728470Y1355593I0J-203D01*
G01Y1352693D01*
G02X728267Y1352490I-203J0D01*
G01X727311D01*
X727263Y1352520D01*
G02X727261Y1352522I137J139D01*
G01X727236Y1352538D01*
X725996Y1353346D01*
G03X725811Y1353341I-88J-180D01*
G01X724513Y1352490D01*
X723557D01*
G02X723354Y1352693I0J203D01*
G01Y1355593D01*
G02X723557Y1355796I203J0D01*
G01X724518D01*
X725821Y1354942D01*
G03X726005Y1354943I91J178D01*
G37*
G36*
G01X738245D02*
X739551Y1355796D01*
X740507D01*
G02X740710Y1355593I0J-203D01*
G01Y1352693D01*
G02X740507Y1352490I-203J0D01*
G01X739551D01*
X739503Y1352520D01*
G02X739501Y1352522I137J139D01*
G01X739476Y1352538D01*
X738236Y1353346D01*
G03X738051Y1353341I-88J-180D01*
G01X736753Y1352490D01*
X735797D01*
G02X735594Y1352693I0J203D01*
G01Y1355593D01*
G02X735797Y1355796I203J0D01*
G01X736758D01*
X738061Y1354942D01*
G03X738245Y1354943I91J178D01*
G37*
G36*
G01X750485D02*
X751791Y1355796D01*
X752747D01*
G02X752950Y1355593I0J-203D01*
G01Y1352693D01*
G02X752747Y1352490I-203J0D01*
G01X751791D01*
X751743Y1352520D01*
G02X751741Y1352522I137J139D01*
G01X751716Y1352538D01*
X750476Y1353346D01*
G03X750291Y1353341I-88J-180D01*
G01X748993Y1352490D01*
X748037D01*
G02X747834Y1352693I0J203D01*
G01Y1355593D01*
G02X748037Y1355796I203J0D01*
G01X748998D01*
X750301Y1354942D01*
G03X750485Y1354943I91J178D01*
G37*
G36*
G01X762725D02*
X764031Y1355796D01*
X764987D01*
G02X765190Y1355593I0J-203D01*
G01Y1352693D01*
G02X764987Y1352490I-203J0D01*
G01X764031D01*
X763983Y1352520D01*
G02X763981Y1352522I137J139D01*
G01X763956Y1352538D01*
X762716Y1353346D01*
G03X762531Y1353341I-88J-180D01*
G01X761233Y1352490D01*
X760277D01*
G02X760074Y1352693I0J203D01*
G01Y1355593D01*
G02X760277Y1355796I203J0D01*
G01X761238D01*
X762541Y1354942D01*
G03X762725Y1354943I91J178D01*
G37*
G36*
G01X774965D02*
X776271Y1355796D01*
X777227D01*
G02X777430Y1355593I0J-203D01*
G01Y1352693D01*
G02X777227Y1352490I-203J0D01*
G01X776271D01*
X776223Y1352520D01*
G02X776221Y1352522I137J139D01*
G01X776196Y1352538D01*
X774956Y1353346D01*
G03X774771Y1353341I-88J-180D01*
G01X773473Y1352490D01*
X772517D01*
G02X772314Y1352693I0J203D01*
G01Y1355593D01*
G02X772517Y1355796I203J0D01*
G01X773478D01*
X774781Y1354942D01*
G03X774965Y1354943I91J178D01*
G37*
G36*
G01X1056510D02*
X1057816Y1355796D01*
X1058772D01*
G02X1058976Y1355593I1J-203D01*
G01Y1352693D01*
G02X1058772Y1352490I-204J1D01*
G01X1057816D01*
X1057768Y1352520D01*
G02X1057766Y1352522I137J139D01*
G01X1057741Y1352538D01*
X1056501Y1353346D01*
G03X1056316Y1353341I-88J-180D01*
G01X1055018Y1352490D01*
X1054062D01*
G02X1053858Y1352693I-1J203D01*
G01Y1355593D01*
G02X1054062Y1355796I204J-1D01*
G01X1055023D01*
X1056326Y1354942D01*
G03X1056510Y1354943I91J178D01*
G37*
G36*
G01X1068750D02*
X1070056Y1355796D01*
X1071012D01*
G02X1071216Y1355593I1J-203D01*
G01Y1352693D01*
G02X1071012Y1352490I-204J1D01*
G01X1070056D01*
X1070008Y1352520D01*
G02X1070006Y1352522I137J139D01*
G01X1069981Y1352538D01*
X1068741Y1353346D01*
G03X1068556Y1353341I-88J-180D01*
G01X1067258Y1352490D01*
X1066302D01*
G02X1066098Y1352693I-1J203D01*
G01Y1355593D01*
G02X1066302Y1355796I204J-1D01*
G01X1067263D01*
X1068566Y1354942D01*
G03X1068750Y1354943I91J178D01*
G37*
G36*
G01X1080990D02*
X1082296Y1355796D01*
X1083252D01*
G02X1083456Y1355593I1J-203D01*
G01Y1352693D01*
G02X1083252Y1352490I-204J1D01*
G01X1082296D01*
X1082248Y1352520D01*
G02X1082246Y1352522I137J139D01*
G01X1082221Y1352538D01*
X1080981Y1353346D01*
G03X1080796Y1353341I-88J-180D01*
G01X1079498Y1352490D01*
X1078542D01*
G02X1078338Y1352693I-1J203D01*
G01Y1355593D01*
G02X1078542Y1355796I204J-1D01*
G01X1079503D01*
X1080806Y1354942D01*
G03X1080990Y1354943I91J178D01*
G37*
G36*
G01X1093230D02*
X1094536Y1355796D01*
X1095492D01*
G02X1095696Y1355593I1J-203D01*
G01Y1352693D01*
G02X1095492Y1352490I-204J1D01*
G01X1094536D01*
X1094488Y1352520D01*
G02X1094486Y1352522I137J139D01*
G01X1094461Y1352538D01*
X1093221Y1353346D01*
G03X1093036Y1353341I-88J-180D01*
G01X1091738Y1352490D01*
X1090782D01*
G02X1090578Y1352693I-1J203D01*
G01Y1355593D01*
G02X1090782Y1355796I204J-1D01*
G01X1091743D01*
X1093046Y1354942D01*
G03X1093230Y1354943I91J178D01*
G37*
G36*
G01X1105470D02*
X1106776Y1355796D01*
X1107732D01*
G02X1107936Y1355593I1J-203D01*
G01Y1352693D01*
G02X1107732Y1352490I-204J1D01*
G01X1106776D01*
X1106728Y1352520D01*
G02X1106726Y1352522I137J139D01*
G01X1106701Y1352538D01*
X1105461Y1353346D01*
G03X1105276Y1353341I-88J-180D01*
G01X1103978Y1352490D01*
X1103022D01*
G02X1102818Y1352693I-1J203D01*
G01Y1355593D01*
G02X1103022Y1355796I204J-1D01*
G01X1103983D01*
X1105286Y1354942D01*
G03X1105470Y1354943I91J178D01*
G37*
G36*
G01X1117710D02*
X1119016Y1355796D01*
X1119972D01*
G02X1120176Y1355593I1J-203D01*
G01Y1352693D01*
G02X1119972Y1352490I-204J1D01*
G01X1119016D01*
X1118968Y1352520D01*
G02X1118966Y1352522I137J139D01*
G01X1118941Y1352538D01*
X1117701Y1353346D01*
G03X1117516Y1353341I-88J-180D01*
G01X1116218Y1352490D01*
X1115262D01*
G02X1115058Y1352693I-1J203D01*
G01Y1355593D01*
G02X1115262Y1355796I204J-1D01*
G01X1116223D01*
X1117526Y1354942D01*
G03X1117710Y1354943I91J178D01*
G37*
G36*
G01X1129950D02*
X1131256Y1355796D01*
X1132212D01*
G02X1132416Y1355593I1J-203D01*
G01Y1352693D01*
G02X1132212Y1352490I-204J1D01*
G01X1131256D01*
X1131208Y1352520D01*
G02X1131206Y1352522I137J139D01*
G01X1131181Y1352538D01*
X1129941Y1353346D01*
G03X1129756Y1353341I-88J-180D01*
G01X1128458Y1352490D01*
X1127502D01*
G02X1127298Y1352693I-1J203D01*
G01Y1355593D01*
G02X1127502Y1355796I204J-1D01*
G01X1128463D01*
X1129766Y1354942D01*
G03X1129950Y1354943I91J178D01*
G37*
G36*
G01X1142190D02*
X1143496Y1355796D01*
X1144452D01*
G02X1144656Y1355593I1J-203D01*
G01Y1352693D01*
G02X1144452Y1352490I-204J1D01*
G01X1143496D01*
X1143448Y1352520D01*
G02X1143446Y1352522I137J139D01*
G01X1143421Y1352538D01*
X1142181Y1353346D01*
G03X1141996Y1353341I-88J-180D01*
G01X1140698Y1352490D01*
X1139742D01*
G02X1139538Y1352693I-1J203D01*
G01Y1355593D01*
G02X1139742Y1355796I204J-1D01*
G01X1140703D01*
X1142006Y1354942D01*
G03X1142190Y1354943I91J178D01*
G37*
G36*
G01X1154430D02*
X1155736Y1355796D01*
X1156692D01*
G02X1156896Y1355593I1J-203D01*
G01Y1352693D01*
G02X1156692Y1352490I-204J1D01*
G01X1155736D01*
X1155688Y1352520D01*
G02X1155686Y1352522I137J139D01*
G01X1155661Y1352538D01*
X1154421Y1353346D01*
G03X1154236Y1353341I-88J-180D01*
G01X1152938Y1352490D01*
X1151982D01*
G02X1151778Y1352693I-1J203D01*
G01Y1355593D01*
G02X1151982Y1355796I204J-1D01*
G01X1152943D01*
X1154246Y1354942D01*
G03X1154430Y1354943I91J178D01*
G37*
G36*
G01X1166670D02*
X1167976Y1355796D01*
X1168932D01*
G02X1169136Y1355593I1J-203D01*
G01Y1352693D01*
G02X1168932Y1352490I-204J1D01*
G01X1167976D01*
X1167928Y1352520D01*
G02X1167926Y1352522I137J139D01*
G01X1167901Y1352538D01*
X1166661Y1353346D01*
G03X1166476Y1353341I-88J-180D01*
G01X1165178Y1352490D01*
X1164222D01*
G02X1164018Y1352693I-1J203D01*
G01Y1355593D01*
G02X1164222Y1355796I204J-1D01*
G01X1165183D01*
X1166486Y1354942D01*
G03X1166670Y1354943I91J178D01*
G37*
G36*
G01X1178910D02*
X1180216Y1355796D01*
X1181172D01*
G02X1181376Y1355593I1J-203D01*
G01Y1352693D01*
G02X1181172Y1352490I-204J1D01*
G01X1180216D01*
X1180168Y1352520D01*
G02X1180166Y1352522I137J139D01*
G01X1180141Y1352538D01*
X1178901Y1353346D01*
G03X1178716Y1353341I-88J-180D01*
G01X1177418Y1352490D01*
X1176462D01*
G02X1176258Y1352693I-1J203D01*
G01Y1355593D01*
G02X1176462Y1355796I204J-1D01*
G01X1177423D01*
X1178726Y1354942D01*
G03X1178910Y1354943I91J178D01*
G37*
G36*
G01X1232123D02*
X1233429Y1355796D01*
X1234385D01*
G02X1234588Y1355593I0J-203D01*
G01Y1352693D01*
G02X1234385Y1352490I-203J0D01*
G01X1233429D01*
X1233381Y1352520D01*
G02X1233379Y1352522I137J139D01*
G01X1233354Y1352538D01*
X1232114Y1353346D01*
G03X1231929Y1353341I-88J-180D01*
G01X1230631Y1352490D01*
X1229675D01*
G02X1229472Y1352693I0J203D01*
G01Y1355593D01*
G02X1229675Y1355796I203J0D01*
G01X1230636D01*
X1231939Y1354942D01*
G03X1232123Y1354943I91J178D01*
G37*
G36*
G01X1244363D02*
X1245669Y1355796D01*
X1246625D01*
G02X1246828Y1355593I0J-203D01*
G01Y1352693D01*
G02X1246625Y1352490I-203J0D01*
G01X1245669D01*
X1245621Y1352520D01*
G02X1245619Y1352522I137J139D01*
G01X1245594Y1352538D01*
X1244354Y1353346D01*
G03X1244169Y1353341I-88J-180D01*
G01X1242871Y1352490D01*
X1241915D01*
G02X1241712Y1352693I0J203D01*
G01Y1355593D01*
G02X1241915Y1355796I203J0D01*
G01X1242876D01*
X1244179Y1354942D01*
G03X1244363Y1354943I91J178D01*
G37*
G36*
G01X1256603D02*
X1257909Y1355796D01*
X1258865D01*
G02X1259068Y1355593I0J-203D01*
G01Y1352693D01*
G02X1258865Y1352490I-203J0D01*
G01X1257909D01*
X1257861Y1352520D01*
G02X1257859Y1352522I137J139D01*
G01X1257834Y1352538D01*
X1256594Y1353346D01*
G03X1256409Y1353341I-88J-180D01*
G01X1255111Y1352490D01*
X1254155D01*
G02X1253952Y1352693I0J203D01*
G01Y1355593D01*
G02X1254155Y1355796I203J0D01*
G01X1255116D01*
X1256419Y1354942D01*
G03X1256603Y1354943I91J178D01*
G37*
G36*
G01X1268843D02*
X1270149Y1355796D01*
X1271105D01*
G02X1271308Y1355593I0J-203D01*
G01Y1352693D01*
G02X1271105Y1352490I-203J0D01*
G01X1270149D01*
X1270101Y1352520D01*
G02X1270099Y1352522I137J139D01*
G01X1270074Y1352538D01*
X1268834Y1353346D01*
G03X1268649Y1353341I-88J-180D01*
G01X1267351Y1352490D01*
X1266395D01*
G02X1266192Y1352693I0J203D01*
G01Y1355593D01*
G02X1266395Y1355796I203J0D01*
G01X1267356D01*
X1268659Y1354942D01*
G03X1268843Y1354943I91J178D01*
G37*
G36*
G01X1281083D02*
X1282389Y1355796D01*
X1283345D01*
G02X1283548Y1355593I0J-203D01*
G01Y1352693D01*
G02X1283345Y1352490I-203J0D01*
G01X1282389D01*
X1282341Y1352520D01*
G02X1282339Y1352522I137J139D01*
G01X1282314Y1352538D01*
X1281074Y1353346D01*
G03X1280889Y1353341I-88J-180D01*
G01X1279591Y1352490D01*
X1278635D01*
G02X1278432Y1352693I0J203D01*
G01Y1355593D01*
G02X1278635Y1355796I203J0D01*
G01X1279596D01*
X1280899Y1354942D01*
G03X1281083Y1354943I91J178D01*
G37*
G36*
G01X1293323D02*
X1294629Y1355796D01*
X1295585D01*
G02X1295788Y1355593I0J-203D01*
G01Y1352693D01*
G02X1295585Y1352490I-203J0D01*
G01X1294629D01*
X1294581Y1352520D01*
G02X1294579Y1352522I137J139D01*
G01X1294554Y1352538D01*
X1293314Y1353346D01*
G03X1293129Y1353341I-88J-180D01*
G01X1291831Y1352490D01*
X1290875D01*
G02X1290672Y1352693I0J203D01*
G01Y1355593D01*
G02X1290875Y1355796I203J0D01*
G01X1291836D01*
X1293139Y1354942D01*
G03X1293323Y1354943I91J178D01*
G37*
G36*
G01X1305563D02*
X1306869Y1355796D01*
X1307825D01*
G02X1308028Y1355593I0J-203D01*
G01Y1352693D01*
G02X1307825Y1352490I-203J0D01*
G01X1306869D01*
X1306821Y1352520D01*
G02X1306819Y1352522I137J139D01*
G01X1306794Y1352538D01*
X1305554Y1353346D01*
G03X1305369Y1353341I-88J-180D01*
G01X1304071Y1352490D01*
X1303115D01*
G02X1302912Y1352693I0J203D01*
G01Y1355593D01*
G02X1303115Y1355796I203J0D01*
G01X1304076D01*
X1305379Y1354942D01*
G03X1305563Y1354943I91J178D01*
G37*
G36*
G01X1317803D02*
X1319109Y1355796D01*
X1320065D01*
G02X1320268Y1355593I0J-203D01*
G01Y1352693D01*
G02X1320065Y1352490I-203J0D01*
G01X1319109D01*
X1319061Y1352520D01*
G02X1319059Y1352522I137J139D01*
G01X1319034Y1352538D01*
X1317794Y1353346D01*
G03X1317609Y1353341I-88J-180D01*
G01X1316311Y1352490D01*
X1315355D01*
G02X1315152Y1352693I0J203D01*
G01Y1355593D01*
G02X1315355Y1355796I203J0D01*
G01X1316316D01*
X1317619Y1354942D01*
G03X1317803Y1354943I91J178D01*
G37*
G36*
G01X1330043D02*
X1331349Y1355796D01*
X1332305D01*
G02X1332508Y1355593I0J-203D01*
G01Y1352693D01*
G02X1332305Y1352490I-203J0D01*
G01X1331349D01*
X1331301Y1352520D01*
G02X1331299Y1352522I137J139D01*
G01X1331274Y1352538D01*
X1330034Y1353346D01*
G03X1329849Y1353341I-88J-180D01*
G01X1328551Y1352490D01*
X1327595D01*
G02X1327392Y1352693I0J203D01*
G01Y1355593D01*
G02X1327595Y1355796I203J0D01*
G01X1328556D01*
X1329859Y1354942D01*
G03X1330043Y1354943I91J178D01*
G37*
G36*
G01X1342283D02*
X1343589Y1355796D01*
X1344545D01*
G02X1344748Y1355593I0J-203D01*
G01Y1352693D01*
G02X1344545Y1352490I-203J0D01*
G01X1343589D01*
X1343541Y1352520D01*
G02X1343539Y1352522I137J139D01*
G01X1343514Y1352538D01*
X1342274Y1353346D01*
G03X1342089Y1353341I-88J-180D01*
G01X1340791Y1352490D01*
X1339835D01*
G02X1339632Y1352693I0J203D01*
G01Y1355593D01*
G02X1339835Y1355796I203J0D01*
G01X1340796D01*
X1342099Y1354942D01*
G03X1342283Y1354943I91J178D01*
G37*
G36*
G01X1354523D02*
X1355829Y1355796D01*
X1356785D01*
G02X1356988Y1355593I0J-203D01*
G01Y1352693D01*
G02X1356785Y1352490I-203J0D01*
G01X1355829D01*
X1355781Y1352520D01*
G02X1355779Y1352522I137J139D01*
G01X1355754Y1352538D01*
X1354514Y1353346D01*
G03X1354329Y1353341I-88J-180D01*
G01X1353031Y1352490D01*
X1352075D01*
G02X1351872Y1352693I0J203D01*
G01Y1355593D01*
G02X1352075Y1355796I203J0D01*
G01X1353036D01*
X1354339Y1354942D01*
G03X1354523Y1354943I91J178D01*
G37*
G36*
G01X1463167D02*
X1464473Y1355796D01*
X1465429D01*
G02X1465632Y1355593I0J-203D01*
G01Y1352693D01*
G02X1465429Y1352490I-203J0D01*
G01X1464473D01*
X1464425Y1352520D01*
G02X1464423Y1352522I137J139D01*
G01X1464398Y1352538D01*
X1463158Y1353346D01*
G03X1462973Y1353341I-88J-180D01*
G01X1461675Y1352490D01*
X1460719D01*
G02X1460516Y1352693I0J203D01*
G01Y1355593D01*
G02X1460719Y1355796I203J0D01*
G01X1461680D01*
X1462983Y1354942D01*
G03X1463167Y1354943I91J178D01*
G37*
G36*
G01X1475407D02*
X1476713Y1355796D01*
X1477669D01*
G02X1477872Y1355593I0J-203D01*
G01Y1352693D01*
G02X1477669Y1352490I-203J0D01*
G01X1476713D01*
X1476665Y1352520D01*
G02X1476663Y1352522I137J139D01*
G01X1476638Y1352538D01*
X1475398Y1353346D01*
G03X1475213Y1353341I-88J-180D01*
G01X1473915Y1352490D01*
X1472959D01*
G02X1472756Y1352693I0J203D01*
G01Y1355593D01*
G02X1472959Y1355796I203J0D01*
G01X1473920D01*
X1475223Y1354942D01*
G03X1475407Y1354943I91J178D01*
G37*
G36*
G01X1487647D02*
X1488953Y1355796D01*
X1489909D01*
G02X1490112Y1355593I0J-203D01*
G01Y1352693D01*
G02X1489909Y1352490I-203J0D01*
G01X1488953D01*
X1488905Y1352520D01*
G02X1488903Y1352522I137J139D01*
G01X1488878Y1352538D01*
X1487638Y1353346D01*
G03X1487453Y1353341I-88J-180D01*
G01X1486155Y1352490D01*
X1485199D01*
G02X1484996Y1352693I0J203D01*
G01Y1355593D01*
G02X1485199Y1355796I203J0D01*
G01X1486160D01*
X1487463Y1354942D01*
G03X1487647Y1354943I91J178D01*
G37*
G36*
G01X1499887D02*
X1501193Y1355796D01*
X1502149D01*
G02X1502352Y1355593I0J-203D01*
G01Y1352693D01*
G02X1502149Y1352490I-203J0D01*
G01X1501193D01*
X1501145Y1352520D01*
G02X1501143Y1352522I137J139D01*
G01X1501118Y1352538D01*
X1499878Y1353346D01*
G03X1499693Y1353341I-88J-180D01*
G01X1498395Y1352490D01*
X1497439D01*
G02X1497236Y1352693I0J203D01*
G01Y1355593D01*
G02X1497439Y1355796I203J0D01*
G01X1498400D01*
X1499703Y1354942D01*
G03X1499887Y1354943I91J178D01*
G37*
G36*
G01X1512127D02*
X1513433Y1355796D01*
X1514389D01*
G02X1514592Y1355593I0J-203D01*
G01Y1352693D01*
G02X1514389Y1352490I-203J0D01*
G01X1513433D01*
X1513385Y1352520D01*
G02X1513383Y1352522I137J139D01*
G01X1513358Y1352538D01*
X1512118Y1353346D01*
G03X1511933Y1353341I-88J-180D01*
G01X1510635Y1352490D01*
X1509679D01*
G02X1509476Y1352693I0J203D01*
G01Y1355593D01*
G02X1509679Y1355796I203J0D01*
G01X1510640D01*
X1511943Y1354942D01*
G03X1512127Y1354943I91J178D01*
G37*
G36*
G01X1524367D02*
X1525673Y1355796D01*
X1526629D01*
G02X1526832Y1355593I0J-203D01*
G01Y1352693D01*
G02X1526629Y1352490I-203J0D01*
G01X1525673D01*
X1525625Y1352520D01*
G02X1525623Y1352522I137J139D01*
G01X1525598Y1352538D01*
X1524358Y1353346D01*
G03X1524173Y1353341I-88J-180D01*
G01X1522875Y1352490D01*
X1521919D01*
G02X1521716Y1352693I0J203D01*
G01Y1355593D01*
G02X1521919Y1355796I203J0D01*
G01X1522880D01*
X1524183Y1354942D01*
G03X1524367Y1354943I91J178D01*
G37*
G36*
G01X1536607D02*
X1537913Y1355796D01*
X1538869D01*
G02X1539072Y1355593I0J-203D01*
G01Y1352693D01*
G02X1538869Y1352490I-203J0D01*
G01X1537913D01*
X1537865Y1352520D01*
G02X1537863Y1352522I137J139D01*
G01X1537838Y1352538D01*
X1536598Y1353346D01*
G03X1536413Y1353341I-88J-180D01*
G01X1535115Y1352490D01*
X1534159D01*
G02X1533956Y1352693I0J203D01*
G01Y1355593D01*
G02X1534159Y1355796I203J0D01*
G01X1535120D01*
X1536423Y1354942D01*
G03X1536607Y1354943I91J178D01*
G37*
G36*
G01X1548847D02*
X1550153Y1355796D01*
X1551109D01*
G02X1551312Y1355593I0J-203D01*
G01Y1352693D01*
G02X1551109Y1352490I-203J0D01*
G01X1550153D01*
X1550105Y1352520D01*
G02X1550103Y1352522I137J139D01*
G01X1550078Y1352538D01*
X1548838Y1353346D01*
G03X1548653Y1353341I-88J-180D01*
G01X1547355Y1352490D01*
X1546399D01*
G02X1546196Y1352693I0J203D01*
G01Y1355593D01*
G02X1546399Y1355796I203J0D01*
G01X1547360D01*
X1548663Y1354942D01*
G03X1548847Y1354943I91J178D01*
G37*
G36*
G01X1561087D02*
X1562393Y1355796D01*
X1563349D01*
G02X1563552Y1355593I0J-203D01*
G01Y1352693D01*
G02X1563349Y1352490I-203J0D01*
G01X1562393D01*
X1562345Y1352520D01*
G02X1562343Y1352522I137J139D01*
G01X1562318Y1352538D01*
X1561078Y1353346D01*
G03X1560893Y1353341I-88J-180D01*
G01X1559595Y1352490D01*
X1558639D01*
G02X1558436Y1352693I0J203D01*
G01Y1355593D01*
G02X1558639Y1355796I203J0D01*
G01X1559600D01*
X1560903Y1354942D01*
G03X1561087Y1354943I91J178D01*
G37*
G36*
G01X1573327D02*
X1574633Y1355796D01*
X1575589D01*
G02X1575792Y1355593I0J-203D01*
G01Y1352693D01*
G02X1575589Y1352490I-203J0D01*
G01X1574633D01*
X1574585Y1352520D01*
G02X1574583Y1352522I137J139D01*
G01X1574558Y1352538D01*
X1573318Y1353346D01*
G03X1573133Y1353341I-88J-180D01*
G01X1571835Y1352490D01*
X1570879D01*
G02X1570676Y1352693I0J203D01*
G01Y1355593D01*
G02X1570879Y1355796I203J0D01*
G01X1571840D01*
X1573143Y1354942D01*
G03X1573327Y1354943I91J178D01*
G37*
G36*
G01X1585567D02*
X1586873Y1355796D01*
X1587829D01*
G02X1588032Y1355593I0J-203D01*
G01Y1352693D01*
G02X1587829Y1352490I-203J0D01*
G01X1586873D01*
X1586825Y1352520D01*
G02X1586823Y1352522I137J139D01*
G01X1586798Y1352538D01*
X1585558Y1353346D01*
G03X1585373Y1353341I-88J-180D01*
G01X1584075Y1352490D01*
X1583119D01*
G02X1582916Y1352693I0J203D01*
G01Y1355593D01*
G02X1583119Y1355796I203J0D01*
G01X1584080D01*
X1585383Y1354942D01*
G03X1585567Y1354943I91J178D01*
G37*
G36*
G01X1613195D02*
X1614501Y1355796D01*
X1615457D01*
G02X1615660Y1355593I0J-203D01*
G01Y1352693D01*
G02X1615457Y1352490I-203J0D01*
G01X1614501D01*
X1614453Y1352520D01*
G02X1614451Y1352522I137J139D01*
G01X1614426Y1352538D01*
X1613186Y1353346D01*
G03X1613001Y1353341I-88J-180D01*
G01X1611703Y1352490D01*
X1610747D01*
G02X1610544Y1352693I0J203D01*
G01Y1355593D01*
G02X1610747Y1355796I203J0D01*
G01X1611708D01*
X1613011Y1354942D01*
G03X1613195Y1354943I91J178D01*
G37*
G36*
G01X1625435D02*
X1626741Y1355796D01*
X1627697D01*
G02X1627900Y1355593I0J-203D01*
G01Y1352693D01*
G02X1627697Y1352490I-203J0D01*
G01X1626741D01*
X1626693Y1352520D01*
G02X1626691Y1352522I137J139D01*
G01X1626666Y1352538D01*
X1625426Y1353346D01*
G03X1625241Y1353341I-88J-180D01*
G01X1623943Y1352490D01*
X1622987D01*
G02X1622784Y1352693I0J203D01*
G01Y1355593D01*
G02X1622987Y1355796I203J0D01*
G01X1623948D01*
X1625251Y1354942D01*
G03X1625435Y1354943I91J178D01*
G37*
G36*
G01X1637675D02*
X1638981Y1355796D01*
X1639937D01*
G02X1640140Y1355593I0J-203D01*
G01Y1352693D01*
G02X1639937Y1352490I-203J0D01*
G01X1638981D01*
X1638933Y1352520D01*
G02X1638931Y1352522I137J139D01*
G01X1638906Y1352538D01*
X1637666Y1353346D01*
G03X1637481Y1353341I-88J-180D01*
G01X1636183Y1352490D01*
X1635227D01*
G02X1635024Y1352693I0J203D01*
G01Y1355593D01*
G02X1635227Y1355796I203J0D01*
G01X1636188D01*
X1637491Y1354942D01*
G03X1637675Y1354943I91J178D01*
G37*
G36*
G01X1649915D02*
X1651221Y1355796D01*
X1652177D01*
G02X1652380Y1355593I0J-203D01*
G01Y1352693D01*
G02X1652177Y1352490I-203J0D01*
G01X1651221D01*
X1651173Y1352520D01*
G02X1651171Y1352522I137J139D01*
G01X1651146Y1352538D01*
X1649906Y1353346D01*
G03X1649721Y1353341I-88J-180D01*
G01X1648423Y1352490D01*
X1647467D01*
G02X1647264Y1352693I0J203D01*
G01Y1355593D01*
G02X1647467Y1355796I203J0D01*
G01X1648428D01*
X1649731Y1354942D01*
G03X1649915Y1354943I91J178D01*
G37*
G36*
G01X1662155D02*
X1663461Y1355796D01*
X1664417D01*
G02X1664620Y1355593I0J-203D01*
G01Y1352693D01*
G02X1664417Y1352490I-203J0D01*
G01X1663461D01*
X1663413Y1352520D01*
G02X1663411Y1352522I137J139D01*
G01X1663386Y1352538D01*
X1662146Y1353346D01*
G03X1661961Y1353341I-88J-180D01*
G01X1660663Y1352490D01*
X1659707D01*
G02X1659504Y1352693I0J203D01*
G01Y1355593D01*
G02X1659707Y1355796I203J0D01*
G01X1660668D01*
X1661971Y1354942D01*
G03X1662155Y1354943I91J178D01*
G37*
G36*
G01X1674395D02*
X1675701Y1355796D01*
X1676657D01*
G02X1676860Y1355593I0J-203D01*
G01Y1352693D01*
G02X1676657Y1352490I-203J0D01*
G01X1675701D01*
X1675653Y1352520D01*
G02X1675651Y1352522I137J139D01*
G01X1675626Y1352538D01*
X1674386Y1353346D01*
G03X1674201Y1353341I-88J-180D01*
G01X1672903Y1352490D01*
X1671947D01*
G02X1671744Y1352693I0J203D01*
G01Y1355593D01*
G02X1671947Y1355796I203J0D01*
G01X1672908D01*
X1674211Y1354942D01*
G03X1674395Y1354943I91J178D01*
G37*
G36*
G01X1686635D02*
X1687941Y1355796D01*
X1688897D01*
G02X1689100Y1355593I0J-203D01*
G01Y1352693D01*
G02X1688897Y1352490I-203J0D01*
G01X1687941D01*
X1687893Y1352520D01*
G02X1687891Y1352522I137J139D01*
G01X1687866Y1352538D01*
X1686626Y1353346D01*
G03X1686441Y1353341I-88J-180D01*
G01X1685143Y1352490D01*
X1684187D01*
G02X1683984Y1352693I0J203D01*
G01Y1355593D01*
G02X1684187Y1355796I203J0D01*
G01X1685148D01*
X1686451Y1354942D01*
G03X1686635Y1354943I91J178D01*
G37*
G36*
G01X1698875D02*
X1700181Y1355796D01*
X1701137D01*
G02X1701340Y1355593I0J-203D01*
G01Y1352693D01*
G02X1701137Y1352490I-203J0D01*
G01X1700181D01*
X1700133Y1352520D01*
G02X1700131Y1352522I137J139D01*
G01X1700106Y1352538D01*
X1698866Y1353346D01*
G03X1698681Y1353341I-88J-180D01*
G01X1697383Y1352490D01*
X1696427D01*
G02X1696224Y1352693I0J203D01*
G01Y1355593D01*
G02X1696427Y1355796I203J0D01*
G01X1697388D01*
X1698691Y1354942D01*
G03X1698875Y1354943I91J178D01*
G37*
G36*
G01X1711115D02*
X1712421Y1355796D01*
X1713377D01*
G02X1713580Y1355593I0J-203D01*
G01Y1352693D01*
G02X1713377Y1352490I-203J0D01*
G01X1712421D01*
X1712373Y1352520D01*
G02X1712371Y1352522I137J139D01*
G01X1712346Y1352538D01*
X1711106Y1353346D01*
G03X1710921Y1353341I-88J-180D01*
G01X1709623Y1352490D01*
X1708667D01*
G02X1708464Y1352693I0J203D01*
G01Y1355593D01*
G02X1708667Y1355796I203J0D01*
G01X1709628D01*
X1710931Y1354942D01*
G03X1711115Y1354943I91J178D01*
G37*
G36*
G01X1723355D02*
X1724661Y1355796D01*
X1725617D01*
G02X1725820Y1355593I0J-203D01*
G01Y1352693D01*
G02X1725617Y1352490I-203J0D01*
G01X1724661D01*
X1724613Y1352520D01*
G02X1724611Y1352522I137J139D01*
G01X1724586Y1352538D01*
X1723346Y1353346D01*
G03X1723161Y1353341I-88J-180D01*
G01X1721863Y1352490D01*
X1720907D01*
G02X1720704Y1352693I0J203D01*
G01Y1355593D01*
G02X1720907Y1355796I203J0D01*
G01X1721868D01*
X1723171Y1354942D01*
G03X1723355Y1354943I91J178D01*
G37*
G36*
G01X1735595D02*
X1736901Y1355796D01*
X1737857D01*
G02X1738060Y1355593I0J-203D01*
G01Y1352693D01*
G02X1737857Y1352490I-203J0D01*
G01X1736901D01*
X1736853Y1352520D01*
G02X1736851Y1352522I137J139D01*
G01X1736826Y1352538D01*
X1735586Y1353346D01*
G03X1735401Y1353341I-88J-180D01*
G01X1734103Y1352490D01*
X1733147D01*
G02X1732944Y1352693I0J203D01*
G01Y1355593D01*
G02X1733147Y1355796I203J0D01*
G01X1734108D01*
X1735411Y1354942D01*
G03X1735595Y1354943I91J178D01*
G37*
G36*
G01X77909Y1379141D02*
X79215Y1379994D01*
X80171D01*
G02X80374Y1379791I0J-203D01*
G01Y1376891D01*
G02X80171Y1376688I-203J0D01*
G01X79215D01*
X79167Y1376718D01*
G02X79165Y1376720I137J139D01*
G01X79140Y1376736D01*
X77900Y1377544D01*
G03X77715Y1377539I-88J-180D01*
G01X76417Y1376688D01*
X75461D01*
G02X75258Y1376891I0J203D01*
G01Y1379791D01*
G02X75461Y1379994I203J0D01*
G01X76422D01*
X77725Y1379140D01*
G03X77909Y1379141I91J178D01*
G37*
G36*
G01X90149D02*
X91455Y1379994D01*
X92411D01*
G02X92614Y1379791I0J-203D01*
G01Y1376891D01*
G02X92411Y1376688I-203J0D01*
G01X91455D01*
X91407Y1376718D01*
G02X91405Y1376720I137J139D01*
G01X91380Y1376736D01*
X90140Y1377544D01*
G03X89955Y1377539I-88J-180D01*
G01X88657Y1376688D01*
X87701D01*
G02X87498Y1376891I0J203D01*
G01Y1379791D01*
G02X87701Y1379994I203J0D01*
G01X88662D01*
X89965Y1379140D01*
G03X90149Y1379141I91J178D01*
G37*
G36*
G01X102389D02*
X103695Y1379994D01*
X104651D01*
G02X104854Y1379791I0J-203D01*
G01Y1376891D01*
G02X104651Y1376688I-203J0D01*
G01X103695D01*
X103647Y1376718D01*
G02X103645Y1376720I137J139D01*
G01X103620Y1376736D01*
X102380Y1377544D01*
G03X102195Y1377539I-88J-180D01*
G01X100897Y1376688D01*
X99941D01*
G02X99738Y1376891I0J203D01*
G01Y1379791D01*
G02X99941Y1379994I203J0D01*
G01X100902D01*
X102205Y1379140D01*
G03X102389Y1379141I91J178D01*
G37*
G36*
G01X114629D02*
X115935Y1379994D01*
X116891D01*
G02X117094Y1379791I0J-203D01*
G01Y1376891D01*
G02X116891Y1376688I-203J0D01*
G01X115935D01*
X115887Y1376718D01*
G02X115885Y1376720I137J139D01*
G01X115860Y1376736D01*
X114620Y1377544D01*
G03X114435Y1377539I-88J-180D01*
G01X113137Y1376688D01*
X112181D01*
G02X111978Y1376891I0J203D01*
G01Y1379791D01*
G02X112181Y1379994I203J0D01*
G01X113142D01*
X114445Y1379140D01*
G03X114629Y1379141I91J178D01*
G37*
G36*
G01X126869D02*
X128175Y1379994D01*
X129131D01*
G02X129334Y1379791I0J-203D01*
G01Y1376891D01*
G02X129131Y1376688I-203J0D01*
G01X128175D01*
X128127Y1376718D01*
G02X128125Y1376720I137J139D01*
G01X128100Y1376736D01*
X126860Y1377544D01*
G03X126675Y1377539I-88J-180D01*
G01X125377Y1376688D01*
X124421D01*
G02X124218Y1376891I0J203D01*
G01Y1379791D01*
G02X124421Y1379994I203J0D01*
G01X125382D01*
X126685Y1379140D01*
G03X126869Y1379141I91J178D01*
G37*
G36*
G01X139109D02*
X140415Y1379994D01*
X141371D01*
G02X141574Y1379791I0J-203D01*
G01Y1376891D01*
G02X141371Y1376688I-203J0D01*
G01X140415D01*
X140367Y1376718D01*
G02X140365Y1376720I137J139D01*
G01X140340Y1376736D01*
X139100Y1377544D01*
G03X138915Y1377539I-88J-180D01*
G01X137617Y1376688D01*
X136661D01*
G02X136458Y1376891I0J203D01*
G01Y1379791D01*
G02X136661Y1379994I203J0D01*
G01X137622D01*
X138925Y1379140D01*
G03X139109Y1379141I91J178D01*
G37*
G36*
G01X151349D02*
X152655Y1379994D01*
X153611D01*
G02X153814Y1379791I0J-203D01*
G01Y1376891D01*
G02X153611Y1376688I-203J0D01*
G01X152655D01*
X152607Y1376718D01*
G02X152605Y1376720I137J139D01*
G01X152580Y1376736D01*
X151340Y1377544D01*
G03X151155Y1377539I-88J-180D01*
G01X149857Y1376688D01*
X148901D01*
G02X148698Y1376891I0J203D01*
G01Y1379791D01*
G02X148901Y1379994I203J0D01*
G01X149862D01*
X151165Y1379140D01*
G03X151349Y1379141I91J178D01*
G37*
G36*
G01X163589D02*
X164895Y1379994D01*
X165851D01*
G02X166054Y1379791I0J-203D01*
G01Y1376891D01*
G02X165851Y1376688I-203J0D01*
G01X164895D01*
X164847Y1376718D01*
G02X164845Y1376720I137J139D01*
G01X164820Y1376736D01*
X163580Y1377544D01*
G03X163395Y1377539I-88J-180D01*
G01X162097Y1376688D01*
X161141D01*
G02X160938Y1376891I0J203D01*
G01Y1379791D01*
G02X161141Y1379994I203J0D01*
G01X162102D01*
X163405Y1379140D01*
G03X163589Y1379141I91J178D01*
G37*
G36*
G01X175829D02*
X177135Y1379994D01*
X178091D01*
G02X178294Y1379791I0J-203D01*
G01Y1376891D01*
G02X178091Y1376688I-203J0D01*
G01X177135D01*
X177087Y1376718D01*
G02X177085Y1376720I137J139D01*
G01X177060Y1376736D01*
X175820Y1377544D01*
G03X175635Y1377539I-88J-180D01*
G01X174337Y1376688D01*
X173381D01*
G02X173178Y1376891I0J203D01*
G01Y1379791D01*
G02X173381Y1379994I203J0D01*
G01X174342D01*
X175645Y1379140D01*
G03X175829Y1379141I91J178D01*
G37*
G36*
G01X188069D02*
X189375Y1379994D01*
X190331D01*
G02X190534Y1379791I0J-203D01*
G01Y1376891D01*
G02X190331Y1376688I-203J0D01*
G01X189375D01*
X189327Y1376718D01*
G02X189325Y1376720I137J139D01*
G01X189300Y1376736D01*
X188060Y1377544D01*
G03X187875Y1377539I-88J-180D01*
G01X186577Y1376688D01*
X185621D01*
G02X185418Y1376891I0J203D01*
G01Y1379791D01*
G02X185621Y1379994I203J0D01*
G01X186582D01*
X187885Y1379140D01*
G03X188069Y1379141I91J178D01*
G37*
G36*
G01X200309D02*
X201615Y1379994D01*
X202571D01*
G02X202774Y1379791I0J-203D01*
G01Y1376891D01*
G02X202571Y1376688I-203J0D01*
G01X201615D01*
X201567Y1376718D01*
G02X201565Y1376720I137J139D01*
G01X201540Y1376736D01*
X200300Y1377544D01*
G03X200115Y1377539I-88J-180D01*
G01X198817Y1376688D01*
X197861D01*
G02X197658Y1376891I0J203D01*
G01Y1379791D01*
G02X197861Y1379994I203J0D01*
G01X198822D01*
X200125Y1379140D01*
G03X200309Y1379141I91J178D01*
G37*
G36*
G01X243420D02*
X244726Y1379994D01*
X245682D01*
G02X245886Y1379791I1J-203D01*
G01Y1376891D01*
G02X245682Y1376688I-204J1D01*
G01X244726D01*
X244678Y1376718D01*
G02X244676Y1376720I137J139D01*
G01X244651Y1376736D01*
X243411Y1377544D01*
G03X243226Y1377539I-88J-180D01*
G01X241928Y1376688D01*
X240972D01*
G02X240768Y1376891I-1J203D01*
G01Y1379791D01*
G02X240972Y1379994I204J-1D01*
G01X241933D01*
X243236Y1379140D01*
G03X243420Y1379141I91J178D01*
G37*
G36*
G01X255660D02*
X256966Y1379994D01*
X257922D01*
G02X258126Y1379791I1J-203D01*
G01Y1376891D01*
G02X257922Y1376688I-204J1D01*
G01X256966D01*
X256918Y1376718D01*
G02X256916Y1376720I137J139D01*
G01X256891Y1376736D01*
X255651Y1377544D01*
G03X255466Y1377539I-88J-180D01*
G01X254168Y1376688D01*
X253212D01*
G02X253008Y1376891I-1J203D01*
G01Y1379791D01*
G02X253212Y1379994I204J-1D01*
G01X254173D01*
X255476Y1379140D01*
G03X255660Y1379141I91J178D01*
G37*
G36*
G01X267900D02*
X269206Y1379994D01*
X270162D01*
G02X270366Y1379791I1J-203D01*
G01Y1376891D01*
G02X270162Y1376688I-204J1D01*
G01X269206D01*
X269158Y1376718D01*
G02X269156Y1376720I137J139D01*
G01X269131Y1376736D01*
X267891Y1377544D01*
G03X267706Y1377539I-88J-180D01*
G01X266408Y1376688D01*
X265452D01*
G02X265248Y1376891I-1J203D01*
G01Y1379791D01*
G02X265452Y1379994I204J-1D01*
G01X266413D01*
X267716Y1379140D01*
G03X267900Y1379141I91J178D01*
G37*
G36*
G01X280140D02*
X281446Y1379994D01*
X282402D01*
G02X282606Y1379791I1J-203D01*
G01Y1376891D01*
G02X282402Y1376688I-204J1D01*
G01X281446D01*
X281398Y1376718D01*
G02X281396Y1376720I137J139D01*
G01X281371Y1376736D01*
X280131Y1377544D01*
G03X279946Y1377539I-88J-180D01*
G01X278648Y1376688D01*
X277692D01*
G02X277488Y1376891I-1J203D01*
G01Y1379791D01*
G02X277692Y1379994I204J-1D01*
G01X278653D01*
X279956Y1379140D01*
G03X280140Y1379141I91J178D01*
G37*
G36*
G01X292380D02*
X293686Y1379994D01*
X294642D01*
G02X294846Y1379791I1J-203D01*
G01Y1376891D01*
G02X294642Y1376688I-204J1D01*
G01X293686D01*
X293638Y1376718D01*
G02X293636Y1376720I137J139D01*
G01X293611Y1376736D01*
X292371Y1377544D01*
G03X292186Y1377539I-88J-180D01*
G01X290888Y1376688D01*
X289932D01*
G02X289728Y1376891I-1J203D01*
G01Y1379791D01*
G02X289932Y1379994I204J-1D01*
G01X290893D01*
X292196Y1379140D01*
G03X292380Y1379141I91J178D01*
G37*
G36*
G01X304620D02*
X305926Y1379994D01*
X306882D01*
G02X307086Y1379791I1J-203D01*
G01Y1376891D01*
G02X306882Y1376688I-204J1D01*
G01X305926D01*
X305878Y1376718D01*
G02X305876Y1376720I137J139D01*
G01X305851Y1376736D01*
X304611Y1377544D01*
G03X304426Y1377539I-88J-180D01*
G01X303128Y1376688D01*
X302172D01*
G02X301968Y1376891I-1J203D01*
G01Y1379791D01*
G02X302172Y1379994I204J-1D01*
G01X303133D01*
X304436Y1379140D01*
G03X304620Y1379141I91J178D01*
G37*
G36*
G01X316860D02*
X318166Y1379994D01*
X319122D01*
G02X319326Y1379791I1J-203D01*
G01Y1376891D01*
G02X319122Y1376688I-204J1D01*
G01X318166D01*
X318118Y1376718D01*
G02X318116Y1376720I137J139D01*
G01X318091Y1376736D01*
X316851Y1377544D01*
G03X316666Y1377539I-88J-180D01*
G01X315368Y1376688D01*
X314412D01*
G02X314208Y1376891I-1J203D01*
G01Y1379791D01*
G02X314412Y1379994I204J-1D01*
G01X315373D01*
X316676Y1379140D01*
G03X316860Y1379141I91J178D01*
G37*
G36*
G01X329100D02*
X330406Y1379994D01*
X331362D01*
G02X331566Y1379791I1J-203D01*
G01Y1376891D01*
G02X331362Y1376688I-204J1D01*
G01X330406D01*
X330358Y1376718D01*
G02X330356Y1376720I137J139D01*
G01X330331Y1376736D01*
X329091Y1377544D01*
G03X328906Y1377539I-88J-180D01*
G01X327608Y1376688D01*
X326652D01*
G02X326448Y1376891I-1J203D01*
G01Y1379791D01*
G02X326652Y1379994I204J-1D01*
G01X327613D01*
X328916Y1379140D01*
G03X329100Y1379141I91J178D01*
G37*
G36*
G01X341340D02*
X342646Y1379994D01*
X343602D01*
G02X343806Y1379791I1J-203D01*
G01Y1376891D01*
G02X343602Y1376688I-204J1D01*
G01X342646D01*
X342598Y1376718D01*
G02X342596Y1376720I137J139D01*
G01X342571Y1376736D01*
X341331Y1377544D01*
G03X341146Y1377539I-88J-180D01*
G01X339848Y1376688D01*
X338892D01*
G02X338688Y1376891I-1J203D01*
G01Y1379791D01*
G02X338892Y1379994I204J-1D01*
G01X339853D01*
X341156Y1379140D01*
G03X341340Y1379141I91J178D01*
G37*
G36*
G01X353580D02*
X354886Y1379994D01*
X355842D01*
G02X356046Y1379791I1J-203D01*
G01Y1376891D01*
G02X355842Y1376688I-204J1D01*
G01X354886D01*
X354838Y1376718D01*
G02X354836Y1376720I137J139D01*
G01X354811Y1376736D01*
X353571Y1377544D01*
G03X353386Y1377539I-88J-180D01*
G01X352088Y1376688D01*
X351132D01*
G02X350928Y1376891I-1J203D01*
G01Y1379791D01*
G02X351132Y1379994I204J-1D01*
G01X352093D01*
X353396Y1379140D01*
G03X353580Y1379141I91J178D01*
G37*
G36*
G01X365820D02*
X367126Y1379994D01*
X368082D01*
G02X368286Y1379791I1J-203D01*
G01Y1376891D01*
G02X368082Y1376688I-204J1D01*
G01X367126D01*
X367078Y1376718D01*
G02X367076Y1376720I137J139D01*
G01X367051Y1376736D01*
X365811Y1377544D01*
G03X365626Y1377539I-88J-180D01*
G01X364328Y1376688D01*
X363372D01*
G02X363168Y1376891I-1J203D01*
G01Y1379791D01*
G02X363372Y1379994I204J-1D01*
G01X364333D01*
X365636Y1379140D01*
G03X365820Y1379141I91J178D01*
G37*
G36*
G01X442199D02*
X443505Y1379994D01*
X444461D01*
G02X444664Y1379791I0J-203D01*
G01Y1376891D01*
G02X444461Y1376688I-203J0D01*
G01X443505D01*
X443457Y1376718D01*
G02X443455Y1376720I137J139D01*
G01X443430Y1376736D01*
X442190Y1377544D01*
G03X442005Y1377539I-88J-180D01*
G01X440707Y1376688D01*
X439751D01*
G02X439548Y1376891I0J203D01*
G01Y1379791D01*
G02X439751Y1379994I203J0D01*
G01X440712D01*
X442015Y1379140D01*
G03X442199Y1379141I91J178D01*
G37*
G36*
G01X454439D02*
X455745Y1379994D01*
X456701D01*
G02X456904Y1379791I0J-203D01*
G01Y1376891D01*
G02X456701Y1376688I-203J0D01*
G01X455745D01*
X455697Y1376718D01*
G02X455695Y1376720I137J139D01*
G01X455670Y1376736D01*
X454430Y1377544D01*
G03X454245Y1377539I-88J-180D01*
G01X452947Y1376688D01*
X451991D01*
G02X451788Y1376891I0J203D01*
G01Y1379791D01*
G02X451991Y1379994I203J0D01*
G01X452952D01*
X454255Y1379140D01*
G03X454439Y1379141I91J178D01*
G37*
G36*
G01X466679D02*
X467985Y1379994D01*
X468941D01*
G02X469144Y1379791I0J-203D01*
G01Y1376891D01*
G02X468941Y1376688I-203J0D01*
G01X467985D01*
X467937Y1376718D01*
G02X467935Y1376720I137J139D01*
G01X467910Y1376736D01*
X466670Y1377544D01*
G03X466485Y1377539I-88J-180D01*
G01X465187Y1376688D01*
X464231D01*
G02X464028Y1376891I0J203D01*
G01Y1379791D01*
G02X464231Y1379994I203J0D01*
G01X465192D01*
X466495Y1379140D01*
G03X466679Y1379141I91J178D01*
G37*
G36*
G01X478919D02*
X480225Y1379994D01*
X481181D01*
G02X481384Y1379791I0J-203D01*
G01Y1376891D01*
G02X481181Y1376688I-203J0D01*
G01X480225D01*
X480177Y1376718D01*
G02X480175Y1376720I137J139D01*
G01X480150Y1376736D01*
X478910Y1377544D01*
G03X478725Y1377539I-88J-180D01*
G01X477427Y1376688D01*
X476471D01*
G02X476268Y1376891I0J203D01*
G01Y1379791D01*
G02X476471Y1379994I203J0D01*
G01X477432D01*
X478735Y1379140D01*
G03X478919Y1379141I91J178D01*
G37*
G36*
G01X491159D02*
X492465Y1379994D01*
X493421D01*
G02X493624Y1379791I0J-203D01*
G01Y1376891D01*
G02X493421Y1376688I-203J0D01*
G01X492465D01*
X492417Y1376718D01*
G02X492415Y1376720I137J139D01*
G01X492390Y1376736D01*
X491150Y1377544D01*
G03X490965Y1377539I-88J-180D01*
G01X489667Y1376688D01*
X488711D01*
G02X488508Y1376891I0J203D01*
G01Y1379791D01*
G02X488711Y1379994I203J0D01*
G01X489672D01*
X490975Y1379140D01*
G03X491159Y1379141I91J178D01*
G37*
G36*
G01X503399D02*
X504705Y1379994D01*
X505661D01*
G02X505864Y1379791I0J-203D01*
G01Y1376891D01*
G02X505661Y1376688I-203J0D01*
G01X504705D01*
X504657Y1376718D01*
G02X504655Y1376720I137J139D01*
G01X504630Y1376736D01*
X503390Y1377544D01*
G03X503205Y1377539I-88J-180D01*
G01X501907Y1376688D01*
X500951D01*
G02X500748Y1376891I0J203D01*
G01Y1379791D01*
G02X500951Y1379994I203J0D01*
G01X501912D01*
X503215Y1379140D01*
G03X503399Y1379141I91J178D01*
G37*
G36*
G01X515639D02*
X516945Y1379994D01*
X517901D01*
G02X518104Y1379791I0J-203D01*
G01Y1376891D01*
G02X517901Y1376688I-203J0D01*
G01X516945D01*
X516897Y1376718D01*
G02X516895Y1376720I137J139D01*
G01X516870Y1376736D01*
X515630Y1377544D01*
G03X515445Y1377539I-88J-180D01*
G01X514147Y1376688D01*
X513191D01*
G02X512988Y1376891I0J203D01*
G01Y1379791D01*
G02X513191Y1379994I203J0D01*
G01X514152D01*
X515455Y1379140D01*
G03X515639Y1379141I91J178D01*
G37*
G36*
G01X527879D02*
X529185Y1379994D01*
X530141D01*
G02X530344Y1379791I0J-203D01*
G01Y1376891D01*
G02X530141Y1376688I-203J0D01*
G01X529185D01*
X529137Y1376718D01*
G02X529135Y1376720I137J139D01*
G01X529110Y1376736D01*
X527870Y1377544D01*
G03X527685Y1377539I-88J-180D01*
G01X526387Y1376688D01*
X525431D01*
G02X525228Y1376891I0J203D01*
G01Y1379791D01*
G02X525431Y1379994I203J0D01*
G01X526392D01*
X527695Y1379140D01*
G03X527879Y1379141I91J178D01*
G37*
G36*
G01X540119D02*
X541425Y1379994D01*
X542381D01*
G02X542584Y1379791I0J-203D01*
G01Y1376891D01*
G02X542381Y1376688I-203J0D01*
G01X541425D01*
X541377Y1376718D01*
G02X541375Y1376720I137J139D01*
G01X541350Y1376736D01*
X540110Y1377544D01*
G03X539925Y1377539I-88J-180D01*
G01X538627Y1376688D01*
X537671D01*
G02X537468Y1376891I0J203D01*
G01Y1379791D01*
G02X537671Y1379994I203J0D01*
G01X538632D01*
X539935Y1379140D01*
G03X540119Y1379141I91J178D01*
G37*
G36*
G01X552359D02*
X553665Y1379994D01*
X554621D01*
G02X554824Y1379791I0J-203D01*
G01Y1376891D01*
G02X554621Y1376688I-203J0D01*
G01X553665D01*
X553617Y1376718D01*
G02X553615Y1376720I137J139D01*
G01X553590Y1376736D01*
X552350Y1377544D01*
G03X552165Y1377539I-88J-180D01*
G01X550867Y1376688D01*
X549911D01*
G02X549708Y1376891I0J203D01*
G01Y1379791D01*
G02X549911Y1379994I203J0D01*
G01X550872D01*
X552175Y1379140D01*
G03X552359Y1379141I91J178D01*
G37*
G36*
G01X564599D02*
X565905Y1379994D01*
X566861D01*
G02X567064Y1379791I0J-203D01*
G01Y1376891D01*
G02X566861Y1376688I-203J0D01*
G01X565905D01*
X565857Y1376718D01*
G02X565855Y1376720I137J139D01*
G01X565830Y1376736D01*
X564590Y1377544D01*
G03X564405Y1377539I-88J-180D01*
G01X563107Y1376688D01*
X562151D01*
G02X561948Y1376891I0J203D01*
G01Y1379791D01*
G02X562151Y1379994I203J0D01*
G01X563112D01*
X564415Y1379140D01*
G03X564599Y1379141I91J178D01*
G37*
G36*
G01X640325D02*
X641631Y1379994D01*
X642587D01*
G02X642790Y1379791I0J-203D01*
G01Y1376891D01*
G02X642587Y1376688I-203J0D01*
G01X641631D01*
X641583Y1376718D01*
G02X641581Y1376720I137J139D01*
G01X641556Y1376736D01*
X640316Y1377544D01*
G03X640131Y1377539I-88J-180D01*
G01X638833Y1376688D01*
X637877D01*
G02X637674Y1376891I0J203D01*
G01Y1379791D01*
G02X637877Y1379994I203J0D01*
G01X638838D01*
X640141Y1379140D01*
G03X640325Y1379141I91J178D01*
G37*
G36*
G01X652565D02*
X653871Y1379994D01*
X654827D01*
G02X655030Y1379791I0J-203D01*
G01Y1376891D01*
G02X654827Y1376688I-203J0D01*
G01X653871D01*
X653823Y1376718D01*
G02X653821Y1376720I137J139D01*
G01X653796Y1376736D01*
X652556Y1377544D01*
G03X652371Y1377539I-88J-180D01*
G01X651073Y1376688D01*
X650117D01*
G02X649914Y1376891I0J203D01*
G01Y1379791D01*
G02X650117Y1379994I203J0D01*
G01X651078D01*
X652381Y1379140D01*
G03X652565Y1379141I91J178D01*
G37*
G36*
G01X664805D02*
X666111Y1379994D01*
X667067D01*
G02X667270Y1379791I0J-203D01*
G01Y1376891D01*
G02X667067Y1376688I-203J0D01*
G01X666111D01*
X666063Y1376718D01*
G02X666061Y1376720I137J139D01*
G01X666036Y1376736D01*
X664796Y1377544D01*
G03X664611Y1377539I-88J-180D01*
G01X663313Y1376688D01*
X662357D01*
G02X662154Y1376891I0J203D01*
G01Y1379791D01*
G02X662357Y1379994I203J0D01*
G01X663318D01*
X664621Y1379140D01*
G03X664805Y1379141I91J178D01*
G37*
G36*
G01X677045D02*
X678351Y1379994D01*
X679307D01*
G02X679510Y1379791I0J-203D01*
G01Y1376891D01*
G02X679307Y1376688I-203J0D01*
G01X678351D01*
X678303Y1376718D01*
G02X678301Y1376720I137J139D01*
G01X678276Y1376736D01*
X677036Y1377544D01*
G03X676851Y1377539I-88J-180D01*
G01X675553Y1376688D01*
X674597D01*
G02X674394Y1376891I0J203D01*
G01Y1379791D01*
G02X674597Y1379994I203J0D01*
G01X675558D01*
X676861Y1379140D01*
G03X677045Y1379141I91J178D01*
G37*
G36*
G01X689285D02*
X690591Y1379994D01*
X691547D01*
G02X691750Y1379791I0J-203D01*
G01Y1376891D01*
G02X691547Y1376688I-203J0D01*
G01X690591D01*
X690543Y1376718D01*
G02X690541Y1376720I137J139D01*
G01X690516Y1376736D01*
X689276Y1377544D01*
G03X689091Y1377539I-88J-180D01*
G01X687793Y1376688D01*
X686837D01*
G02X686634Y1376891I0J203D01*
G01Y1379791D01*
G02X686837Y1379994I203J0D01*
G01X687798D01*
X689101Y1379140D01*
G03X689285Y1379141I91J178D01*
G37*
G36*
G01X701525D02*
X702831Y1379994D01*
X703787D01*
G02X703990Y1379791I0J-203D01*
G01Y1376891D01*
G02X703787Y1376688I-203J0D01*
G01X702831D01*
X702783Y1376718D01*
G02X702781Y1376720I137J139D01*
G01X702756Y1376736D01*
X701516Y1377544D01*
G03X701331Y1377539I-88J-180D01*
G01X700033Y1376688D01*
X699077D01*
G02X698874Y1376891I0J203D01*
G01Y1379791D01*
G02X699077Y1379994I203J0D01*
G01X700038D01*
X701341Y1379140D01*
G03X701525Y1379141I91J178D01*
G37*
G36*
G01X713765D02*
X715071Y1379994D01*
X716027D01*
G02X716230Y1379791I0J-203D01*
G01Y1376891D01*
G02X716027Y1376688I-203J0D01*
G01X715071D01*
X715023Y1376718D01*
G02X715021Y1376720I137J139D01*
G01X714996Y1376736D01*
X713756Y1377544D01*
G03X713571Y1377539I-88J-180D01*
G01X712273Y1376688D01*
X711317D01*
G02X711114Y1376891I0J203D01*
G01Y1379791D01*
G02X711317Y1379994I203J0D01*
G01X712278D01*
X713581Y1379140D01*
G03X713765Y1379141I91J178D01*
G37*
G36*
G01X726005D02*
X727311Y1379994D01*
X728267D01*
G02X728470Y1379791I0J-203D01*
G01Y1376891D01*
G02X728267Y1376688I-203J0D01*
G01X727311D01*
X727263Y1376718D01*
G02X727261Y1376720I137J139D01*
G01X727236Y1376736D01*
X725996Y1377544D01*
G03X725811Y1377539I-88J-180D01*
G01X724513Y1376688D01*
X723557D01*
G02X723354Y1376891I0J203D01*
G01Y1379791D01*
G02X723557Y1379994I203J0D01*
G01X724518D01*
X725821Y1379140D01*
G03X726005Y1379141I91J178D01*
G37*
G36*
G01X738245D02*
X739551Y1379994D01*
X740507D01*
G02X740710Y1379791I0J-203D01*
G01Y1376891D01*
G02X740507Y1376688I-203J0D01*
G01X739551D01*
X739503Y1376718D01*
G02X739501Y1376720I137J139D01*
G01X739476Y1376736D01*
X738236Y1377544D01*
G03X738051Y1377539I-88J-180D01*
G01X736753Y1376688D01*
X735797D01*
G02X735594Y1376891I0J203D01*
G01Y1379791D01*
G02X735797Y1379994I203J0D01*
G01X736758D01*
X738061Y1379140D01*
G03X738245Y1379141I91J178D01*
G37*
G36*
G01X750485D02*
X751791Y1379994D01*
X752747D01*
G02X752950Y1379791I0J-203D01*
G01Y1376891D01*
G02X752747Y1376688I-203J0D01*
G01X751791D01*
X751743Y1376718D01*
G02X751741Y1376720I137J139D01*
G01X751716Y1376736D01*
X750476Y1377544D01*
G03X750291Y1377539I-88J-180D01*
G01X748993Y1376688D01*
X748037D01*
G02X747834Y1376891I0J203D01*
G01Y1379791D01*
G02X748037Y1379994I203J0D01*
G01X748998D01*
X750301Y1379140D01*
G03X750485Y1379141I91J178D01*
G37*
G36*
G01X762725D02*
X764031Y1379994D01*
X764987D01*
G02X765190Y1379791I0J-203D01*
G01Y1376891D01*
G02X764987Y1376688I-203J0D01*
G01X764031D01*
X763983Y1376718D01*
G02X763981Y1376720I137J139D01*
G01X763956Y1376736D01*
X762716Y1377544D01*
G03X762531Y1377539I-88J-180D01*
G01X761233Y1376688D01*
X760277D01*
G02X760074Y1376891I0J203D01*
G01Y1379791D01*
G02X760277Y1379994I203J0D01*
G01X761238D01*
X762541Y1379140D01*
G03X762725Y1379141I91J178D01*
G37*
G36*
G01X1056510D02*
X1057816Y1379994D01*
X1058772D01*
G02X1058976Y1379791I1J-203D01*
G01Y1376891D01*
G02X1058772Y1376688I-204J1D01*
G01X1057816D01*
X1057768Y1376718D01*
G02X1057766Y1376720I137J139D01*
G01X1057741Y1376736D01*
X1056501Y1377544D01*
G03X1056316Y1377539I-88J-180D01*
G01X1055018Y1376688D01*
X1054062D01*
G02X1053858Y1376891I-1J203D01*
G01Y1379791D01*
G02X1054062Y1379994I204J-1D01*
G01X1055023D01*
X1056326Y1379140D01*
G03X1056510Y1379141I91J178D01*
G37*
G36*
G01X1068750D02*
X1070056Y1379994D01*
X1071012D01*
G02X1071216Y1379791I1J-203D01*
G01Y1376891D01*
G02X1071012Y1376688I-204J1D01*
G01X1070056D01*
X1070008Y1376718D01*
G02X1070006Y1376720I137J139D01*
G01X1069981Y1376736D01*
X1068741Y1377544D01*
G03X1068556Y1377539I-88J-180D01*
G01X1067258Y1376688D01*
X1066302D01*
G02X1066098Y1376891I-1J203D01*
G01Y1379791D01*
G02X1066302Y1379994I204J-1D01*
G01X1067263D01*
X1068566Y1379140D01*
G03X1068750Y1379141I91J178D01*
G37*
G36*
G01X1080990D02*
X1082296Y1379994D01*
X1083252D01*
G02X1083456Y1379791I1J-203D01*
G01Y1376891D01*
G02X1083252Y1376688I-204J1D01*
G01X1082296D01*
X1082248Y1376718D01*
G02X1082246Y1376720I137J139D01*
G01X1082221Y1376736D01*
X1080981Y1377544D01*
G03X1080796Y1377539I-88J-180D01*
G01X1079498Y1376688D01*
X1078542D01*
G02X1078338Y1376891I-1J203D01*
G01Y1379791D01*
G02X1078542Y1379994I204J-1D01*
G01X1079503D01*
X1080806Y1379140D01*
G03X1080990Y1379141I91J178D01*
G37*
G36*
G01X1093230D02*
X1094536Y1379994D01*
X1095492D01*
G02X1095696Y1379791I1J-203D01*
G01Y1376891D01*
G02X1095492Y1376688I-204J1D01*
G01X1094536D01*
X1094488Y1376718D01*
G02X1094486Y1376720I137J139D01*
G01X1094461Y1376736D01*
X1093221Y1377544D01*
G03X1093036Y1377539I-88J-180D01*
G01X1091738Y1376688D01*
X1090782D01*
G02X1090578Y1376891I-1J203D01*
G01Y1379791D01*
G02X1090782Y1379994I204J-1D01*
G01X1091743D01*
X1093046Y1379140D01*
G03X1093230Y1379141I91J178D01*
G37*
G36*
G01X1105470D02*
X1106776Y1379994D01*
X1107732D01*
G02X1107936Y1379791I1J-203D01*
G01Y1376891D01*
G02X1107732Y1376688I-204J1D01*
G01X1106776D01*
X1106728Y1376718D01*
G02X1106726Y1376720I137J139D01*
G01X1106701Y1376736D01*
X1105461Y1377544D01*
G03X1105276Y1377539I-88J-180D01*
G01X1103978Y1376688D01*
X1103022D01*
G02X1102818Y1376891I-1J203D01*
G01Y1379791D01*
G02X1103022Y1379994I204J-1D01*
G01X1103983D01*
X1105286Y1379140D01*
G03X1105470Y1379141I91J178D01*
G37*
G36*
G01X1117710D02*
X1119016Y1379994D01*
X1119972D01*
G02X1120176Y1379791I1J-203D01*
G01Y1376891D01*
G02X1119972Y1376688I-204J1D01*
G01X1119016D01*
X1118968Y1376718D01*
G02X1118966Y1376720I137J139D01*
G01X1118941Y1376736D01*
X1117701Y1377544D01*
G03X1117516Y1377539I-88J-180D01*
G01X1116218Y1376688D01*
X1115262D01*
G02X1115058Y1376891I-1J203D01*
G01Y1379791D01*
G02X1115262Y1379994I204J-1D01*
G01X1116223D01*
X1117526Y1379140D01*
G03X1117710Y1379141I91J178D01*
G37*
G36*
G01X1129950D02*
X1131256Y1379994D01*
X1132212D01*
G02X1132416Y1379791I1J-203D01*
G01Y1376891D01*
G02X1132212Y1376688I-204J1D01*
G01X1131256D01*
X1131208Y1376718D01*
G02X1131206Y1376720I137J139D01*
G01X1131181Y1376736D01*
X1129941Y1377544D01*
G03X1129756Y1377539I-88J-180D01*
G01X1128458Y1376688D01*
X1127502D01*
G02X1127298Y1376891I-1J203D01*
G01Y1379791D01*
G02X1127502Y1379994I204J-1D01*
G01X1128463D01*
X1129766Y1379140D01*
G03X1129950Y1379141I91J178D01*
G37*
G36*
G01X1142190D02*
X1143496Y1379994D01*
X1144452D01*
G02X1144656Y1379791I1J-203D01*
G01Y1376891D01*
G02X1144452Y1376688I-204J1D01*
G01X1143496D01*
X1143448Y1376718D01*
G02X1143446Y1376720I137J139D01*
G01X1143421Y1376736D01*
X1142181Y1377544D01*
G03X1141996Y1377539I-88J-180D01*
G01X1140698Y1376688D01*
X1139742D01*
G02X1139538Y1376891I-1J203D01*
G01Y1379791D01*
G02X1139742Y1379994I204J-1D01*
G01X1140703D01*
X1142006Y1379140D01*
G03X1142190Y1379141I91J178D01*
G37*
G36*
G01X1154430D02*
X1155736Y1379994D01*
X1156692D01*
G02X1156896Y1379791I1J-203D01*
G01Y1376891D01*
G02X1156692Y1376688I-204J1D01*
G01X1155736D01*
X1155688Y1376718D01*
G02X1155686Y1376720I137J139D01*
G01X1155661Y1376736D01*
X1154421Y1377544D01*
G03X1154236Y1377539I-88J-180D01*
G01X1152938Y1376688D01*
X1151982D01*
G02X1151778Y1376891I-1J203D01*
G01Y1379791D01*
G02X1151982Y1379994I204J-1D01*
G01X1152943D01*
X1154246Y1379140D01*
G03X1154430Y1379141I91J178D01*
G37*
G36*
G01X1166670D02*
X1167976Y1379994D01*
X1168932D01*
G02X1169136Y1379791I1J-203D01*
G01Y1376891D01*
G02X1168932Y1376688I-204J1D01*
G01X1167976D01*
X1167928Y1376718D01*
G02X1167926Y1376720I137J139D01*
G01X1167901Y1376736D01*
X1166661Y1377544D01*
G03X1166476Y1377539I-88J-180D01*
G01X1165178Y1376688D01*
X1164222D01*
G02X1164018Y1376891I-1J203D01*
G01Y1379791D01*
G02X1164222Y1379994I204J-1D01*
G01X1165183D01*
X1166486Y1379140D01*
G03X1166670Y1379141I91J178D01*
G37*
G36*
G01X1178910D02*
X1180216Y1379994D01*
X1181172D01*
G02X1181376Y1379791I1J-203D01*
G01Y1376891D01*
G02X1181172Y1376688I-204J1D01*
G01X1180216D01*
X1180168Y1376718D01*
G02X1180166Y1376720I137J139D01*
G01X1180141Y1376736D01*
X1178901Y1377544D01*
G03X1178716Y1377539I-88J-180D01*
G01X1177418Y1376688D01*
X1176462D01*
G02X1176258Y1376891I-1J203D01*
G01Y1379791D01*
G02X1176462Y1379994I204J-1D01*
G01X1177423D01*
X1178726Y1379140D01*
G03X1178910Y1379141I91J178D01*
G37*
G36*
G01X1232123D02*
X1233429Y1379994D01*
X1234385D01*
G02X1234588Y1379791I0J-203D01*
G01Y1376891D01*
G02X1234385Y1376688I-203J0D01*
G01X1233429D01*
X1233381Y1376718D01*
G02X1233379Y1376720I137J139D01*
G01X1233354Y1376736D01*
X1232114Y1377544D01*
G03X1231929Y1377539I-88J-180D01*
G01X1230631Y1376688D01*
X1229675D01*
G02X1229472Y1376891I0J203D01*
G01Y1379791D01*
G02X1229675Y1379994I203J0D01*
G01X1230636D01*
X1231939Y1379140D01*
G03X1232123Y1379141I91J178D01*
G37*
G36*
G01X1244363D02*
X1245669Y1379994D01*
X1246625D01*
G02X1246828Y1379791I0J-203D01*
G01Y1376891D01*
G02X1246625Y1376688I-203J0D01*
G01X1245669D01*
X1245621Y1376718D01*
G02X1245619Y1376720I137J139D01*
G01X1245594Y1376736D01*
X1244354Y1377544D01*
G03X1244169Y1377539I-88J-180D01*
G01X1242871Y1376688D01*
X1241915D01*
G02X1241712Y1376891I0J203D01*
G01Y1379791D01*
G02X1241915Y1379994I203J0D01*
G01X1242876D01*
X1244179Y1379140D01*
G03X1244363Y1379141I91J178D01*
G37*
G36*
G01X1256603D02*
X1257909Y1379994D01*
X1258865D01*
G02X1259068Y1379791I0J-203D01*
G01Y1376891D01*
G02X1258865Y1376688I-203J0D01*
G01X1257909D01*
X1257861Y1376718D01*
G02X1257859Y1376720I137J139D01*
G01X1257834Y1376736D01*
X1256594Y1377544D01*
G03X1256409Y1377539I-88J-180D01*
G01X1255111Y1376688D01*
X1254155D01*
G02X1253952Y1376891I0J203D01*
G01Y1379791D01*
G02X1254155Y1379994I203J0D01*
G01X1255116D01*
X1256419Y1379140D01*
G03X1256603Y1379141I91J178D01*
G37*
G36*
G01X1268843D02*
X1270149Y1379994D01*
X1271105D01*
G02X1271308Y1379791I0J-203D01*
G01Y1376891D01*
G02X1271105Y1376688I-203J0D01*
G01X1270149D01*
X1270101Y1376718D01*
G02X1270099Y1376720I137J139D01*
G01X1270074Y1376736D01*
X1268834Y1377544D01*
G03X1268649Y1377539I-88J-180D01*
G01X1267351Y1376688D01*
X1266395D01*
G02X1266192Y1376891I0J203D01*
G01Y1379791D01*
G02X1266395Y1379994I203J0D01*
G01X1267356D01*
X1268659Y1379140D01*
G03X1268843Y1379141I91J178D01*
G37*
G36*
G01X1281083D02*
X1282389Y1379994D01*
X1283345D01*
G02X1283548Y1379791I0J-203D01*
G01Y1376891D01*
G02X1283345Y1376688I-203J0D01*
G01X1282389D01*
X1282341Y1376718D01*
G02X1282339Y1376720I137J139D01*
G01X1282314Y1376736D01*
X1281074Y1377544D01*
G03X1280889Y1377539I-88J-180D01*
G01X1279591Y1376688D01*
X1278635D01*
G02X1278432Y1376891I0J203D01*
G01Y1379791D01*
G02X1278635Y1379994I203J0D01*
G01X1279596D01*
X1280899Y1379140D01*
G03X1281083Y1379141I91J178D01*
G37*
G36*
G01X1293323D02*
X1294629Y1379994D01*
X1295585D01*
G02X1295788Y1379791I0J-203D01*
G01Y1376891D01*
G02X1295585Y1376688I-203J0D01*
G01X1294629D01*
X1294581Y1376718D01*
G02X1294579Y1376720I137J139D01*
G01X1294554Y1376736D01*
X1293314Y1377544D01*
G03X1293129Y1377539I-88J-180D01*
G01X1291831Y1376688D01*
X1290875D01*
G02X1290672Y1376891I0J203D01*
G01Y1379791D01*
G02X1290875Y1379994I203J0D01*
G01X1291836D01*
X1293139Y1379140D01*
G03X1293323Y1379141I91J178D01*
G37*
G36*
G01X1305563D02*
X1306869Y1379994D01*
X1307825D01*
G02X1308028Y1379791I0J-203D01*
G01Y1376891D01*
G02X1307825Y1376688I-203J0D01*
G01X1306869D01*
X1306821Y1376718D01*
G02X1306819Y1376720I137J139D01*
G01X1306794Y1376736D01*
X1305554Y1377544D01*
G03X1305369Y1377539I-88J-180D01*
G01X1304071Y1376688D01*
X1303115D01*
G02X1302912Y1376891I0J203D01*
G01Y1379791D01*
G02X1303115Y1379994I203J0D01*
G01X1304076D01*
X1305379Y1379140D01*
G03X1305563Y1379141I91J178D01*
G37*
G36*
G01X1317803D02*
X1319109Y1379994D01*
X1320065D01*
G02X1320268Y1379791I0J-203D01*
G01Y1376891D01*
G02X1320065Y1376688I-203J0D01*
G01X1319109D01*
X1319061Y1376718D01*
G02X1319059Y1376720I137J139D01*
G01X1319034Y1376736D01*
X1317794Y1377544D01*
G03X1317609Y1377539I-88J-180D01*
G01X1316311Y1376688D01*
X1315355D01*
G02X1315152Y1376891I0J203D01*
G01Y1379791D01*
G02X1315355Y1379994I203J0D01*
G01X1316316D01*
X1317619Y1379140D01*
G03X1317803Y1379141I91J178D01*
G37*
G36*
G01X1330043D02*
X1331349Y1379994D01*
X1332305D01*
G02X1332508Y1379791I0J-203D01*
G01Y1376891D01*
G02X1332305Y1376688I-203J0D01*
G01X1331349D01*
X1331301Y1376718D01*
G02X1331299Y1376720I137J139D01*
G01X1331274Y1376736D01*
X1330034Y1377544D01*
G03X1329849Y1377539I-88J-180D01*
G01X1328551Y1376688D01*
X1327595D01*
G02X1327392Y1376891I0J203D01*
G01Y1379791D01*
G02X1327595Y1379994I203J0D01*
G01X1328556D01*
X1329859Y1379140D01*
G03X1330043Y1379141I91J178D01*
G37*
G36*
G01X1342283D02*
X1343589Y1379994D01*
X1344545D01*
G02X1344748Y1379791I0J-203D01*
G01Y1376891D01*
G02X1344545Y1376688I-203J0D01*
G01X1343589D01*
X1343541Y1376718D01*
G02X1343539Y1376720I137J139D01*
G01X1343514Y1376736D01*
X1342274Y1377544D01*
G03X1342089Y1377539I-88J-180D01*
G01X1340791Y1376688D01*
X1339835D01*
G02X1339632Y1376891I0J203D01*
G01Y1379791D01*
G02X1339835Y1379994I203J0D01*
G01X1340796D01*
X1342099Y1379140D01*
G03X1342283Y1379141I91J178D01*
G37*
G36*
G01X1354523D02*
X1355829Y1379994D01*
X1356785D01*
G02X1356988Y1379791I0J-203D01*
G01Y1376891D01*
G02X1356785Y1376688I-203J0D01*
G01X1355829D01*
X1355781Y1376718D01*
G02X1355779Y1376720I137J139D01*
G01X1355754Y1376736D01*
X1354514Y1377544D01*
G03X1354329Y1377539I-88J-180D01*
G01X1353031Y1376688D01*
X1352075D01*
G02X1351872Y1376891I0J203D01*
G01Y1379791D01*
G02X1352075Y1379994I203J0D01*
G01X1353036D01*
X1354339Y1379140D01*
G03X1354523Y1379141I91J178D01*
G37*
G36*
G01X1463167D02*
X1464473Y1379994D01*
X1465429D01*
G02X1465632Y1379791I0J-203D01*
G01Y1376891D01*
G02X1465429Y1376688I-203J0D01*
G01X1464473D01*
X1464425Y1376718D01*
G02X1464423Y1376720I137J139D01*
G01X1464398Y1376736D01*
X1463158Y1377544D01*
G03X1462973Y1377539I-88J-180D01*
G01X1461675Y1376688D01*
X1460719D01*
G02X1460516Y1376891I0J203D01*
G01Y1379791D01*
G02X1460719Y1379994I203J0D01*
G01X1461680D01*
X1462983Y1379140D01*
G03X1463167Y1379141I91J178D01*
G37*
G36*
G01X1475407D02*
X1476713Y1379994D01*
X1477669D01*
G02X1477872Y1379791I0J-203D01*
G01Y1376891D01*
G02X1477669Y1376688I-203J0D01*
G01X1476713D01*
X1476665Y1376718D01*
G02X1476663Y1376720I137J139D01*
G01X1476638Y1376736D01*
X1475398Y1377544D01*
G03X1475213Y1377539I-88J-180D01*
G01X1473915Y1376688D01*
X1472959D01*
G02X1472756Y1376891I0J203D01*
G01Y1379791D01*
G02X1472959Y1379994I203J0D01*
G01X1473920D01*
X1475223Y1379140D01*
G03X1475407Y1379141I91J178D01*
G37*
G36*
G01X1487647D02*
X1488953Y1379994D01*
X1489909D01*
G02X1490112Y1379791I0J-203D01*
G01Y1376891D01*
G02X1489909Y1376688I-203J0D01*
G01X1488953D01*
X1488905Y1376718D01*
G02X1488903Y1376720I137J139D01*
G01X1488878Y1376736D01*
X1487638Y1377544D01*
G03X1487453Y1377539I-88J-180D01*
G01X1486155Y1376688D01*
X1485199D01*
G02X1484996Y1376891I0J203D01*
G01Y1379791D01*
G02X1485199Y1379994I203J0D01*
G01X1486160D01*
X1487463Y1379140D01*
G03X1487647Y1379141I91J178D01*
G37*
G36*
G01X1499887D02*
X1501193Y1379994D01*
X1502149D01*
G02X1502352Y1379791I0J-203D01*
G01Y1376891D01*
G02X1502149Y1376688I-203J0D01*
G01X1501193D01*
X1501145Y1376718D01*
G02X1501143Y1376720I137J139D01*
G01X1501118Y1376736D01*
X1499878Y1377544D01*
G03X1499693Y1377539I-88J-180D01*
G01X1498395Y1376688D01*
X1497439D01*
G02X1497236Y1376891I0J203D01*
G01Y1379791D01*
G02X1497439Y1379994I203J0D01*
G01X1498400D01*
X1499703Y1379140D01*
G03X1499887Y1379141I91J178D01*
G37*
G36*
G01X1512127D02*
X1513433Y1379994D01*
X1514389D01*
G02X1514592Y1379791I0J-203D01*
G01Y1376891D01*
G02X1514389Y1376688I-203J0D01*
G01X1513433D01*
X1513385Y1376718D01*
G02X1513383Y1376720I137J139D01*
G01X1513358Y1376736D01*
X1512118Y1377544D01*
G03X1511933Y1377539I-88J-180D01*
G01X1510635Y1376688D01*
X1509679D01*
G02X1509476Y1376891I0J203D01*
G01Y1379791D01*
G02X1509679Y1379994I203J0D01*
G01X1510640D01*
X1511943Y1379140D01*
G03X1512127Y1379141I91J178D01*
G37*
G36*
G01X1524367D02*
X1525673Y1379994D01*
X1526629D01*
G02X1526832Y1379791I0J-203D01*
G01Y1376891D01*
G02X1526629Y1376688I-203J0D01*
G01X1525673D01*
X1525625Y1376718D01*
G02X1525623Y1376720I137J139D01*
G01X1525598Y1376736D01*
X1524358Y1377544D01*
G03X1524173Y1377539I-88J-180D01*
G01X1522875Y1376688D01*
X1521919D01*
G02X1521716Y1376891I0J203D01*
G01Y1379791D01*
G02X1521919Y1379994I203J0D01*
G01X1522880D01*
X1524183Y1379140D01*
G03X1524367Y1379141I91J178D01*
G37*
G36*
G01X1536607D02*
X1537913Y1379994D01*
X1538869D01*
G02X1539072Y1379791I0J-203D01*
G01Y1376891D01*
G02X1538869Y1376688I-203J0D01*
G01X1537913D01*
X1537865Y1376718D01*
G02X1537863Y1376720I137J139D01*
G01X1537838Y1376736D01*
X1536598Y1377544D01*
G03X1536413Y1377539I-88J-180D01*
G01X1535115Y1376688D01*
X1534159D01*
G02X1533956Y1376891I0J203D01*
G01Y1379791D01*
G02X1534159Y1379994I203J0D01*
G01X1535120D01*
X1536423Y1379140D01*
G03X1536607Y1379141I91J178D01*
G37*
G36*
G01X1548847D02*
X1550153Y1379994D01*
X1551109D01*
G02X1551312Y1379791I0J-203D01*
G01Y1376891D01*
G02X1551109Y1376688I-203J0D01*
G01X1550153D01*
X1550105Y1376718D01*
G02X1550103Y1376720I137J139D01*
G01X1550078Y1376736D01*
X1548838Y1377544D01*
G03X1548653Y1377539I-88J-180D01*
G01X1547355Y1376688D01*
X1546399D01*
G02X1546196Y1376891I0J203D01*
G01Y1379791D01*
G02X1546399Y1379994I203J0D01*
G01X1547360D01*
X1548663Y1379140D01*
G03X1548847Y1379141I91J178D01*
G37*
G36*
G01X1561087D02*
X1562393Y1379994D01*
X1563349D01*
G02X1563552Y1379791I0J-203D01*
G01Y1376891D01*
G02X1563349Y1376688I-203J0D01*
G01X1562393D01*
X1562345Y1376718D01*
G02X1562343Y1376720I137J139D01*
G01X1562318Y1376736D01*
X1561078Y1377544D01*
G03X1560893Y1377539I-88J-180D01*
G01X1559595Y1376688D01*
X1558639D01*
G02X1558436Y1376891I0J203D01*
G01Y1379791D01*
G02X1558639Y1379994I203J0D01*
G01X1559600D01*
X1560903Y1379140D01*
G03X1561087Y1379141I91J178D01*
G37*
G36*
G01X1573327D02*
X1574633Y1379994D01*
X1575589D01*
G02X1575792Y1379791I0J-203D01*
G01Y1376891D01*
G02X1575589Y1376688I-203J0D01*
G01X1574633D01*
X1574585Y1376718D01*
G02X1574583Y1376720I137J139D01*
G01X1574558Y1376736D01*
X1573318Y1377544D01*
G03X1573133Y1377539I-88J-180D01*
G01X1571835Y1376688D01*
X1570879D01*
G02X1570676Y1376891I0J203D01*
G01Y1379791D01*
G02X1570879Y1379994I203J0D01*
G01X1571840D01*
X1573143Y1379140D01*
G03X1573327Y1379141I91J178D01*
G37*
G36*
G01X1585567D02*
X1586873Y1379994D01*
X1587829D01*
G02X1588032Y1379791I0J-203D01*
G01Y1376891D01*
G02X1587829Y1376688I-203J0D01*
G01X1586873D01*
X1586825Y1376718D01*
G02X1586823Y1376720I137J139D01*
G01X1586798Y1376736D01*
X1585558Y1377544D01*
G03X1585373Y1377539I-88J-180D01*
G01X1584075Y1376688D01*
X1583119D01*
G02X1582916Y1376891I0J203D01*
G01Y1379791D01*
G02X1583119Y1379994I203J0D01*
G01X1584080D01*
X1585383Y1379140D01*
G03X1585567Y1379141I91J178D01*
G37*
G36*
G01X1613195D02*
X1614501Y1379994D01*
X1615457D01*
G02X1615660Y1379791I0J-203D01*
G01Y1376891D01*
G02X1615457Y1376688I-203J0D01*
G01X1614501D01*
X1614453Y1376718D01*
G02X1614451Y1376720I137J139D01*
G01X1614426Y1376736D01*
X1613186Y1377544D01*
G03X1613001Y1377539I-88J-180D01*
G01X1611703Y1376688D01*
X1610747D01*
G02X1610544Y1376891I0J203D01*
G01Y1379791D01*
G02X1610747Y1379994I203J0D01*
G01X1611708D01*
X1613011Y1379140D01*
G03X1613195Y1379141I91J178D01*
G37*
G36*
G01X1625435D02*
X1626741Y1379994D01*
X1627697D01*
G02X1627900Y1379791I0J-203D01*
G01Y1376891D01*
G02X1627697Y1376688I-203J0D01*
G01X1626741D01*
X1626693Y1376718D01*
G02X1626691Y1376720I137J139D01*
G01X1626666Y1376736D01*
X1625426Y1377544D01*
G03X1625241Y1377539I-88J-180D01*
G01X1623943Y1376688D01*
X1622987D01*
G02X1622784Y1376891I0J203D01*
G01Y1379791D01*
G02X1622987Y1379994I203J0D01*
G01X1623948D01*
X1625251Y1379140D01*
G03X1625435Y1379141I91J178D01*
G37*
G36*
G01X1637675D02*
X1638981Y1379994D01*
X1639937D01*
G02X1640140Y1379791I0J-203D01*
G01Y1376891D01*
G02X1639937Y1376688I-203J0D01*
G01X1638981D01*
X1638933Y1376718D01*
G02X1638931Y1376720I137J139D01*
G01X1638906Y1376736D01*
X1637666Y1377544D01*
G03X1637481Y1377539I-88J-180D01*
G01X1636183Y1376688D01*
X1635227D01*
G02X1635024Y1376891I0J203D01*
G01Y1379791D01*
G02X1635227Y1379994I203J0D01*
G01X1636188D01*
X1637491Y1379140D01*
G03X1637675Y1379141I91J178D01*
G37*
G36*
G01X1649915D02*
X1651221Y1379994D01*
X1652177D01*
G02X1652380Y1379791I0J-203D01*
G01Y1376891D01*
G02X1652177Y1376688I-203J0D01*
G01X1651221D01*
X1651173Y1376718D01*
G02X1651171Y1376720I137J139D01*
G01X1651146Y1376736D01*
X1649906Y1377544D01*
G03X1649721Y1377539I-88J-180D01*
G01X1648423Y1376688D01*
X1647467D01*
G02X1647264Y1376891I0J203D01*
G01Y1379791D01*
G02X1647467Y1379994I203J0D01*
G01X1648428D01*
X1649731Y1379140D01*
G03X1649915Y1379141I91J178D01*
G37*
G36*
G01X1662155D02*
X1663461Y1379994D01*
X1664417D01*
G02X1664620Y1379791I0J-203D01*
G01Y1376891D01*
G02X1664417Y1376688I-203J0D01*
G01X1663461D01*
X1663413Y1376718D01*
G02X1663411Y1376720I137J139D01*
G01X1663386Y1376736D01*
X1662146Y1377544D01*
G03X1661961Y1377539I-88J-180D01*
G01X1660663Y1376688D01*
X1659707D01*
G02X1659504Y1376891I0J203D01*
G01Y1379791D01*
G02X1659707Y1379994I203J0D01*
G01X1660668D01*
X1661971Y1379140D01*
G03X1662155Y1379141I91J178D01*
G37*
G36*
G01X1674395D02*
X1675701Y1379994D01*
X1676657D01*
G02X1676860Y1379791I0J-203D01*
G01Y1376891D01*
G02X1676657Y1376688I-203J0D01*
G01X1675701D01*
X1675653Y1376718D01*
G02X1675651Y1376720I137J139D01*
G01X1675626Y1376736D01*
X1674386Y1377544D01*
G03X1674201Y1377539I-88J-180D01*
G01X1672903Y1376688D01*
X1671947D01*
G02X1671744Y1376891I0J203D01*
G01Y1379791D01*
G02X1671947Y1379994I203J0D01*
G01X1672908D01*
X1674211Y1379140D01*
G03X1674395Y1379141I91J178D01*
G37*
G36*
G01X1686635D02*
X1687941Y1379994D01*
X1688897D01*
G02X1689100Y1379791I0J-203D01*
G01Y1376891D01*
G02X1688897Y1376688I-203J0D01*
G01X1687941D01*
X1687893Y1376718D01*
G02X1687891Y1376720I137J139D01*
G01X1687866Y1376736D01*
X1686626Y1377544D01*
G03X1686441Y1377539I-88J-180D01*
G01X1685143Y1376688D01*
X1684187D01*
G02X1683984Y1376891I0J203D01*
G01Y1379791D01*
G02X1684187Y1379994I203J0D01*
G01X1685148D01*
X1686451Y1379140D01*
G03X1686635Y1379141I91J178D01*
G37*
G36*
G01X1698875D02*
X1700181Y1379994D01*
X1701137D01*
G02X1701340Y1379791I0J-203D01*
G01Y1376891D01*
G02X1701137Y1376688I-203J0D01*
G01X1700181D01*
X1700133Y1376718D01*
G02X1700131Y1376720I137J139D01*
G01X1700106Y1376736D01*
X1698866Y1377544D01*
G03X1698681Y1377539I-88J-180D01*
G01X1697383Y1376688D01*
X1696427D01*
G02X1696224Y1376891I0J203D01*
G01Y1379791D01*
G02X1696427Y1379994I203J0D01*
G01X1697388D01*
X1698691Y1379140D01*
G03X1698875Y1379141I91J178D01*
G37*
G36*
G01X1711115D02*
X1712421Y1379994D01*
X1713377D01*
G02X1713580Y1379791I0J-203D01*
G01Y1376891D01*
G02X1713377Y1376688I-203J0D01*
G01X1712421D01*
X1712373Y1376718D01*
G02X1712371Y1376720I137J139D01*
G01X1712346Y1376736D01*
X1711106Y1377544D01*
G03X1710921Y1377539I-88J-180D01*
G01X1709623Y1376688D01*
X1708667D01*
G02X1708464Y1376891I0J203D01*
G01Y1379791D01*
G02X1708667Y1379994I203J0D01*
G01X1709628D01*
X1710931Y1379140D01*
G03X1711115Y1379141I91J178D01*
G37*
G36*
G01X1723355D02*
X1724661Y1379994D01*
X1725617D01*
G02X1725820Y1379791I0J-203D01*
G01Y1376891D01*
G02X1725617Y1376688I-203J0D01*
G01X1724661D01*
X1724613Y1376718D01*
G02X1724611Y1376720I137J139D01*
G01X1724586Y1376736D01*
X1723346Y1377544D01*
G03X1723161Y1377539I-88J-180D01*
G01X1721863Y1376688D01*
X1720907D01*
G02X1720704Y1376891I0J203D01*
G01Y1379791D01*
G02X1720907Y1379994I203J0D01*
G01X1721868D01*
X1723171Y1379140D01*
G03X1723355Y1379141I91J178D01*
G37*
G36*
G01X1735595D02*
X1736901Y1379994D01*
X1737857D01*
G02X1738060Y1379791I0J-203D01*
G01Y1376891D01*
G02X1737857Y1376688I-203J0D01*
G01X1736901D01*
X1736853Y1376718D01*
G02X1736851Y1376720I137J139D01*
G01X1736826Y1376736D01*
X1735586Y1377544D01*
G03X1735401Y1377539I-88J-180D01*
G01X1734103Y1376688D01*
X1733147D01*
G02X1732944Y1376891I0J203D01*
G01Y1379791D01*
G02X1733147Y1379994I203J0D01*
G01X1734108D01*
X1735411Y1379140D01*
G03X1735595Y1379141I91J178D01*
G37*
G36*
G01X726005Y1403245D02*
X727311Y1404098D01*
X728267D01*
G02X728470Y1403895I0J-203D01*
G01Y1400995D01*
G02X728267Y1400792I-203J0D01*
G01X727311D01*
X727263Y1400822D01*
G02X727261Y1400824I137J139D01*
G01X727236Y1400840D01*
X725996Y1401648D01*
G03X725811Y1401643I-88J-180D01*
G01X724513Y1400792D01*
X723557D01*
G02X723354Y1400995I0J203D01*
G01Y1403895D01*
G02X723557Y1404098I203J0D01*
G01X724518D01*
X725821Y1403244D01*
G03X726005Y1403245I91J178D01*
G37*
G36*
G01X738245D02*
X739551Y1404098D01*
X740507D01*
G02X740710Y1403895I0J-203D01*
G01Y1400995D01*
G02X740507Y1400792I-203J0D01*
G01X739551D01*
X739503Y1400822D01*
G02X739501Y1400824I137J139D01*
G01X739476Y1400840D01*
X738236Y1401648D01*
G03X738051Y1401643I-88J-180D01*
G01X736753Y1400792D01*
X735797D01*
G02X735594Y1400995I0J203D01*
G01Y1403895D01*
G02X735797Y1404098I203J0D01*
G01X736758D01*
X738061Y1403244D01*
G03X738245Y1403245I91J178D01*
G37*
G36*
G01X90149Y1403339D02*
X91455Y1404192D01*
X92411D01*
G02X92614Y1403989I0J-203D01*
G01Y1401089D01*
G02X92411Y1400886I-203J0D01*
G01X91455D01*
X91407Y1400916D01*
G02X91405Y1400918I137J139D01*
G01X91380Y1400934D01*
X90140Y1401742D01*
G03X89955Y1401737I-88J-180D01*
G01X88657Y1400886D01*
X87701D01*
G02X87498Y1401089I0J203D01*
G01Y1403989D01*
G02X87701Y1404192I203J0D01*
G01X88662D01*
X89965Y1403338D01*
G03X90149Y1403339I91J178D01*
G37*
G36*
G01X102389D02*
X103695Y1404192D01*
X104651D01*
G02X104854Y1403989I0J-203D01*
G01Y1401089D01*
G02X104651Y1400886I-203J0D01*
G01X103695D01*
X103647Y1400916D01*
G02X103645Y1400918I137J139D01*
G01X103620Y1400934D01*
X102380Y1401742D01*
G03X102195Y1401737I-88J-180D01*
G01X100897Y1400886D01*
X99941D01*
G02X99738Y1401089I0J203D01*
G01Y1403989D01*
G02X99941Y1404192I203J0D01*
G01X100902D01*
X102205Y1403338D01*
G03X102389Y1403339I91J178D01*
G37*
G36*
G01X114629D02*
X115935Y1404192D01*
X116891D01*
G02X117094Y1403989I0J-203D01*
G01Y1401089D01*
G02X116891Y1400886I-203J0D01*
G01X115935D01*
X115887Y1400916D01*
G02X115885Y1400918I137J139D01*
G01X115860Y1400934D01*
X114620Y1401742D01*
G03X114435Y1401737I-88J-180D01*
G01X113137Y1400886D01*
X112181D01*
G02X111978Y1401089I0J203D01*
G01Y1403989D01*
G02X112181Y1404192I203J0D01*
G01X113142D01*
X114445Y1403338D01*
G03X114629Y1403339I91J178D01*
G37*
G36*
G01X126869D02*
X128175Y1404192D01*
X129131D01*
G02X129334Y1403989I0J-203D01*
G01Y1401089D01*
G02X129131Y1400886I-203J0D01*
G01X128175D01*
X128127Y1400916D01*
G02X128125Y1400918I137J139D01*
G01X128100Y1400934D01*
X126860Y1401742D01*
G03X126675Y1401737I-88J-180D01*
G01X125377Y1400886D01*
X124421D01*
G02X124218Y1401089I0J203D01*
G01Y1403989D01*
G02X124421Y1404192I203J0D01*
G01X125382D01*
X126685Y1403338D01*
G03X126869Y1403339I91J178D01*
G37*
G36*
G01X139109D02*
X140415Y1404192D01*
X141371D01*
G02X141574Y1403989I0J-203D01*
G01Y1401089D01*
G02X141371Y1400886I-203J0D01*
G01X140415D01*
X140367Y1400916D01*
G02X140365Y1400918I137J139D01*
G01X140340Y1400934D01*
X139100Y1401742D01*
G03X138915Y1401737I-88J-180D01*
G01X137617Y1400886D01*
X136661D01*
G02X136458Y1401089I0J203D01*
G01Y1403989D01*
G02X136661Y1404192I203J0D01*
G01X137622D01*
X138925Y1403338D01*
G03X139109Y1403339I91J178D01*
G37*
G36*
G01X151349D02*
X152655Y1404192D01*
X153611D01*
G02X153814Y1403989I0J-203D01*
G01Y1401089D01*
G02X153611Y1400886I-203J0D01*
G01X152655D01*
X152607Y1400916D01*
G02X152605Y1400918I137J139D01*
G01X152580Y1400934D01*
X151340Y1401742D01*
G03X151155Y1401737I-88J-180D01*
G01X149857Y1400886D01*
X148901D01*
G02X148698Y1401089I0J203D01*
G01Y1403989D01*
G02X148901Y1404192I203J0D01*
G01X149862D01*
X151165Y1403338D01*
G03X151349Y1403339I91J178D01*
G37*
G36*
G01X163589D02*
X164895Y1404192D01*
X165851D01*
G02X166054Y1403989I0J-203D01*
G01Y1401089D01*
G02X165851Y1400886I-203J0D01*
G01X164895D01*
X164847Y1400916D01*
G02X164845Y1400918I137J139D01*
G01X164820Y1400934D01*
X163580Y1401742D01*
G03X163395Y1401737I-88J-180D01*
G01X162097Y1400886D01*
X161141D01*
G02X160938Y1401089I0J203D01*
G01Y1403989D01*
G02X161141Y1404192I203J0D01*
G01X162102D01*
X163405Y1403338D01*
G03X163589Y1403339I91J178D01*
G37*
G36*
G01X175829D02*
X177135Y1404192D01*
X178091D01*
G02X178294Y1403989I0J-203D01*
G01Y1401089D01*
G02X178091Y1400886I-203J0D01*
G01X177135D01*
X177087Y1400916D01*
G02X177085Y1400918I137J139D01*
G01X177060Y1400934D01*
X175820Y1401742D01*
G03X175635Y1401737I-88J-180D01*
G01X174337Y1400886D01*
X173381D01*
G02X173178Y1401089I0J203D01*
G01Y1403989D01*
G02X173381Y1404192I203J0D01*
G01X174342D01*
X175645Y1403338D01*
G03X175829Y1403339I91J178D01*
G37*
G36*
G01X188069D02*
X189375Y1404192D01*
X190331D01*
G02X190534Y1403989I0J-203D01*
G01Y1401089D01*
G02X190331Y1400886I-203J0D01*
G01X189375D01*
X189327Y1400916D01*
G02X189325Y1400918I137J139D01*
G01X189300Y1400934D01*
X188060Y1401742D01*
G03X187875Y1401737I-88J-180D01*
G01X186577Y1400886D01*
X185621D01*
G02X185418Y1401089I0J203D01*
G01Y1403989D01*
G02X185621Y1404192I203J0D01*
G01X186582D01*
X187885Y1403338D01*
G03X188069Y1403339I91J178D01*
G37*
G36*
G01X200309D02*
X201615Y1404192D01*
X202571D01*
G02X202774Y1403989I0J-203D01*
G01Y1401089D01*
G02X202571Y1400886I-203J0D01*
G01X201615D01*
X201567Y1400916D01*
G02X201565Y1400918I137J139D01*
G01X201540Y1400934D01*
X200300Y1401742D01*
G03X200115Y1401737I-88J-180D01*
G01X198817Y1400886D01*
X197861D01*
G02X197658Y1401089I0J203D01*
G01Y1403989D01*
G02X197861Y1404192I203J0D01*
G01X198822D01*
X200125Y1403338D01*
G03X200309Y1403339I91J178D01*
G37*
G36*
G01X255660D02*
X256966Y1404192D01*
X257922D01*
G02X258126Y1403989I1J-203D01*
G01Y1401089D01*
G02X257922Y1400886I-204J1D01*
G01X256966D01*
X256918Y1400916D01*
G02X256916Y1400918I137J139D01*
G01X256891Y1400934D01*
X255651Y1401742D01*
G03X255466Y1401737I-88J-180D01*
G01X254168Y1400886D01*
X253212D01*
G02X253008Y1401089I-1J203D01*
G01Y1403989D01*
G02X253212Y1404192I204J-1D01*
G01X254173D01*
X255476Y1403338D01*
G03X255660Y1403339I91J178D01*
G37*
G36*
G01X267900D02*
X269206Y1404192D01*
X270162D01*
G02X270366Y1403989I1J-203D01*
G01Y1401089D01*
G02X270162Y1400886I-204J1D01*
G01X269206D01*
X269158Y1400916D01*
G02X269156Y1400918I137J139D01*
G01X269131Y1400934D01*
X267891Y1401742D01*
G03X267706Y1401737I-88J-180D01*
G01X266408Y1400886D01*
X265452D01*
G02X265248Y1401089I-1J203D01*
G01Y1403989D01*
G02X265452Y1404192I204J-1D01*
G01X266413D01*
X267716Y1403338D01*
G03X267900Y1403339I91J178D01*
G37*
G36*
G01X280140D02*
X281446Y1404192D01*
X282402D01*
G02X282606Y1403989I1J-203D01*
G01Y1401089D01*
G02X282402Y1400886I-204J1D01*
G01X281446D01*
X281398Y1400916D01*
G02X281396Y1400918I137J139D01*
G01X281371Y1400934D01*
X280131Y1401742D01*
G03X279946Y1401737I-88J-180D01*
G01X278648Y1400886D01*
X277692D01*
G02X277488Y1401089I-1J203D01*
G01Y1403989D01*
G02X277692Y1404192I204J-1D01*
G01X278653D01*
X279956Y1403338D01*
G03X280140Y1403339I91J178D01*
G37*
G36*
G01X292380D02*
X293686Y1404192D01*
X294642D01*
G02X294846Y1403989I1J-203D01*
G01Y1401089D01*
G02X294642Y1400886I-204J1D01*
G01X293686D01*
X293638Y1400916D01*
G02X293636Y1400918I137J139D01*
G01X293611Y1400934D01*
X292371Y1401742D01*
G03X292186Y1401737I-88J-180D01*
G01X290888Y1400886D01*
X289932D01*
G02X289728Y1401089I-1J203D01*
G01Y1403989D01*
G02X289932Y1404192I204J-1D01*
G01X290893D01*
X292196Y1403338D01*
G03X292380Y1403339I91J178D01*
G37*
G36*
G01X304620D02*
X305926Y1404192D01*
X306882D01*
G02X307086Y1403989I1J-203D01*
G01Y1401089D01*
G02X306882Y1400886I-204J1D01*
G01X305926D01*
X305878Y1400916D01*
G02X305876Y1400918I137J139D01*
G01X305851Y1400934D01*
X304611Y1401742D01*
G03X304426Y1401737I-88J-180D01*
G01X303128Y1400886D01*
X302172D01*
G02X301968Y1401089I-1J203D01*
G01Y1403989D01*
G02X302172Y1404192I204J-1D01*
G01X303133D01*
X304436Y1403338D01*
G03X304620Y1403339I91J178D01*
G37*
G36*
G01X316860D02*
X318166Y1404192D01*
X319122D01*
G02X319326Y1403989I1J-203D01*
G01Y1401089D01*
G02X319122Y1400886I-204J1D01*
G01X318166D01*
X318118Y1400916D01*
G02X318116Y1400918I137J139D01*
G01X318091Y1400934D01*
X316851Y1401742D01*
G03X316666Y1401737I-88J-180D01*
G01X315368Y1400886D01*
X314412D01*
G02X314208Y1401089I-1J203D01*
G01Y1403989D01*
G02X314412Y1404192I204J-1D01*
G01X315373D01*
X316676Y1403338D01*
G03X316860Y1403339I91J178D01*
G37*
G36*
G01X329100D02*
X330406Y1404192D01*
X331362D01*
G02X331566Y1403989I1J-203D01*
G01Y1401089D01*
G02X331362Y1400886I-204J1D01*
G01X330406D01*
X330358Y1400916D01*
G02X330356Y1400918I137J139D01*
G01X330331Y1400934D01*
X329091Y1401742D01*
G03X328906Y1401737I-88J-180D01*
G01X327608Y1400886D01*
X326652D01*
G02X326448Y1401089I-1J203D01*
G01Y1403989D01*
G02X326652Y1404192I204J-1D01*
G01X327613D01*
X328916Y1403338D01*
G03X329100Y1403339I91J178D01*
G37*
G36*
G01X341340D02*
X342646Y1404192D01*
X343602D01*
G02X343806Y1403989I1J-203D01*
G01Y1401089D01*
G02X343602Y1400886I-204J1D01*
G01X342646D01*
X342598Y1400916D01*
G02X342596Y1400918I137J139D01*
G01X342571Y1400934D01*
X341331Y1401742D01*
G03X341146Y1401737I-88J-180D01*
G01X339848Y1400886D01*
X338892D01*
G02X338688Y1401089I-1J203D01*
G01Y1403989D01*
G02X338892Y1404192I204J-1D01*
G01X339853D01*
X341156Y1403338D01*
G03X341340Y1403339I91J178D01*
G37*
G36*
G01X353580D02*
X354886Y1404192D01*
X355842D01*
G02X356046Y1403989I1J-203D01*
G01Y1401089D01*
G02X355842Y1400886I-204J1D01*
G01X354886D01*
X354838Y1400916D01*
G02X354836Y1400918I137J139D01*
G01X354811Y1400934D01*
X353571Y1401742D01*
G03X353386Y1401737I-88J-180D01*
G01X352088Y1400886D01*
X351132D01*
G02X350928Y1401089I-1J203D01*
G01Y1403989D01*
G02X351132Y1404192I204J-1D01*
G01X352093D01*
X353396Y1403338D01*
G03X353580Y1403339I91J178D01*
G37*
G36*
G01X365820D02*
X367126Y1404192D01*
X368082D01*
G02X368286Y1403989I1J-203D01*
G01Y1401089D01*
G02X368082Y1400886I-204J1D01*
G01X367126D01*
X367078Y1400916D01*
G02X367076Y1400918I137J139D01*
G01X367051Y1400934D01*
X365811Y1401742D01*
G03X365626Y1401737I-88J-180D01*
G01X364328Y1400886D01*
X363372D01*
G02X363168Y1401089I-1J203D01*
G01Y1403989D01*
G02X363372Y1404192I204J-1D01*
G01X364333D01*
X365636Y1403338D01*
G03X365820Y1403339I91J178D01*
G37*
G36*
G01X454439D02*
X455745Y1404192D01*
X456701D01*
G02X456904Y1403989I0J-203D01*
G01Y1401089D01*
G02X456701Y1400886I-203J0D01*
G01X455745D01*
X455697Y1400916D01*
G02X455695Y1400918I137J139D01*
G01X455670Y1400934D01*
X454430Y1401742D01*
G03X454245Y1401737I-88J-180D01*
G01X452947Y1400886D01*
X451991D01*
G02X451788Y1401089I0J203D01*
G01Y1403989D01*
G02X451991Y1404192I203J0D01*
G01X452952D01*
X454255Y1403338D01*
G03X454439Y1403339I91J178D01*
G37*
G36*
G01X466679D02*
X467985Y1404192D01*
X468941D01*
G02X469144Y1403989I0J-203D01*
G01Y1401089D01*
G02X468941Y1400886I-203J0D01*
G01X467985D01*
X467937Y1400916D01*
G02X467935Y1400918I137J139D01*
G01X467910Y1400934D01*
X466670Y1401742D01*
G03X466485Y1401737I-88J-180D01*
G01X465187Y1400886D01*
X464231D01*
G02X464028Y1401089I0J203D01*
G01Y1403989D01*
G02X464231Y1404192I203J0D01*
G01X465192D01*
X466495Y1403338D01*
G03X466679Y1403339I91J178D01*
G37*
G36*
G01X478919D02*
X480225Y1404192D01*
X481181D01*
G02X481384Y1403989I0J-203D01*
G01Y1401089D01*
G02X481181Y1400886I-203J0D01*
G01X480225D01*
X480177Y1400916D01*
G02X480175Y1400918I137J139D01*
G01X480150Y1400934D01*
X478910Y1401742D01*
G03X478725Y1401737I-88J-180D01*
G01X477427Y1400886D01*
X476471D01*
G02X476268Y1401089I0J203D01*
G01Y1403989D01*
G02X476471Y1404192I203J0D01*
G01X477432D01*
X478735Y1403338D01*
G03X478919Y1403339I91J178D01*
G37*
G36*
G01X491159D02*
X492465Y1404192D01*
X493421D01*
G02X493624Y1403989I0J-203D01*
G01Y1401089D01*
G02X493421Y1400886I-203J0D01*
G01X492465D01*
X492417Y1400916D01*
G02X492415Y1400918I137J139D01*
G01X492390Y1400934D01*
X491150Y1401742D01*
G03X490965Y1401737I-88J-180D01*
G01X489667Y1400886D01*
X488711D01*
G02X488508Y1401089I0J203D01*
G01Y1403989D01*
G02X488711Y1404192I203J0D01*
G01X489672D01*
X490975Y1403338D01*
G03X491159Y1403339I91J178D01*
G37*
G36*
G01X503399D02*
X504705Y1404192D01*
X505661D01*
G02X505864Y1403989I0J-203D01*
G01Y1401089D01*
G02X505661Y1400886I-203J0D01*
G01X504705D01*
X504657Y1400916D01*
G02X504655Y1400918I137J139D01*
G01X504630Y1400934D01*
X503390Y1401742D01*
G03X503205Y1401737I-88J-180D01*
G01X501907Y1400886D01*
X500951D01*
G02X500748Y1401089I0J203D01*
G01Y1403989D01*
G02X500951Y1404192I203J0D01*
G01X501912D01*
X503215Y1403338D01*
G03X503399Y1403339I91J178D01*
G37*
G36*
G01X515639D02*
X516945Y1404192D01*
X517901D01*
G02X518104Y1403989I0J-203D01*
G01Y1401089D01*
G02X517901Y1400886I-203J0D01*
G01X516945D01*
X516897Y1400916D01*
G02X516895Y1400918I137J139D01*
G01X516870Y1400934D01*
X515630Y1401742D01*
G03X515445Y1401737I-88J-180D01*
G01X514147Y1400886D01*
X513191D01*
G02X512988Y1401089I0J203D01*
G01Y1403989D01*
G02X513191Y1404192I203J0D01*
G01X514152D01*
X515455Y1403338D01*
G03X515639Y1403339I91J178D01*
G37*
G36*
G01X527879D02*
X529185Y1404192D01*
X530141D01*
G02X530344Y1403989I0J-203D01*
G01Y1401089D01*
G02X530141Y1400886I-203J0D01*
G01X529185D01*
X529137Y1400916D01*
G02X529135Y1400918I137J139D01*
G01X529110Y1400934D01*
X527870Y1401742D01*
G03X527685Y1401737I-88J-180D01*
G01X526387Y1400886D01*
X525431D01*
G02X525228Y1401089I0J203D01*
G01Y1403989D01*
G02X525431Y1404192I203J0D01*
G01X526392D01*
X527695Y1403338D01*
G03X527879Y1403339I91J178D01*
G37*
G36*
G01X540119D02*
X541425Y1404192D01*
X542381D01*
G02X542584Y1403989I0J-203D01*
G01Y1401089D01*
G02X542381Y1400886I-203J0D01*
G01X541425D01*
X541377Y1400916D01*
G02X541375Y1400918I137J139D01*
G01X541350Y1400934D01*
X540110Y1401742D01*
G03X539925Y1401737I-88J-180D01*
G01X538627Y1400886D01*
X537671D01*
G02X537468Y1401089I0J203D01*
G01Y1403989D01*
G02X537671Y1404192I203J0D01*
G01X538632D01*
X539935Y1403338D01*
G03X540119Y1403339I91J178D01*
G37*
G36*
G01X552359D02*
X553665Y1404192D01*
X554621D01*
G02X554824Y1403989I0J-203D01*
G01Y1401089D01*
G02X554621Y1400886I-203J0D01*
G01X553665D01*
X553617Y1400916D01*
G02X553615Y1400918I137J139D01*
G01X553590Y1400934D01*
X552350Y1401742D01*
G03X552165Y1401737I-88J-180D01*
G01X550867Y1400886D01*
X549911D01*
G02X549708Y1401089I0J203D01*
G01Y1403989D01*
G02X549911Y1404192I203J0D01*
G01X550872D01*
X552175Y1403338D01*
G03X552359Y1403339I91J178D01*
G37*
G36*
G01X564599D02*
X565905Y1404192D01*
X566861D01*
G02X567064Y1403989I0J-203D01*
G01Y1401089D01*
G02X566861Y1400886I-203J0D01*
G01X565905D01*
X565857Y1400916D01*
G02X565855Y1400918I137J139D01*
G01X565830Y1400934D01*
X564590Y1401742D01*
G03X564405Y1401737I-88J-180D01*
G01X563107Y1400886D01*
X562151D01*
G02X561948Y1401089I0J203D01*
G01Y1403989D01*
G02X562151Y1404192I203J0D01*
G01X563112D01*
X564415Y1403338D01*
G03X564599Y1403339I91J178D01*
G37*
G36*
G01X628085D02*
X629391Y1404192D01*
X630347D01*
G02X630550Y1403989I0J-203D01*
G01Y1401089D01*
G02X630347Y1400886I-203J0D01*
G01X629391D01*
X629343Y1400916D01*
G02X629341Y1400918I137J139D01*
G01X629316Y1400934D01*
X628076Y1401742D01*
G03X627891Y1401737I-88J-180D01*
G01X626593Y1400886D01*
X625637D01*
G02X625434Y1401089I0J203D01*
G01Y1403989D01*
G02X625637Y1404192I203J0D01*
G01X626598D01*
X627901Y1403338D01*
G03X628085Y1403339I91J178D01*
G37*
G36*
G01X640325D02*
X641631Y1404192D01*
X642587D01*
G02X642790Y1403989I0J-203D01*
G01Y1401089D01*
G02X642587Y1400886I-203J0D01*
G01X641631D01*
X641583Y1400916D01*
G02X641581Y1400918I137J139D01*
G01X641556Y1400934D01*
X640316Y1401742D01*
G03X640131Y1401737I-88J-180D01*
G01X638833Y1400886D01*
X637877D01*
G02X637674Y1401089I0J203D01*
G01Y1403989D01*
G02X637877Y1404192I203J0D01*
G01X638838D01*
X640141Y1403338D01*
G03X640325Y1403339I91J178D01*
G37*
G36*
G01X652565D02*
X653871Y1404192D01*
X654827D01*
G02X655030Y1403989I0J-203D01*
G01Y1401089D01*
G02X654827Y1400886I-203J0D01*
G01X653871D01*
X653823Y1400916D01*
G02X653821Y1400918I137J139D01*
G01X653796Y1400934D01*
X652556Y1401742D01*
G03X652371Y1401737I-88J-180D01*
G01X651073Y1400886D01*
X650117D01*
G02X649914Y1401089I0J203D01*
G01Y1403989D01*
G02X650117Y1404192I203J0D01*
G01X651078D01*
X652381Y1403338D01*
G03X652565Y1403339I91J178D01*
G37*
G36*
G01X664805D02*
X666111Y1404192D01*
X667067D01*
G02X667270Y1403989I0J-203D01*
G01Y1401089D01*
G02X667067Y1400886I-203J0D01*
G01X666111D01*
X666063Y1400916D01*
G02X666061Y1400918I137J139D01*
G01X666036Y1400934D01*
X664796Y1401742D01*
G03X664611Y1401737I-88J-180D01*
G01X663313Y1400886D01*
X662357D01*
G02X662154Y1401089I0J203D01*
G01Y1403989D01*
G02X662357Y1404192I203J0D01*
G01X663318D01*
X664621Y1403338D01*
G03X664805Y1403339I91J178D01*
G37*
G36*
G01X677045D02*
X678351Y1404192D01*
X679307D01*
G02X679510Y1403989I0J-203D01*
G01Y1401089D01*
G02X679307Y1400886I-203J0D01*
G01X678351D01*
X678303Y1400916D01*
G02X678301Y1400918I137J139D01*
G01X678276Y1400934D01*
X677036Y1401742D01*
G03X676851Y1401737I-88J-180D01*
G01X675553Y1400886D01*
X674597D01*
G02X674394Y1401089I0J203D01*
G01Y1403989D01*
G02X674597Y1404192I203J0D01*
G01X675558D01*
X676861Y1403338D01*
G03X677045Y1403339I91J178D01*
G37*
G36*
G01X689285D02*
X690591Y1404192D01*
X691547D01*
G02X691750Y1403989I0J-203D01*
G01Y1401089D01*
G02X691547Y1400886I-203J0D01*
G01X690591D01*
X690543Y1400916D01*
G02X690541Y1400918I137J139D01*
G01X690516Y1400934D01*
X689276Y1401742D01*
G03X689091Y1401737I-88J-180D01*
G01X687793Y1400886D01*
X686837D01*
G02X686634Y1401089I0J203D01*
G01Y1403989D01*
G02X686837Y1404192I203J0D01*
G01X687798D01*
X689101Y1403338D01*
G03X689285Y1403339I91J178D01*
G37*
G36*
G01X701525D02*
X702831Y1404192D01*
X703787D01*
G02X703990Y1403989I0J-203D01*
G01Y1401089D01*
G02X703787Y1400886I-203J0D01*
G01X702831D01*
X702783Y1400916D01*
G02X702781Y1400918I137J139D01*
G01X702756Y1400934D01*
X701516Y1401742D01*
G03X701331Y1401737I-88J-180D01*
G01X700033Y1400886D01*
X699077D01*
G02X698874Y1401089I0J203D01*
G01Y1403989D01*
G02X699077Y1404192I203J0D01*
G01X700038D01*
X701341Y1403338D01*
G03X701525Y1403339I91J178D01*
G37*
G36*
G01X713765D02*
X715071Y1404192D01*
X716027D01*
G02X716230Y1403989I0J-203D01*
G01Y1401089D01*
G02X716027Y1400886I-203J0D01*
G01X715071D01*
X715023Y1400916D01*
G02X715021Y1400918I137J139D01*
G01X714996Y1400934D01*
X713756Y1401742D01*
G03X713571Y1401737I-88J-180D01*
G01X712273Y1400886D01*
X711317D01*
G02X711114Y1401089I0J203D01*
G01Y1403989D01*
G02X711317Y1404192I203J0D01*
G01X712278D01*
X713581Y1403338D01*
G03X713765Y1403339I91J178D01*
G37*
G36*
G01X1068750D02*
X1070056Y1404192D01*
X1071012D01*
G02X1071216Y1403989I1J-203D01*
G01Y1401089D01*
G02X1071012Y1400886I-204J1D01*
G01X1070056D01*
X1070008Y1400916D01*
G02X1070006Y1400918I137J139D01*
G01X1069981Y1400934D01*
X1068741Y1401742D01*
G03X1068556Y1401737I-88J-180D01*
G01X1067258Y1400886D01*
X1066302D01*
G02X1066098Y1401089I-1J203D01*
G01Y1403989D01*
G02X1066302Y1404192I204J-1D01*
G01X1067263D01*
X1068566Y1403338D01*
G03X1068750Y1403339I91J178D01*
G37*
G36*
G01X1080990D02*
X1082296Y1404192D01*
X1083252D01*
G02X1083456Y1403989I1J-203D01*
G01Y1401089D01*
G02X1083252Y1400886I-204J1D01*
G01X1082296D01*
X1082248Y1400916D01*
G02X1082246Y1400918I137J139D01*
G01X1082221Y1400934D01*
X1080981Y1401742D01*
G03X1080796Y1401737I-88J-180D01*
G01X1079498Y1400886D01*
X1078542D01*
G02X1078338Y1401089I-1J203D01*
G01Y1403989D01*
G02X1078542Y1404192I204J-1D01*
G01X1079503D01*
X1080806Y1403338D01*
G03X1080990Y1403339I91J178D01*
G37*
G36*
G01X1093230D02*
X1094536Y1404192D01*
X1095492D01*
G02X1095696Y1403989I1J-203D01*
G01Y1401089D01*
G02X1095492Y1400886I-204J1D01*
G01X1094536D01*
X1094488Y1400916D01*
G02X1094486Y1400918I137J139D01*
G01X1094461Y1400934D01*
X1093221Y1401742D01*
G03X1093036Y1401737I-88J-180D01*
G01X1091738Y1400886D01*
X1090782D01*
G02X1090578Y1401089I-1J203D01*
G01Y1403989D01*
G02X1090782Y1404192I204J-1D01*
G01X1091743D01*
X1093046Y1403338D01*
G03X1093230Y1403339I91J178D01*
G37*
G36*
G01X1105470D02*
X1106776Y1404192D01*
X1107732D01*
G02X1107936Y1403989I1J-203D01*
G01Y1401089D01*
G02X1107732Y1400886I-204J1D01*
G01X1106776D01*
X1106728Y1400916D01*
G02X1106726Y1400918I137J139D01*
G01X1106701Y1400934D01*
X1105461Y1401742D01*
G03X1105276Y1401737I-88J-180D01*
G01X1103978Y1400886D01*
X1103022D01*
G02X1102818Y1401089I-1J203D01*
G01Y1403989D01*
G02X1103022Y1404192I204J-1D01*
G01X1103983D01*
X1105286Y1403338D01*
G03X1105470Y1403339I91J178D01*
G37*
G36*
G01X1117710D02*
X1119016Y1404192D01*
X1119972D01*
G02X1120176Y1403989I1J-203D01*
G01Y1401089D01*
G02X1119972Y1400886I-204J1D01*
G01X1119016D01*
X1118968Y1400916D01*
G02X1118966Y1400918I137J139D01*
G01X1118941Y1400934D01*
X1117701Y1401742D01*
G03X1117516Y1401737I-88J-180D01*
G01X1116218Y1400886D01*
X1115262D01*
G02X1115058Y1401089I-1J203D01*
G01Y1403989D01*
G02X1115262Y1404192I204J-1D01*
G01X1116223D01*
X1117526Y1403338D01*
G03X1117710Y1403339I91J178D01*
G37*
G36*
G01X1129950D02*
X1131256Y1404192D01*
X1132212D01*
G02X1132416Y1403989I1J-203D01*
G01Y1401089D01*
G02X1132212Y1400886I-204J1D01*
G01X1131256D01*
X1131208Y1400916D01*
G02X1131206Y1400918I137J139D01*
G01X1131181Y1400934D01*
X1129941Y1401742D01*
G03X1129756Y1401737I-88J-180D01*
G01X1128458Y1400886D01*
X1127502D01*
G02X1127298Y1401089I-1J203D01*
G01Y1403989D01*
G02X1127502Y1404192I204J-1D01*
G01X1128463D01*
X1129766Y1403338D01*
G03X1129950Y1403339I91J178D01*
G37*
G36*
G01X1142190D02*
X1143496Y1404192D01*
X1144452D01*
G02X1144656Y1403989I1J-203D01*
G01Y1401089D01*
G02X1144452Y1400886I-204J1D01*
G01X1143496D01*
X1143448Y1400916D01*
G02X1143446Y1400918I137J139D01*
G01X1143421Y1400934D01*
X1142181Y1401742D01*
G03X1141996Y1401737I-88J-180D01*
G01X1140698Y1400886D01*
X1139742D01*
G02X1139538Y1401089I-1J203D01*
G01Y1403989D01*
G02X1139742Y1404192I204J-1D01*
G01X1140703D01*
X1142006Y1403338D01*
G03X1142190Y1403339I91J178D01*
G37*
G36*
G01X1154430D02*
X1155736Y1404192D01*
X1156692D01*
G02X1156896Y1403989I1J-203D01*
G01Y1401089D01*
G02X1156692Y1400886I-204J1D01*
G01X1155736D01*
X1155688Y1400916D01*
G02X1155686Y1400918I137J139D01*
G01X1155661Y1400934D01*
X1154421Y1401742D01*
G03X1154236Y1401737I-88J-180D01*
G01X1152938Y1400886D01*
X1151982D01*
G02X1151778Y1401089I-1J203D01*
G01Y1403989D01*
G02X1151982Y1404192I204J-1D01*
G01X1152943D01*
X1154246Y1403338D01*
G03X1154430Y1403339I91J178D01*
G37*
G36*
G01X1166670D02*
X1167976Y1404192D01*
X1168932D01*
G02X1169136Y1403989I1J-203D01*
G01Y1401089D01*
G02X1168932Y1400886I-204J1D01*
G01X1167976D01*
X1167928Y1400916D01*
G02X1167926Y1400918I137J139D01*
G01X1167901Y1400934D01*
X1166661Y1401742D01*
G03X1166476Y1401737I-88J-180D01*
G01X1165178Y1400886D01*
X1164222D01*
G02X1164018Y1401089I-1J203D01*
G01Y1403989D01*
G02X1164222Y1404192I204J-1D01*
G01X1165183D01*
X1166486Y1403338D01*
G03X1166670Y1403339I91J178D01*
G37*
G36*
G01X1178910D02*
X1180216Y1404192D01*
X1181172D01*
G02X1181376Y1403989I1J-203D01*
G01Y1401089D01*
G02X1181172Y1400886I-204J1D01*
G01X1180216D01*
X1180168Y1400916D01*
G02X1180166Y1400918I137J139D01*
G01X1180141Y1400934D01*
X1178901Y1401742D01*
G03X1178716Y1401737I-88J-180D01*
G01X1177418Y1400886D01*
X1176462D01*
G02X1176258Y1401089I-1J203D01*
G01Y1403989D01*
G02X1176462Y1404192I204J-1D01*
G01X1177423D01*
X1178726Y1403338D01*
G03X1178910Y1403339I91J178D01*
G37*
G36*
G01X1244363D02*
X1245669Y1404192D01*
X1246625D01*
G02X1246828Y1403989I0J-203D01*
G01Y1401089D01*
G02X1246625Y1400886I-203J0D01*
G01X1245669D01*
X1245621Y1400916D01*
G02X1245619Y1400918I137J139D01*
G01X1245594Y1400934D01*
X1244354Y1401742D01*
G03X1244169Y1401737I-88J-180D01*
G01X1242871Y1400886D01*
X1241915D01*
G02X1241712Y1401089I0J203D01*
G01Y1403989D01*
G02X1241915Y1404192I203J0D01*
G01X1242876D01*
X1244179Y1403338D01*
G03X1244363Y1403339I91J178D01*
G37*
G36*
G01X1256603D02*
X1257909Y1404192D01*
X1258865D01*
G02X1259068Y1403989I0J-203D01*
G01Y1401089D01*
G02X1258865Y1400886I-203J0D01*
G01X1257909D01*
X1257861Y1400916D01*
G02X1257859Y1400918I137J139D01*
G01X1257834Y1400934D01*
X1256594Y1401742D01*
G03X1256409Y1401737I-88J-180D01*
G01X1255111Y1400886D01*
X1254155D01*
G02X1253952Y1401089I0J203D01*
G01Y1403989D01*
G02X1254155Y1404192I203J0D01*
G01X1255116D01*
X1256419Y1403338D01*
G03X1256603Y1403339I91J178D01*
G37*
G36*
G01X1268843D02*
X1270149Y1404192D01*
X1271105D01*
G02X1271308Y1403989I0J-203D01*
G01Y1401089D01*
G02X1271105Y1400886I-203J0D01*
G01X1270149D01*
X1270101Y1400916D01*
G02X1270099Y1400918I137J139D01*
G01X1270074Y1400934D01*
X1268834Y1401742D01*
G03X1268649Y1401737I-88J-180D01*
G01X1267351Y1400886D01*
X1266395D01*
G02X1266192Y1401089I0J203D01*
G01Y1403989D01*
G02X1266395Y1404192I203J0D01*
G01X1267356D01*
X1268659Y1403338D01*
G03X1268843Y1403339I91J178D01*
G37*
G36*
G01X1281083D02*
X1282389Y1404192D01*
X1283345D01*
G02X1283548Y1403989I0J-203D01*
G01Y1401089D01*
G02X1283345Y1400886I-203J0D01*
G01X1282389D01*
X1282341Y1400916D01*
G02X1282339Y1400918I137J139D01*
G01X1282314Y1400934D01*
X1281074Y1401742D01*
G03X1280889Y1401737I-88J-180D01*
G01X1279591Y1400886D01*
X1278635D01*
G02X1278432Y1401089I0J203D01*
G01Y1403989D01*
G02X1278635Y1404192I203J0D01*
G01X1279596D01*
X1280899Y1403338D01*
G03X1281083Y1403339I91J178D01*
G37*
G36*
G01X1293323D02*
X1294629Y1404192D01*
X1295585D01*
G02X1295788Y1403989I0J-203D01*
G01Y1401089D01*
G02X1295585Y1400886I-203J0D01*
G01X1294629D01*
X1294581Y1400916D01*
G02X1294579Y1400918I137J139D01*
G01X1294554Y1400934D01*
X1293314Y1401742D01*
G03X1293129Y1401737I-88J-180D01*
G01X1291831Y1400886D01*
X1290875D01*
G02X1290672Y1401089I0J203D01*
G01Y1403989D01*
G02X1290875Y1404192I203J0D01*
G01X1291836D01*
X1293139Y1403338D01*
G03X1293323Y1403339I91J178D01*
G37*
G36*
G01X1305563D02*
X1306869Y1404192D01*
X1307825D01*
G02X1308028Y1403989I0J-203D01*
G01Y1401089D01*
G02X1307825Y1400886I-203J0D01*
G01X1306869D01*
X1306821Y1400916D01*
G02X1306819Y1400918I137J139D01*
G01X1306794Y1400934D01*
X1305554Y1401742D01*
G03X1305369Y1401737I-88J-180D01*
G01X1304071Y1400886D01*
X1303115D01*
G02X1302912Y1401089I0J203D01*
G01Y1403989D01*
G02X1303115Y1404192I203J0D01*
G01X1304076D01*
X1305379Y1403338D01*
G03X1305563Y1403339I91J178D01*
G37*
G36*
G01X1317803D02*
X1319109Y1404192D01*
X1320065D01*
G02X1320268Y1403989I0J-203D01*
G01Y1401089D01*
G02X1320065Y1400886I-203J0D01*
G01X1319109D01*
X1319061Y1400916D01*
G02X1319059Y1400918I137J139D01*
G01X1319034Y1400934D01*
X1317794Y1401742D01*
G03X1317609Y1401737I-88J-180D01*
G01X1316311Y1400886D01*
X1315355D01*
G02X1315152Y1401089I0J203D01*
G01Y1403989D01*
G02X1315355Y1404192I203J0D01*
G01X1316316D01*
X1317619Y1403338D01*
G03X1317803Y1403339I91J178D01*
G37*
G36*
G01X1330043D02*
X1331349Y1404192D01*
X1332305D01*
G02X1332508Y1403989I0J-203D01*
G01Y1401089D01*
G02X1332305Y1400886I-203J0D01*
G01X1331349D01*
X1331301Y1400916D01*
G02X1331299Y1400918I137J139D01*
G01X1331274Y1400934D01*
X1330034Y1401742D01*
G03X1329849Y1401737I-88J-180D01*
G01X1328551Y1400886D01*
X1327595D01*
G02X1327392Y1401089I0J203D01*
G01Y1403989D01*
G02X1327595Y1404192I203J0D01*
G01X1328556D01*
X1329859Y1403338D01*
G03X1330043Y1403339I91J178D01*
G37*
G36*
G01X1342283D02*
X1343589Y1404192D01*
X1344545D01*
G02X1344748Y1403989I0J-203D01*
G01Y1401089D01*
G02X1344545Y1400886I-203J0D01*
G01X1343589D01*
X1343541Y1400916D01*
G02X1343539Y1400918I137J139D01*
G01X1343514Y1400934D01*
X1342274Y1401742D01*
G03X1342089Y1401737I-88J-180D01*
G01X1340791Y1400886D01*
X1339835D01*
G02X1339632Y1401089I0J203D01*
G01Y1403989D01*
G02X1339835Y1404192I203J0D01*
G01X1340796D01*
X1342099Y1403338D01*
G03X1342283Y1403339I91J178D01*
G37*
G36*
G01X1354523D02*
X1355829Y1404192D01*
X1356785D01*
G02X1356988Y1403989I0J-203D01*
G01Y1401089D01*
G02X1356785Y1400886I-203J0D01*
G01X1355829D01*
X1355781Y1400916D01*
G02X1355779Y1400918I137J139D01*
G01X1355754Y1400934D01*
X1354514Y1401742D01*
G03X1354329Y1401737I-88J-180D01*
G01X1353031Y1400886D01*
X1352075D01*
G02X1351872Y1401089I0J203D01*
G01Y1403989D01*
G02X1352075Y1404192I203J0D01*
G01X1353036D01*
X1354339Y1403338D01*
G03X1354523Y1403339I91J178D01*
G37*
G36*
G01X1475407D02*
X1476713Y1404192D01*
X1477669D01*
G02X1477872Y1403989I0J-203D01*
G01Y1401089D01*
G02X1477669Y1400886I-203J0D01*
G01X1476713D01*
X1476665Y1400916D01*
G02X1476663Y1400918I137J139D01*
G01X1476638Y1400934D01*
X1475398Y1401742D01*
G03X1475213Y1401737I-88J-180D01*
G01X1473915Y1400886D01*
X1472959D01*
G02X1472756Y1401089I0J203D01*
G01Y1403989D01*
G02X1472959Y1404192I203J0D01*
G01X1473920D01*
X1475223Y1403338D01*
G03X1475407Y1403339I91J178D01*
G37*
G36*
G01X1487647D02*
X1488953Y1404192D01*
X1489909D01*
G02X1490112Y1403989I0J-203D01*
G01Y1401089D01*
G02X1489909Y1400886I-203J0D01*
G01X1488953D01*
X1488905Y1400916D01*
G02X1488903Y1400918I137J139D01*
G01X1488878Y1400934D01*
X1487638Y1401742D01*
G03X1487453Y1401737I-88J-180D01*
G01X1486155Y1400886D01*
X1485199D01*
G02X1484996Y1401089I0J203D01*
G01Y1403989D01*
G02X1485199Y1404192I203J0D01*
G01X1486160D01*
X1487463Y1403338D01*
G03X1487647Y1403339I91J178D01*
G37*
G36*
G01X1499887D02*
X1501193Y1404192D01*
X1502149D01*
G02X1502352Y1403989I0J-203D01*
G01Y1401089D01*
G02X1502149Y1400886I-203J0D01*
G01X1501193D01*
X1501145Y1400916D01*
G02X1501143Y1400918I137J139D01*
G01X1501118Y1400934D01*
X1499878Y1401742D01*
G03X1499693Y1401737I-88J-180D01*
G01X1498395Y1400886D01*
X1497439D01*
G02X1497236Y1401089I0J203D01*
G01Y1403989D01*
G02X1497439Y1404192I203J0D01*
G01X1498400D01*
X1499703Y1403338D01*
G03X1499887Y1403339I91J178D01*
G37*
G36*
G01X1512127D02*
X1513433Y1404192D01*
X1514389D01*
G02X1514592Y1403989I0J-203D01*
G01Y1401089D01*
G02X1514389Y1400886I-203J0D01*
G01X1513433D01*
X1513385Y1400916D01*
G02X1513383Y1400918I137J139D01*
G01X1513358Y1400934D01*
X1512118Y1401742D01*
G03X1511933Y1401737I-88J-180D01*
G01X1510635Y1400886D01*
X1509679D01*
G02X1509476Y1401089I0J203D01*
G01Y1403989D01*
G02X1509679Y1404192I203J0D01*
G01X1510640D01*
X1511943Y1403338D01*
G03X1512127Y1403339I91J178D01*
G37*
G36*
G01X1524367D02*
X1525673Y1404192D01*
X1526629D01*
G02X1526832Y1403989I0J-203D01*
G01Y1401089D01*
G02X1526629Y1400886I-203J0D01*
G01X1525673D01*
X1525625Y1400916D01*
G02X1525623Y1400918I137J139D01*
G01X1525598Y1400934D01*
X1524358Y1401742D01*
G03X1524173Y1401737I-88J-180D01*
G01X1522875Y1400886D01*
X1521919D01*
G02X1521716Y1401089I0J203D01*
G01Y1403989D01*
G02X1521919Y1404192I203J0D01*
G01X1522880D01*
X1524183Y1403338D01*
G03X1524367Y1403339I91J178D01*
G37*
G36*
G01X1536607D02*
X1537913Y1404192D01*
X1538869D01*
G02X1539072Y1403989I0J-203D01*
G01Y1401089D01*
G02X1538869Y1400886I-203J0D01*
G01X1537913D01*
X1537865Y1400916D01*
G02X1537863Y1400918I137J139D01*
G01X1537838Y1400934D01*
X1536598Y1401742D01*
G03X1536413Y1401737I-88J-180D01*
G01X1535115Y1400886D01*
X1534159D01*
G02X1533956Y1401089I0J203D01*
G01Y1403989D01*
G02X1534159Y1404192I203J0D01*
G01X1535120D01*
X1536423Y1403338D01*
G03X1536607Y1403339I91J178D01*
G37*
G36*
G01X1548847D02*
X1550153Y1404192D01*
X1551109D01*
G02X1551312Y1403989I0J-203D01*
G01Y1401089D01*
G02X1551109Y1400886I-203J0D01*
G01X1550153D01*
X1550105Y1400916D01*
G02X1550103Y1400918I137J139D01*
G01X1550078Y1400934D01*
X1548838Y1401742D01*
G03X1548653Y1401737I-88J-180D01*
G01X1547355Y1400886D01*
X1546399D01*
G02X1546196Y1401089I0J203D01*
G01Y1403989D01*
G02X1546399Y1404192I203J0D01*
G01X1547360D01*
X1548663Y1403338D01*
G03X1548847Y1403339I91J178D01*
G37*
G36*
G01X1561087D02*
X1562393Y1404192D01*
X1563349D01*
G02X1563552Y1403989I0J-203D01*
G01Y1401089D01*
G02X1563349Y1400886I-203J0D01*
G01X1562393D01*
X1562345Y1400916D01*
G02X1562343Y1400918I137J139D01*
G01X1562318Y1400934D01*
X1561078Y1401742D01*
G03X1560893Y1401737I-88J-180D01*
G01X1559595Y1400886D01*
X1558639D01*
G02X1558436Y1401089I0J203D01*
G01Y1403989D01*
G02X1558639Y1404192I203J0D01*
G01X1559600D01*
X1560903Y1403338D01*
G03X1561087Y1403339I91J178D01*
G37*
G36*
G01X1573327D02*
X1574633Y1404192D01*
X1575589D01*
G02X1575792Y1403989I0J-203D01*
G01Y1401089D01*
G02X1575589Y1400886I-203J0D01*
G01X1574633D01*
X1574585Y1400916D01*
G02X1574583Y1400918I137J139D01*
G01X1574558Y1400934D01*
X1573318Y1401742D01*
G03X1573133Y1401737I-88J-180D01*
G01X1571835Y1400886D01*
X1570879D01*
G02X1570676Y1401089I0J203D01*
G01Y1403989D01*
G02X1570879Y1404192I203J0D01*
G01X1571840D01*
X1573143Y1403338D01*
G03X1573327Y1403339I91J178D01*
G37*
G36*
G01X1585567D02*
X1586873Y1404192D01*
X1587829D01*
G02X1588032Y1403989I0J-203D01*
G01Y1401089D01*
G02X1587829Y1400886I-203J0D01*
G01X1586873D01*
X1586825Y1400916D01*
G02X1586823Y1400918I137J139D01*
G01X1586798Y1400934D01*
X1585558Y1401742D01*
G03X1585373Y1401737I-88J-180D01*
G01X1584075Y1400886D01*
X1583119D01*
G02X1582916Y1401089I0J203D01*
G01Y1403989D01*
G02X1583119Y1404192I203J0D01*
G01X1584080D01*
X1585383Y1403338D01*
G03X1585567Y1403339I91J178D01*
G37*
G36*
G01X1625435D02*
X1626741Y1404192D01*
X1627697D01*
G02X1627900Y1403989I0J-203D01*
G01Y1401089D01*
G02X1627697Y1400886I-203J0D01*
G01X1626741D01*
X1626693Y1400916D01*
G02X1626691Y1400918I137J139D01*
G01X1626666Y1400934D01*
X1625426Y1401742D01*
G03X1625241Y1401737I-88J-180D01*
G01X1623943Y1400886D01*
X1622987D01*
G02X1622784Y1401089I0J203D01*
G01Y1403989D01*
G02X1622987Y1404192I203J0D01*
G01X1623948D01*
X1625251Y1403338D01*
G03X1625435Y1403339I91J178D01*
G37*
G36*
G01X1637675D02*
X1638981Y1404192D01*
X1639937D01*
G02X1640140Y1403989I0J-203D01*
G01Y1401089D01*
G02X1639937Y1400886I-203J0D01*
G01X1638981D01*
X1638933Y1400916D01*
G02X1638931Y1400918I137J139D01*
G01X1638906Y1400934D01*
X1637666Y1401742D01*
G03X1637481Y1401737I-88J-180D01*
G01X1636183Y1400886D01*
X1635227D01*
G02X1635024Y1401089I0J203D01*
G01Y1403989D01*
G02X1635227Y1404192I203J0D01*
G01X1636188D01*
X1637491Y1403338D01*
G03X1637675Y1403339I91J178D01*
G37*
G36*
G01X1649915D02*
X1651221Y1404192D01*
X1652177D01*
G02X1652380Y1403989I0J-203D01*
G01Y1401089D01*
G02X1652177Y1400886I-203J0D01*
G01X1651221D01*
X1651173Y1400916D01*
G02X1651171Y1400918I137J139D01*
G01X1651146Y1400934D01*
X1649906Y1401742D01*
G03X1649721Y1401737I-88J-180D01*
G01X1648423Y1400886D01*
X1647467D01*
G02X1647264Y1401089I0J203D01*
G01Y1403989D01*
G02X1647467Y1404192I203J0D01*
G01X1648428D01*
X1649731Y1403338D01*
G03X1649915Y1403339I91J178D01*
G37*
G36*
G01X1662155D02*
X1663461Y1404192D01*
X1664417D01*
G02X1664620Y1403989I0J-203D01*
G01Y1401089D01*
G02X1664417Y1400886I-203J0D01*
G01X1663461D01*
X1663413Y1400916D01*
G02X1663411Y1400918I137J139D01*
G01X1663386Y1400934D01*
X1662146Y1401742D01*
G03X1661961Y1401737I-88J-180D01*
G01X1660663Y1400886D01*
X1659707D01*
G02X1659504Y1401089I0J203D01*
G01Y1403989D01*
G02X1659707Y1404192I203J0D01*
G01X1660668D01*
X1661971Y1403338D01*
G03X1662155Y1403339I91J178D01*
G37*
G36*
G01X1674395D02*
X1675701Y1404192D01*
X1676657D01*
G02X1676860Y1403989I0J-203D01*
G01Y1401089D01*
G02X1676657Y1400886I-203J0D01*
G01X1675701D01*
X1675653Y1400916D01*
G02X1675651Y1400918I137J139D01*
G01X1675626Y1400934D01*
X1674386Y1401742D01*
G03X1674201Y1401737I-88J-180D01*
G01X1672903Y1400886D01*
X1671947D01*
G02X1671744Y1401089I0J203D01*
G01Y1403989D01*
G02X1671947Y1404192I203J0D01*
G01X1672908D01*
X1674211Y1403338D01*
G03X1674395Y1403339I91J178D01*
G37*
G36*
G01X1686635D02*
X1687941Y1404192D01*
X1688897D01*
G02X1689100Y1403989I0J-203D01*
G01Y1401089D01*
G02X1688897Y1400886I-203J0D01*
G01X1687941D01*
X1687893Y1400916D01*
G02X1687891Y1400918I137J139D01*
G01X1687866Y1400934D01*
X1686626Y1401742D01*
G03X1686441Y1401737I-88J-180D01*
G01X1685143Y1400886D01*
X1684187D01*
G02X1683984Y1401089I0J203D01*
G01Y1403989D01*
G02X1684187Y1404192I203J0D01*
G01X1685148D01*
X1686451Y1403338D01*
G03X1686635Y1403339I91J178D01*
G37*
G36*
G01X1698875D02*
X1700181Y1404192D01*
X1701137D01*
G02X1701340Y1403989I0J-203D01*
G01Y1401089D01*
G02X1701137Y1400886I-203J0D01*
G01X1700181D01*
X1700133Y1400916D01*
G02X1700131Y1400918I137J139D01*
G01X1700106Y1400934D01*
X1698866Y1401742D01*
G03X1698681Y1401737I-88J-180D01*
G01X1697383Y1400886D01*
X1696427D01*
G02X1696224Y1401089I0J203D01*
G01Y1403989D01*
G02X1696427Y1404192I203J0D01*
G01X1697388D01*
X1698691Y1403338D01*
G03X1698875Y1403339I91J178D01*
G37*
G36*
G01X1711115D02*
X1712421Y1404192D01*
X1713377D01*
G02X1713580Y1403989I0J-203D01*
G01Y1401089D01*
G02X1713377Y1400886I-203J0D01*
G01X1712421D01*
X1712373Y1400916D01*
G02X1712371Y1400918I137J139D01*
G01X1712346Y1400934D01*
X1711106Y1401742D01*
G03X1710921Y1401737I-88J-180D01*
G01X1709623Y1400886D01*
X1708667D01*
G02X1708464Y1401089I0J203D01*
G01Y1403989D01*
G02X1708667Y1404192I203J0D01*
G01X1709628D01*
X1710931Y1403338D01*
G03X1711115Y1403339I91J178D01*
G37*
G36*
G01X1723355D02*
X1724661Y1404192D01*
X1725617D01*
G02X1725820Y1403989I0J-203D01*
G01Y1401089D01*
G02X1725617Y1400886I-203J0D01*
G01X1724661D01*
X1724613Y1400916D01*
G02X1724611Y1400918I137J139D01*
G01X1724586Y1400934D01*
X1723346Y1401742D01*
G03X1723161Y1401737I-88J-180D01*
G01X1721863Y1400886D01*
X1720907D01*
G02X1720704Y1401089I0J203D01*
G01Y1403989D01*
G02X1720907Y1404192I203J0D01*
G01X1721868D01*
X1723171Y1403338D01*
G03X1723355Y1403339I91J178D01*
G37*
G36*
G01X1735595D02*
X1736901Y1404192D01*
X1737857D01*
G02X1738060Y1403989I0J-203D01*
G01Y1401089D01*
G02X1737857Y1400886I-203J0D01*
G01X1736901D01*
X1736853Y1400916D01*
G02X1736851Y1400918I137J139D01*
G01X1736826Y1400934D01*
X1735586Y1401742D01*
G03X1735401Y1401737I-88J-180D01*
G01X1734103Y1400886D01*
X1733147D01*
G02X1732944Y1401089I0J203D01*
G01Y1403989D01*
G02X1733147Y1404192I203J0D01*
G01X1734108D01*
X1735411Y1403338D01*
G03X1735595Y1403339I91J178D01*
G37*
G36*
G01X218956Y1451512D02*
G02X219159Y1451716I203J1D01*
G01X222059D01*
G02X222262Y1451512I-1J-204D01*
G01Y1450556D01*
X222232Y1450508D01*
G02X222230Y1450506I-143J141D01*
G01X222214Y1450481D01*
X221406Y1449241D01*
G03X221411Y1449056I180J-88D01*
G01X222262Y1447758D01*
Y1446802D01*
G02X222059Y1446598I-203J-1D01*
G01X219159D01*
G02X218956Y1446802I1J204D01*
G01Y1447763D01*
X219810Y1449066D01*
G03X219809Y1449250I-178J91D01*
G01X218956Y1450556D01*
Y1451512D01*
G37*
G36*
G01Y1462512D02*
G02X219159Y1462716I203J1D01*
G01X222059D01*
G02X222262Y1462512I-1J-204D01*
G01Y1461556D01*
X222232Y1461508D01*
G02X222230Y1461506I-143J141D01*
G01X222214Y1461481D01*
X221406Y1460241D01*
G03X221411Y1460056I180J-88D01*
G01X222262Y1458758D01*
Y1457802D01*
G02X222059Y1457598I-203J-1D01*
G01X219159D01*
G02X218956Y1457802I1J204D01*
G01Y1458763D01*
X219810Y1460066D01*
G03X219809Y1460250I-178J91D01*
G01X218956Y1461556D01*
Y1462512D01*
G37*
G36*
G01X208954Y1643834D02*
G02X209256Y1644136I302J0D01*
G01X261611D01*
G02X261912Y1643834I-1J-302D01*
G01Y1642872D01*
Y1552470D01*
X261722Y1552280D01*
X208952D01*
Y1642872D01*
X208954D01*
Y1643834D01*
G37*
G36*
G01X1232576D02*
G02X1232878Y1644136I302J0D01*
G01X1285233D01*
G02X1285534Y1643834I-1J-302D01*
G01Y1643226D01*
Y1552461D01*
X1285353Y1552280D01*
X1232574D01*
Y1643226D01*
X1232576D01*
Y1643834D01*
G37*
G36*
G01X1579032D02*
G02X1579335Y1644136I303J-1D01*
G01X1631688D01*
G02X1631990Y1643834I0J-302D01*
G01Y1643174D01*
X1631992D01*
Y1552573D01*
X1631698Y1552280D01*
X1579032D01*
Y1643174D01*
Y1643834D01*
G37*
G36*
G01X177763Y1512216D02*
X180583D01*
G02X180786Y1512014I1J-202D01*
G01Y1511392D01*
G03X180836Y1511260I200J0D01*
G02Y1508348I-1664J-1456D01*
G03X180786Y1508216I150J-132D01*
G01Y1506273D01*
G03X180836Y1506141I200J0D01*
G02Y1503229I-1664J-1456D01*
G03X180786Y1503097I150J-132D01*
G01Y1502476D01*
G02X180583Y1502274I-203J1D01*
G01X177763D01*
G02X177560Y1502476I-1J202D01*
G01Y1503097D01*
G03X177510Y1503229I-200J0D01*
G02Y1506141I1664J1456D01*
G03X177560Y1506273I-150J132D01*
G01Y1508216D01*
G03X177510Y1508348I-200J0D01*
G02Y1511260I1664J1456D01*
G03X177560Y1511392I-150J132D01*
G01Y1512014D01*
G02X177763Y1512216I203J-1D01*
G37*
G36*
G01X350991D02*
X353811D01*
G02X354014Y1512014I1J-202D01*
G01Y1511392D01*
G03X354064Y1511260I200J0D01*
G02Y1508348I-1664J-1456D01*
G03X354014Y1508216I150J-132D01*
G01Y1506273D01*
G03X354064Y1506141I200J0D01*
G02Y1503229I-1664J-1456D01*
G03X354014Y1503097I150J-132D01*
G01Y1502476D01*
G02X353811Y1502274I-203J1D01*
G01X350991D01*
G02X350788Y1502476I-1J202D01*
G01Y1503097D01*
G03X350738Y1503229I-200J0D01*
G02Y1506141I1664J1456D01*
G03X350788Y1506273I-150J132D01*
G01Y1508216D01*
G03X350738Y1508348I-200J0D01*
G02Y1511260I1664J1456D01*
G03X350788Y1511392I-150J132D01*
G01Y1512014D01*
G02X350991Y1512216I203J-1D01*
G37*
G36*
G01X186425Y1516546D02*
X189245D01*
G02X189448Y1516344I1J-202D01*
G01Y1515722D01*
G03X189498Y1515590I200J0D01*
G02Y1512678I-1664J-1456D01*
G03X189448Y1512546I150J-132D01*
G01Y1510604D01*
G03X189498Y1510472I200J0D01*
G02Y1507560I-1664J-1456D01*
G03X189448Y1507428I150J-132D01*
G01Y1506806D01*
G02X189245Y1506604I-203J1D01*
G01X186425D01*
G02X186222Y1506806I-1J202D01*
G01Y1507428D01*
G03X186172Y1507560I-200J0D01*
G02Y1510472I1664J1456D01*
G03X186222Y1510604I-150J132D01*
G01Y1512546D01*
G03X186172Y1512678I-200J0D01*
G02Y1515590I1664J1456D01*
G03X186222Y1515722I-150J132D01*
G01Y1516344D01*
G02X186425Y1516546I203J-1D01*
G37*
G36*
G01X359653D02*
X362473D01*
G02X362676Y1516344I1J-202D01*
G01Y1515722D01*
G03X362726Y1515590I200J0D01*
G02Y1512678I-1664J-1456D01*
G03X362676Y1512546I150J-132D01*
G01Y1510604D01*
G03X362726Y1510472I200J0D01*
G02Y1507560I-1664J-1456D01*
G03X362676Y1507428I150J-132D01*
G01Y1506806D01*
G02X362473Y1506604I-203J1D01*
G01X359653D01*
G02X359450Y1506806I-1J202D01*
G01Y1507428D01*
G03X359400Y1507560I-200J0D01*
G02Y1510472I1664J1456D01*
G03X359450Y1510604I-150J132D01*
G01Y1512546D01*
G03X359400Y1512678I-200J0D01*
G02Y1515590I1664J1456D01*
G03X359450Y1515722I-150J132D01*
G01Y1516344D01*
G02X359653Y1516546I203J-1D01*
G37*
G36*
G01X177763Y1568516D02*
X180583D01*
G02X180786Y1568313I0J-203D01*
G01Y1567691D01*
G03X180836Y1567559I200J0D01*
G02Y1564647I-1664J-1456D01*
G03X180786Y1564515I150J-132D01*
G01Y1562573D01*
G03X180836Y1562441I200J0D01*
G02Y1559529I-1664J-1456D01*
G03X180786Y1559397I150J-132D01*
G01Y1558775D01*
G02X180583Y1558572I-203J0D01*
G01X177763D01*
G02X177560Y1558775I0J203D01*
G01Y1559397D01*
G03X177510Y1559529I-200J0D01*
G02Y1562441I1664J1456D01*
G03X177560Y1562573I-150J132D01*
G01Y1564515D01*
G03X177510Y1564647I-200J0D01*
G02Y1567559I1664J1456D01*
G03X177560Y1567691I-150J132D01*
G01Y1568313D01*
G02X177763Y1568516I203J0D01*
G37*
G36*
G01X350991D02*
X353811D01*
G02X354014Y1568313I0J-203D01*
G01Y1567691D01*
G03X354064Y1567559I200J0D01*
G02Y1564647I-1664J-1456D01*
G03X354014Y1564515I150J-132D01*
G01Y1562573D01*
G03X354064Y1562441I200J0D01*
G02Y1559529I-1664J-1456D01*
G03X354014Y1559397I150J-132D01*
G01Y1558775D01*
G02X353811Y1558572I-203J0D01*
G01X350991D01*
G02X350788Y1558775I0J203D01*
G01Y1559397D01*
G03X350738Y1559529I-200J0D01*
G02Y1562441I1664J1456D01*
G03X350788Y1562573I-150J132D01*
G01Y1564515D01*
G03X350738Y1564647I-200J0D01*
G02Y1567559I1664J1456D01*
G03X350788Y1567691I-150J132D01*
G01Y1568313D01*
G02X350991Y1568516I203J0D01*
G37*
G36*
G01X186425Y1572846D02*
X189245D01*
G02X189448Y1572644I1J-202D01*
G01Y1572022D01*
G03X189498Y1571890I200J0D01*
G02Y1568978I-1664J-1456D01*
G03X189448Y1568846I150J-132D01*
G01Y1566903D01*
G03X189498Y1566771I200J0D01*
G02Y1563859I-1664J-1456D01*
G03X189448Y1563727I150J-132D01*
G01Y1563106D01*
G02X189245Y1562904I-203J1D01*
G01X186425D01*
G02X186222Y1563106I-1J202D01*
G01Y1563727D01*
G03X186172Y1563859I-200J0D01*
G02Y1566771I1664J1456D01*
G03X186222Y1566903I-150J132D01*
G01Y1568846D01*
G03X186172Y1568978I-200J0D01*
G02Y1571890I1664J1456D01*
G03X186222Y1572022I-150J132D01*
G01Y1572644D01*
G02X186425Y1572846I203J-1D01*
G37*
G36*
G01X359653D02*
X362473D01*
G02X362676Y1572644I1J-202D01*
G01Y1572022D01*
G03X362726Y1571890I200J0D01*
G02Y1568978I-1664J-1456D01*
G03X362676Y1568846I150J-132D01*
G01Y1566903D01*
G03X362726Y1566771I200J0D01*
G02Y1563859I-1664J-1456D01*
G03X362676Y1563727I150J-132D01*
G01Y1563106D01*
G02X362473Y1562904I-203J1D01*
G01X359653D01*
G02X359450Y1563106I-1J202D01*
G01Y1563727D01*
G03X359400Y1563859I-200J0D01*
G02Y1566771I1664J1456D01*
G03X359450Y1566903I-150J132D01*
G01Y1568846D01*
G03X359400Y1568978I-200J0D01*
G02Y1571890I1664J1456D01*
G03X359450Y1572022I-150J132D01*
G01Y1572644D01*
G02X359653Y1572846I203J-1D01*
G37*
G36*
G01X177763Y1583870D02*
X180583D01*
G02X180786Y1583667I0J-203D01*
G01Y1583045D01*
G03X180836Y1582913I200J0D01*
G02Y1580001I-1664J-1456D01*
G03X180786Y1579869I150J-132D01*
G01Y1577927D01*
G03X180836Y1577795I200J0D01*
G02Y1574883I-1664J-1456D01*
G03X180786Y1574751I150J-132D01*
G01Y1574129D01*
G02X180583Y1573926I-203J0D01*
G01X177763D01*
G02X177560Y1574129I0J203D01*
G01Y1574751D01*
G03X177510Y1574883I-200J0D01*
G02Y1577795I1664J1456D01*
G03X177560Y1577927I-150J132D01*
G01Y1579869D01*
G03X177510Y1580001I-200J0D01*
G02Y1582913I1664J1456D01*
G03X177560Y1583045I-150J132D01*
G01Y1583667D01*
G02X177763Y1583870I203J0D01*
G37*
G36*
G01X956709Y1489429D02*
X1046333D01*
G02X1047217Y1489063I0J-1251D01*
G01X1048852Y1487428D01*
G02X1049218Y1486544I-885J-884D01*
G01Y1451702D01*
G02X1048852Y1450818I-1251J0D01*
G01X1046676Y1448642D01*
G02X1045792Y1448276I-884J885D01*
G01X929991D01*
G02X929107Y1448642I0J1251D01*
G01X927428Y1450321D01*
G02X927062Y1451205I885J884D01*
G01Y1481492D01*
G02X927428Y1482376I1251J0D01*
G01X929075Y1484023D01*
G02X929959Y1484389I884J-885D01*
G01X952618D01*
G03X952760Y1484448I0J200D01*
G01X953133Y1484821D01*
G03X953192Y1484963I-141J142D01*
G01Y1485912D01*
G02X953558Y1486796I1251J0D01*
G01X955825Y1489063D01*
G02X956709Y1489429I884J-885D01*
G37*
G36*
G01X404759Y1350874D02*
X408159D01*
G02Y1347270I0J-1802D01*
G01X404759D01*
G02Y1350874I0J1802D01*
G37*
G36*
G01X402489Y1419078D02*
X405889D01*
G02Y1415472I0J-1803D01*
G01X402489D01*
G02Y1419078I0J1803D01*
G37*
G36*
G01X1443660Y1308896D02*
X1440260D01*
G02Y1312500I0J1802D01*
G01X1443660D01*
G02Y1308896I0J-1802D01*
G37*
G36*
G01X970197Y665850D02*
X966797D01*
G02Y669456I0J1803D01*
G01X970197D01*
G02Y665850I0J-1803D01*
G37*
G36*
G01X501495Y772260D02*
X504895D01*
G02Y768654I0J-1803D01*
G01X501495D01*
G02Y772260I0J1803D01*
G37*
G36*
G01X909508Y623418D02*
X912908D01*
G02Y619814I0J-1802D01*
G01X909508D01*
G02Y623418I0J1802D01*
G37*
G36*
G01X900676Y623338D02*
X904076D01*
G02Y619734I0J-1802D01*
G01X900676D01*
G02Y623338I0J1802D01*
G37*
G36*
G01X526264Y665858D02*
X529664D01*
G02Y662254I0J-1802D01*
G01X526264D01*
G02Y665858I0J1802D01*
G37*
G36*
G01X534264Y663358D02*
X537664D01*
G02Y659754I0J-1802D01*
G01X534264D01*
G02Y663358I0J1802D01*
G37*
G36*
G01X538985Y734790D02*
X535585D01*
G02Y738396I0J1803D01*
G01X538985D01*
G02Y734790I0J-1803D01*
G37*
G36*
G01X530985Y739790D02*
X527585D01*
G02Y743396I0J1803D01*
G01X530985D01*
G02Y739790I0J-1803D01*
G37*
G36*
G01X517731Y742874D02*
X521131D01*
G02Y739268I0J-1803D01*
G01X517731D01*
G02Y742874I0J1803D01*
G37*
G36*
G01X511724Y739232D02*
X508324D01*
G02Y742838I0J1803D01*
G01X511724D01*
G02Y739232I0J-1803D01*
G37*
G36*
G01X415777Y306272D02*
X419177D01*
G02Y302668I0J-1802D01*
G01X415777D01*
G02Y306272I0J1802D01*
G37*
G36*
G01X423651Y309272D02*
X427051D01*
G02Y305668I0J-1802D01*
G01X423651D01*
G02Y309272I0J1802D01*
G37*
G36*
G01X431525Y306272D02*
X434925D01*
G02Y302668I0J-1802D01*
G01X431525D01*
G02Y306272I0J1802D01*
G37*
G36*
G01X434924Y368506D02*
X431524D01*
G02Y372112I0J1803D01*
G01X434924D01*
G02Y368506I0J-1803D01*
G37*
G36*
G01X183922Y545543D02*
Y541581D01*
G02X183719Y541378I-203J0D01*
G01X179069D01*
G02X178866Y541581I0J203D01*
G01Y545543D01*
G02X179069Y545746I203J0D01*
G01X183719D01*
G02X183922Y545543I0J-203D01*
G37*
G36*
G01X641008D02*
Y541581D01*
G02X640805Y541378I-203J0D01*
G01X636155D01*
G02X635952Y541581I0J203D01*
G01Y545543D01*
G02X636155Y545746I203J0D01*
G01X640805D01*
G02X641008Y545543I0J-203D01*
G37*
G36*
G01X1555182D02*
Y541581D01*
G02X1554979Y541378I-203J0D01*
G01X1550329D01*
G02X1550126Y541581I0J203D01*
G01Y545543D01*
G02X1550329Y545746I203J0D01*
G01X1554979D01*
G02X1555182Y545543I0J-203D01*
G37*
G36*
G01X1657024Y459969D02*
Y463931D01*
G02X1657226Y464134I202J1D01*
G01X1661876D01*
G02X1662078Y463931I-1J-203D01*
G01Y459969D01*
G02X1661876Y459766I-202J-1D01*
G01X1657226D01*
G02X1657024Y459969I1J203D01*
G37*
G36*
G01X285764D02*
Y463931D01*
G02X285966Y464134I202J1D01*
G01X290616D01*
G02X290818Y463931I-1J-203D01*
G01Y459969D01*
G02X290616Y459766I-202J-1D01*
G01X285966D01*
G02X285764Y459969I1J203D01*
G37*
G36*
G01X742850D02*
Y463931D01*
G02X743052Y464134I202J1D01*
G01X747702D01*
G02X747904Y463931I-1J-203D01*
G01Y459969D01*
G02X747702Y459766I-202J-1D01*
G01X743052D01*
G02X742850Y459969I1J203D01*
G37*
G36*
G01X1098094Y545543D02*
Y541581D01*
G02X1097892Y541378I-202J-1D01*
G01X1093242D01*
G02X1093040Y541581I1J203D01*
G01Y545543D01*
G02X1093242Y545746I202J1D01*
G01X1097892D01*
G02X1098094Y545543I-1J-203D01*
G37*
G36*
G01X26772Y1559218D02*
X20472D01*
G02Y1575428I0J8105D01*
G01X26772D01*
G02Y1559218I0J-8105D01*
G37*
G36*
G01X55129Y1486992D02*
X53545D01*
G02X53342Y1487195I0J203D01*
G01Y1488796D01*
G02X53545Y1488998I203J-1D01*
G01X55129D01*
G02X55332Y1488796I1J-202D01*
G01Y1487195D01*
G02X55129Y1486992I-203J0D01*
G37*
G36*
G01X53561Y1484862D02*
X55145D01*
G02X55348Y1484660I1J-202D01*
G01Y1483059D01*
G02X55145Y1482856I-203J0D01*
G01X53561D01*
G02X53358Y1483059I0J203D01*
G01Y1484660D01*
G02X53561Y1484862I203J-1D01*
G37*
G36*
G01X414680Y1524086D02*
Y1522502D01*
G02X414478Y1522300I-202J0D01*
G01X412877D01*
G02X412674Y1522502I-1J202D01*
G01Y1524086D01*
G02X412877Y1524288I203J-1D01*
G01X414478D01*
G02X414680Y1524086I0J-202D01*
G37*
G36*
G01X416224Y1522506D02*
Y1524090D01*
G02X416427Y1524292I203J-1D01*
G01X418028D01*
G02X418230Y1524090I0J-202D01*
G01Y1522506D01*
G02X418028Y1522304I-202J0D01*
G01X416427D01*
G02X416224Y1522506I-1J202D01*
G37*
G36*
G01X951084Y899100D02*
Y900684D01*
G02X951287Y900886I203J-1D01*
G01X952888D01*
G02X953090Y900684I0J-202D01*
G01Y899100D01*
G02X952888Y898898I-202J0D01*
G01X951287D01*
G02X951084Y899100I-1J202D01*
G37*
G36*
G01X948894Y900680D02*
Y899096D01*
G02X948691Y898894I-203J1D01*
G01X947090D01*
G02X946888Y899096I0J202D01*
G01Y900680D01*
G02X947090Y900882I202J0D01*
G01X948691D01*
G02X948894Y900680I1J-202D01*
G37*
G36*
G01X1770223Y911218D02*
X1768153D01*
G02X1767652Y911720I1J502D01*
G01Y914120D01*
G02X1768155Y914622I503J-1D01*
G01X1770225D01*
G02X1770726Y914120I-1J-502D01*
G01Y911720D01*
G02X1770223Y911218I-503J1D01*
G37*
G36*
G01X397523Y778618D02*
X395453D01*
G02X394952Y779120I1J502D01*
G01Y781520D01*
G02X395455Y782022I503J-1D01*
G01X397525D01*
G02X398026Y781520I-1J-502D01*
G01Y779120D01*
G02X397523Y778618I-503J1D01*
G37*
G36*
G01X216125Y1441832D02*
X219525D01*
G02Y1438226I0J-1803D01*
G01X216125D01*
G02Y1441832I0J1803D01*
G37*
G36*
G01X221043Y1426712D02*
X222045D01*
G02X222546Y1426210I-1J-502D01*
G01Y1425418D01*
G02X222043Y1424916I-503J1D01*
G01X221041D01*
G02X220540Y1425418I1J502D01*
G01Y1426210D01*
G02X221043Y1426712I503J-1D01*
G37*
G36*
G01Y1429862D02*
X222045D01*
G02X222546Y1429360I-1J-502D01*
G01Y1428568D01*
G02X222043Y1428066I-503J1D01*
G01X221041D01*
G02X220540Y1428568I1J502D01*
G01Y1429360D01*
G02X221043Y1429862I503J-1D01*
G37*
G36*
G01Y1433012D02*
X222045D01*
G02X222546Y1432510I-1J-502D01*
G01Y1431718D01*
G02X222043Y1431216I-503J1D01*
G01X221041D01*
G02X220540Y1431718I1J502D01*
G01Y1432510D01*
G02X221043Y1433012I503J-1D01*
G37*
G36*
G01X213691Y1433110D02*
X214691D01*
G02X215194Y1432607I0J-503D01*
G01Y1431815D01*
G02X214691Y1431312I-503J0D01*
G01X213691D01*
G02X213188Y1431815I0J503D01*
G01Y1432607D01*
G02X213691Y1433110I503J0D01*
G37*
G36*
G01Y1429960D02*
X214691D01*
G02X215194Y1429457I0J-503D01*
G01Y1428665D01*
G02X214691Y1428162I-503J0D01*
G01X213691D01*
G02X213188Y1428665I0J503D01*
G01Y1429457D01*
G02X213691Y1429960I503J0D01*
G37*
G36*
G01Y1426810D02*
X214691D01*
G02X215194Y1426307I0J-503D01*
G01Y1425515D01*
G02X214691Y1425012I-503J0D01*
G01X213691D01*
G02X213188Y1425515I0J503D01*
G01Y1426307D01*
G02X213691Y1426810I503J0D01*
G37*
G36*
G01X418339Y1502078D02*
X419341D01*
G02X419842Y1501576I-1J-502D01*
G01Y1500784D01*
G02X419339Y1500282I-503J1D01*
G01X418337D01*
G02X417836Y1500784I1J502D01*
G01Y1501576D01*
G02X418339Y1502078I503J-1D01*
G37*
G36*
G01Y1498928D02*
X419341D01*
G02X419842Y1498426I-1J-502D01*
G01Y1497634D01*
G02X419339Y1497132I-503J1D01*
G01X418337D01*
G02X417836Y1497634I1J502D01*
G01Y1498426D01*
G02X418339Y1498928I503J-1D01*
G37*
G36*
G01Y1495778D02*
X419341D01*
G02X419842Y1495276I-1J-502D01*
G01Y1494484D01*
G02X419339Y1493982I-503J1D01*
G01X418337D01*
G02X417836Y1494484I1J502D01*
G01Y1495276D01*
G02X418339Y1495778I503J-1D01*
G37*
G36*
G01X410987Y1495876D02*
X411987D01*
G02X412490Y1495373I0J-503D01*
G01Y1494581D01*
G02X411987Y1494078I-503J0D01*
G01X410987D01*
G02X410484Y1494581I0J503D01*
G01Y1495373D01*
G02X410987Y1495876I503J0D01*
G37*
G36*
G01Y1502176D02*
X411987D01*
G02X412490Y1501673I0J-503D01*
G01Y1500881D01*
G02X411987Y1500378I-503J0D01*
G01X410987D01*
G02X410484Y1500881I0J503D01*
G01Y1501673D01*
G02X410987Y1502176I503J0D01*
G37*
G36*
G01Y1499026D02*
X411987D01*
G02X412490Y1498523I0J-503D01*
G01Y1497731D01*
G02X411987Y1497228I-503J0D01*
G01X410987D01*
G02X410484Y1497731I0J503D01*
G01Y1498523D01*
G02X410987Y1499026I503J0D01*
G37*
G36*
G01X392618Y1519199D02*
Y1519993D01*
G02X393120Y1520494I502J-1D01*
G01X394120D01*
G02X394622Y1519991I-1J-503D01*
G01Y1519197D01*
G02X394120Y1518696I-502J1D01*
G01X393120D01*
G02X392618Y1519199I1J503D01*
G37*
G36*
G01Y1512899D02*
Y1513693D01*
G02X393120Y1514194I502J-1D01*
G01X394120D01*
G02X394622Y1513691I-1J-503D01*
G01Y1512897D01*
G02X394120Y1512396I-502J1D01*
G01X393120D01*
G02X392618Y1512899I1J503D01*
G37*
G36*
G01X56721Y1509320D02*
X58085D01*
G02X58586Y1508818I-1J-502D01*
G01Y1506905D01*
G02X58083Y1506402I-503J0D01*
G01X56721D01*
G02X56218Y1506905I0J503D01*
G01Y1508818D01*
G02X56721Y1509320I503J-1D01*
G37*
G36*
G01X413753Y1518690D02*
X417153D01*
G02Y1515084I0J-1803D01*
G01X413753D01*
G02Y1518690I0J1803D01*
G37*
G36*
G01X417334Y1475298D02*
X413934D01*
G02Y1478902I0J1802D01*
G01X417334D01*
G02Y1475298I0J-1802D01*
G37*
G36*
G01X919628Y334530D02*
X916228D01*
G02Y338136I0J1803D01*
G01X919628D01*
G02Y334530I0J-1803D01*
G37*
G36*
G01X23437Y1526088D02*
X22073D01*
G02X21572Y1526590I1J502D01*
G01Y1528503D01*
G02X22075Y1529006I503J0D01*
G01X23437D01*
G02X23940Y1528503I0J-503D01*
G01Y1526590D01*
G02X23437Y1526088I-503J1D01*
G37*
G36*
G01X1799392Y824566D02*
Y820688D01*
G02X1799190Y820486I-202J0D01*
G01X1793686D01*
G02X1793484Y820688I0J202D01*
G01Y824566D01*
G02X1793686Y824768I202J0D01*
G01X1799190D01*
G02X1799392Y824566I0J-202D01*
G37*
G36*
G01X549004Y791831D02*
Y786827D01*
G02X548802Y786624I-202J-1D01*
G01X546126D01*
G02X545924Y786827I1J203D01*
G01Y791831D01*
G02X546126Y792034I202J1D01*
G01X548802D01*
G02X549004Y791831I-1J-203D01*
G37*
G36*
G01X1784668Y819893D02*
Y817496D01*
G02X1784465Y817294I-203J1D01*
G01X1782468D01*
G02X1782266Y817496I0J202D01*
G01Y819893D01*
G02X1782468Y820096I202J1D01*
G01X1784465D01*
G02X1784668Y819893I0J-203D01*
G37*
G36*
G01X1513762Y919220D02*
Y914177D01*
G02X1513560Y913974I-202J-1D01*
G01X1510881D01*
G02X1510678Y914177I0J203D01*
G01Y919220D01*
G02X1510881Y919422I203J-1D01*
G01X1513560D01*
G02X1513762Y919220I0J-202D01*
G37*
G36*
G01X1784714Y827793D02*
Y825611D01*
G02X1784511Y825408I-203J0D01*
G01X1782426D01*
G02X1782224Y825611I1J203D01*
G01Y827793D01*
G02X1782426Y827996I202J1D01*
G01X1784511D01*
G02X1784714Y827793I0J-203D01*
G37*
G36*
G01X57346Y103835D02*
Y107897D01*
G02X57548Y108100I202J1D01*
G01X62398D01*
G02X62600Y107897I-1J-203D01*
G01Y103835D01*
G02X62398Y103632I-202J-1D01*
G01X57548D01*
G02X57346Y103835I1J203D01*
G37*
G36*
G01Y110922D02*
Y114984D01*
G02X57548Y115186I202J0D01*
G01X62398D01*
G02X62600Y114984I0J-202D01*
G01Y110922D01*
G02X62398Y110720I-202J0D01*
G01X57548D01*
G02X57346Y110922I0J202D01*
G37*
G36*
G01Y118009D02*
Y122071D01*
G02X57548Y122274I202J1D01*
G01X62398D01*
G02X62600Y122071I-1J-203D01*
G01Y118009D01*
G02X62398Y117806I-202J-1D01*
G01X57548D01*
G02X57346Y118009I1J203D01*
G37*
G36*
G01Y125095D02*
Y129157D01*
G02X57548Y129360I202J1D01*
G01X62398D01*
G02X62600Y129157I-1J-203D01*
G01Y125095D01*
G02X62398Y124892I-202J-1D01*
G01X57548D01*
G02X57346Y125095I1J203D01*
G37*
G36*
G01Y132182D02*
Y136244D01*
G02X57548Y136446I202J0D01*
G01X62398D01*
G02X62600Y136244I0J-202D01*
G01Y132182D01*
G02X62398Y131980I-202J0D01*
G01X57548D01*
G02X57346Y132182I0J202D01*
G37*
G36*
G01X66992Y1595799D02*
Y1620437D01*
G02X67346Y1621291I1210J-1D01*
G01X67591Y1621536D01*
G02X68445Y1621890I854J-854D01*
G01X85058D01*
G02X85913Y1621536I-1J-1213D01*
G01X85918Y1621531D01*
Y1595799D01*
G02X85563Y1594944I-1208J0D01*
G01X85378Y1594759D01*
G02X84524Y1594406I-855J858D01*
G01X68386D01*
G02X67531Y1594760I1J1211D01*
G01X67346Y1594945D01*
G02X66992Y1595799I853J854D01*
G37*
G36*
G01X719156Y110922D02*
Y114984D01*
G02X719359Y115186I203J-1D01*
G01X724209D01*
G02X724412Y114984I1J-202D01*
G01Y110922D01*
G02X724209Y110720I-203J1D01*
G01X719359D01*
G02X719156Y110922I-1J202D01*
G37*
G36*
G01Y103835D02*
Y107897D01*
G02X719359Y108100I203J0D01*
G01X724209D01*
G02X724412Y107897I0J-203D01*
G01Y103835D01*
G02X724209Y103632I-203J0D01*
G01X719359D01*
G02X719156Y103835I0J203D01*
G37*
G36*
G01Y132182D02*
Y136244D01*
G02X719359Y136446I203J-1D01*
G01X724209D01*
G02X724412Y136244I1J-202D01*
G01Y132182D01*
G02X724209Y131980I-203J1D01*
G01X719359D01*
G02X719156Y132182I-1J202D01*
G37*
G36*
G01Y125095D02*
Y129157D01*
G02X719359Y129360I203J0D01*
G01X724209D01*
G02X724412Y129157I0J-203D01*
G01Y125095D01*
G02X724209Y124892I-203J0D01*
G01X719359D01*
G02X719156Y125095I0J203D01*
G37*
G36*
G01Y118009D02*
Y122071D01*
G02X719359Y122274I203J0D01*
G01X724209D01*
G02X724412Y122071I0J-203D01*
G01Y118009D01*
G02X724209Y117806I-203J0D01*
G01X719359D01*
G02X719156Y118009I0J203D01*
G37*
G36*
G01X742850Y467054D02*
Y471016D01*
G02X743052Y471218I202J0D01*
G01X747702D01*
G02X747904Y471016I0J-202D01*
G01Y467054D01*
G02X747702Y466852I-202J0D01*
G01X743052D01*
G02X742850Y467054I0J202D01*
G37*
G36*
G01Y474141D02*
Y478103D01*
G02X743052Y478306I202J1D01*
G01X747702D01*
G02X747904Y478103I-1J-203D01*
G01Y474141D01*
G02X747702Y473938I-202J-1D01*
G01X743052D01*
G02X742850Y474141I1J203D01*
G37*
G36*
G01Y481228D02*
Y485190D01*
G02X743052Y485392I202J0D01*
G01X747702D01*
G02X747904Y485190I0J-202D01*
G01Y481228D01*
G02X747702Y481026I-202J0D01*
G01X743052D01*
G02X742850Y481228I0J202D01*
G37*
G36*
G01Y488314D02*
Y492276D01*
G02X743052Y492478I202J0D01*
G01X747702D01*
G02X747904Y492276I0J-202D01*
G01Y488314D01*
G02X747702Y488112I-202J0D01*
G01X743052D01*
G02X742850Y488314I0J202D01*
G37*
G36*
G01Y518275D02*
Y522237D01*
G02X743052Y522440I202J1D01*
G01X747702D01*
G02X747904Y522237I-1J-203D01*
G01Y518275D01*
G02X747702Y518072I-202J-1D01*
G01X743052D01*
G02X742850Y518275I1J203D01*
G37*
G36*
G01Y511188D02*
Y515150D01*
G02X743052Y515352I202J0D01*
G01X747702D01*
G02X747904Y515150I0J-202D01*
G01Y511188D01*
G02X747702Y510986I-202J0D01*
G01X743052D01*
G02X742850Y511188I0J202D01*
G37*
G36*
G01Y532448D02*
Y536410D01*
G02X743052Y536612I202J0D01*
G01X747702D01*
G02X747904Y536410I0J-202D01*
G01Y532448D01*
G02X747702Y532246I-202J0D01*
G01X743052D01*
G02X742850Y532448I0J202D01*
G37*
G36*
G01Y525362D02*
Y529324D01*
G02X743052Y529526I202J0D01*
G01X747702D01*
G02X747904Y529324I0J-202D01*
G01Y525362D01*
G02X747702Y525160I-202J0D01*
G01X743052D01*
G02X742850Y525362I0J202D01*
G37*
G36*
G01Y561228D02*
Y565190D01*
G02X743052Y565392I202J0D01*
G01X747702D01*
G02X747904Y565190I0J-202D01*
G01Y561228D01*
G02X747702Y561026I-202J0D01*
G01X743052D01*
G02X742850Y561228I0J202D01*
G37*
G36*
G01Y568314D02*
Y572276D01*
G02X743052Y572478I202J0D01*
G01X747702D01*
G02X747904Y572276I0J-202D01*
G01Y568314D01*
G02X747702Y568112I-202J0D01*
G01X743052D01*
G02X742850Y568314I0J202D01*
G37*
G36*
G01Y575401D02*
Y579363D01*
G02X743052Y579566I202J1D01*
G01X747702D01*
G02X747904Y579363I-1J-203D01*
G01Y575401D01*
G02X747702Y575198I-202J-1D01*
G01X743052D01*
G02X742850Y575401I1J203D01*
G37*
G36*
G01Y582488D02*
Y586450D01*
G02X743052Y586652I202J0D01*
G01X747702D01*
G02X747904Y586450I0J-202D01*
G01Y582488D01*
G02X747702Y582286I-202J0D01*
G01X743052D01*
G02X742850Y582488I0J202D01*
G37*
G36*
G01Y589574D02*
Y593536D01*
G02X743052Y593738I202J0D01*
G01X747702D01*
G02X747904Y593536I0J-202D01*
G01Y589574D01*
G02X747702Y589372I-202J0D01*
G01X743052D01*
G02X742850Y589574I0J202D01*
G37*
G36*
G01Y596661D02*
Y600623D01*
G02X743052Y600826I202J1D01*
G01X747702D01*
G02X747904Y600623I-1J-203D01*
G01Y596661D01*
G02X747702Y596458I-202J-1D01*
G01X743052D01*
G02X742850Y596661I1J203D01*
G37*
G36*
G01Y603747D02*
Y607709D01*
G02X743052Y607912I202J1D01*
G01X747702D01*
G02X747904Y607709I-1J-203D01*
G01Y603747D01*
G02X747702Y603544I-202J-1D01*
G01X743052D01*
G02X742850Y603747I1J203D01*
G37*
G36*
G01Y610834D02*
Y614796D01*
G02X743052Y614998I202J0D01*
G01X747702D01*
G02X747904Y614796I0J-202D01*
G01Y610834D01*
G02X747702Y610632I-202J0D01*
G01X743052D01*
G02X742850Y610834I0J202D01*
G37*
G36*
G01X159708Y110922D02*
Y114984D01*
G02X159910Y115186I202J0D01*
G01X164760D01*
G02X164962Y114984I0J-202D01*
G01Y110922D01*
G02X164760Y110720I-202J0D01*
G01X159910D01*
G02X159708Y110922I0J202D01*
G37*
G36*
G01Y103835D02*
Y107897D01*
G02X159910Y108100I202J1D01*
G01X164760D01*
G02X164962Y107897I-1J-203D01*
G01Y103835D01*
G02X164760Y103632I-202J-1D01*
G01X159910D01*
G02X159708Y103835I1J203D01*
G37*
G36*
G01Y132182D02*
Y136244D01*
G02X159910Y136446I202J0D01*
G01X164760D01*
G02X164962Y136244I0J-202D01*
G01Y132182D01*
G02X164760Y131980I-202J0D01*
G01X159910D01*
G02X159708Y132182I0J202D01*
G37*
G36*
G01X821518Y110922D02*
Y114984D01*
G02X821721Y115186I203J-1D01*
G01X826571D01*
G02X826774Y114984I1J-202D01*
G01Y110922D01*
G02X826571Y110720I-203J1D01*
G01X821721D01*
G02X821518Y110922I-1J202D01*
G37*
G36*
G01X159708Y125095D02*
Y129157D01*
G02X159910Y129360I202J1D01*
G01X164760D01*
G02X164962Y129157I-1J-203D01*
G01Y125095D01*
G02X164760Y124892I-202J-1D01*
G01X159910D01*
G02X159708Y125095I1J203D01*
G37*
G36*
G01X821518Y103835D02*
Y107897D01*
G02X821721Y108100I203J0D01*
G01X826571D01*
G02X826774Y107897I0J-203D01*
G01Y103835D01*
G02X826571Y103632I-203J0D01*
G01X821721D01*
G02X821518Y103835I0J203D01*
G37*
G36*
G01Y132182D02*
Y136244D01*
G02X821721Y136446I203J-1D01*
G01X826571D01*
G02X826774Y136244I1J-202D01*
G01Y132182D01*
G02X826571Y131980I-203J1D01*
G01X821721D01*
G02X821518Y132182I-1J202D01*
G37*
G36*
G01Y125095D02*
Y129157D01*
G02X821721Y129360I203J0D01*
G01X826571D01*
G02X826774Y129157I0J-203D01*
G01Y125095D01*
G02X826571Y124892I-203J0D01*
G01X821721D01*
G02X821518Y125095I0J203D01*
G37*
G36*
G01X159708Y118009D02*
Y122071D01*
G02X159910Y122274I202J1D01*
G01X164760D01*
G02X164962Y122071I-1J-203D01*
G01Y118009D01*
G02X164760Y117806I-202J-1D01*
G01X159910D01*
G02X159708Y118009I1J203D01*
G37*
G36*
G01X821518D02*
Y122071D01*
G02X821721Y122274I203J0D01*
G01X826571D01*
G02X826774Y122071I0J-203D01*
G01Y118009D01*
G02X826571Y117806I-203J0D01*
G01X821721D01*
G02X821518Y118009I0J203D01*
G37*
G36*
G01X905706Y311200D02*
Y309321D01*
G02X905504Y309118I-202J-1D01*
G01X903897D01*
G02X903694Y309321I0J203D01*
G01Y311200D01*
G02X903897Y311402I203J-1D01*
G01X905504D01*
G02X905706Y311200I0J-202D01*
G37*
G36*
G01X908076Y308031D02*
Y310440D01*
G02X908279Y310642I203J-1D01*
G01X908489D01*
G02X908692Y310440I1J-202D01*
G01Y308031D01*
G02X908489Y307828I-203J0D01*
G01X908279D01*
G02X908076Y308031I0J203D01*
G37*
G36*
G01X906502D02*
Y310440D01*
G02X906705Y310642I203J-1D01*
G01X906915D01*
G02X907118Y310440I1J-202D01*
G01Y308031D01*
G02X906915Y307828I-203J0D01*
G01X906705D01*
G02X906502Y308031I0J203D01*
G37*
G36*
G01X908694Y314061D02*
Y311652D01*
G02X908491Y311450I-203J1D01*
G01X908281D01*
G02X908078Y311652I-1J202D01*
G01Y314061D01*
G02X908281Y314264I203J0D01*
G01X908491D01*
G02X908694Y314061I0J-203D01*
G37*
G36*
G01X907120D02*
Y311652D01*
G02X906917Y311450I-203J1D01*
G01X906707D01*
G02X906504Y311652I-1J202D01*
G01Y314061D01*
G02X906707Y314264I203J0D01*
G01X906917D01*
G02X907120Y314061I0J-203D01*
G37*
G36*
G01X905404Y339384D02*
X903820D01*
G02X903618Y339587I1J203D01*
G01Y341188D01*
G02X903820Y341390I202J0D01*
G01X905404D01*
G02X905606Y341188I0J-202D01*
G01Y339587D01*
G02X905404Y339384I-202J-1D01*
G37*
G36*
G01X903824Y344344D02*
X905408D01*
G02X905610Y344141I-1J-203D01*
G01Y342540D01*
G02X905408Y342338I-202J0D01*
G01X903824D01*
G02X903622Y342540I0J202D01*
G01Y344141D01*
G02X903824Y344344I202J1D01*
G37*
G36*
G01X908904Y339384D02*
X907320D01*
G02X907118Y339587I1J203D01*
G01Y341188D01*
G02X907320Y341390I202J0D01*
G01X908904D01*
G02X909106Y341188I0J-202D01*
G01Y339587D01*
G02X908904Y339384I-202J-1D01*
G37*
G36*
G01X907324Y344344D02*
X908908D01*
G02X909110Y344141I-1J-203D01*
G01Y342540D01*
G02X908908Y342338I-202J0D01*
G01X907324D01*
G02X907122Y342540I0J202D01*
G01Y344141D01*
G02X907324Y344344I202J1D01*
G37*
G36*
G01X927764Y355019D02*
Y352506D01*
G02X927561Y352304I-203J1D01*
G01X924946D01*
G02X924744Y352506I0J202D01*
G01Y355019D01*
G02X924946Y355222I202J1D01*
G01X927561D01*
G02X927764Y355019I0J-203D01*
G37*
G36*
G01X921858D02*
Y352506D01*
G02X921655Y352304I-203J1D01*
G01X919040D01*
G02X918838Y352506I0J202D01*
G01Y355019D01*
G02X919040Y355222I202J1D01*
G01X921655D01*
G02X921858Y355019I0J-203D01*
G37*
G36*
G01X917920D02*
Y352506D01*
G02X917718Y352304I-202J0D01*
G01X915103D01*
G02X914900Y352506I-1J202D01*
G01Y355019D01*
G02X915103Y355222I203J0D01*
G01X917718D01*
G02X917920Y355019I-1J-203D01*
G37*
G36*
G01X183922Y394678D02*
Y390716D01*
G02X183719Y390514I-203J1D01*
G01X179069D01*
G02X178866Y390716I-1J202D01*
G01Y394678D01*
G02X179069Y394880I203J-1D01*
G01X183719D01*
G02X183922Y394678I1J-202D01*
G37*
G36*
G01Y408852D02*
Y404890D01*
G02X183719Y404688I-203J1D01*
G01X179069D01*
G02X178866Y404890I-1J202D01*
G01Y408852D01*
G02X179069Y409054I203J-1D01*
G01X183719D01*
G02X183922Y408852I1J-202D01*
G37*
G36*
G01Y401765D02*
Y397803D01*
G02X183719Y397600I-203J0D01*
G01X179069D01*
G02X178866Y397803I0J203D01*
G01Y401765D01*
G02X179069Y401968I203J0D01*
G01X183719D01*
G02X183922Y401765I0J-203D01*
G37*
G36*
G01Y415938D02*
Y411976D01*
G02X183719Y411774I-203J1D01*
G01X179069D01*
G02X178866Y411976I-1J202D01*
G01Y415938D01*
G02X179069Y416140I203J-1D01*
G01X183719D01*
G02X183922Y415938I1J-202D01*
G37*
G36*
G01Y423024D02*
Y419062D01*
G02X183719Y418860I-203J1D01*
G01X179069D01*
G02X178866Y419062I-1J202D01*
G01Y423024D01*
G02X179069Y423226I203J-1D01*
G01X183719D01*
G02X183922Y423024I1J-202D01*
G37*
G36*
G01Y444284D02*
Y440322D01*
G02X183719Y440120I-203J1D01*
G01X179069D01*
G02X178866Y440322I-1J202D01*
G01Y444284D01*
G02X179069Y444486I203J-1D01*
G01X183719D01*
G02X183922Y444284I1J-202D01*
G37*
G36*
G01Y437198D02*
Y433236D01*
G02X183719Y433034I-203J1D01*
G01X179069D01*
G02X178866Y433236I-1J202D01*
G01Y437198D01*
G02X179069Y437400I203J-1D01*
G01X183719D01*
G02X183922Y437198I1J-202D01*
G37*
G36*
G01Y430111D02*
Y426149D01*
G02X183719Y425946I-203J0D01*
G01X179069D01*
G02X178866Y426149I0J203D01*
G01Y430111D01*
G02X179069Y430314I203J0D01*
G01X183719D01*
G02X183922Y430111I0J-203D01*
G37*
G36*
G01Y473064D02*
Y469102D01*
G02X183719Y468900I-203J1D01*
G01X179069D01*
G02X178866Y469102I-1J202D01*
G01Y473064D01*
G02X179069Y473266I203J-1D01*
G01X183719D01*
G02X183922Y473064I1J-202D01*
G37*
G36*
G01X971518Y110922D02*
Y114984D01*
G02X971721Y115186I203J-1D01*
G01X976571D01*
G02X976774Y114984I1J-202D01*
G01Y110922D01*
G02X976571Y110720I-203J1D01*
G01X971721D01*
G02X971518Y110922I-1J202D01*
G37*
G36*
G01X183922Y487238D02*
Y483276D01*
G02X183719Y483074I-203J1D01*
G01X179069D01*
G02X178866Y483276I-1J202D01*
G01Y487238D01*
G02X179069Y487440I203J-1D01*
G01X183719D01*
G02X183922Y487238I1J-202D01*
G37*
G36*
G01X971518Y103835D02*
Y107897D01*
G02X971721Y108100I203J0D01*
G01X976571D01*
G02X976774Y107897I0J-203D01*
G01Y103835D01*
G02X976571Y103632I-203J0D01*
G01X971721D01*
G02X971518Y103835I0J203D01*
G37*
G36*
G01X183922Y480151D02*
Y476189D01*
G02X183719Y475986I-203J0D01*
G01X179069D01*
G02X178866Y476189I0J203D01*
G01Y480151D01*
G02X179069Y480354I203J0D01*
G01X183719D01*
G02X183922Y480151I0J-203D01*
G37*
G36*
G01X971518Y132182D02*
Y136244D01*
G02X971721Y136446I203J-1D01*
G01X976571D01*
G02X976774Y136244I1J-202D01*
G01Y132182D01*
G02X976571Y131980I-203J1D01*
G01X971721D01*
G02X971518Y132182I-1J202D01*
G37*
G36*
G01Y125095D02*
Y129157D01*
G02X971721Y129360I203J0D01*
G01X976571D01*
G02X976774Y129157I0J-203D01*
G01Y125095D01*
G02X976571Y124892I-203J0D01*
G01X971721D01*
G02X971518Y125095I0J203D01*
G37*
G36*
G01Y118009D02*
Y122071D01*
G02X971721Y122274I203J0D01*
G01X976571D01*
G02X976774Y122071I0J-203D01*
G01Y118009D01*
G02X976571Y117806I-203J0D01*
G01X971721D01*
G02X971518Y118009I0J203D01*
G37*
G36*
G01X1073880Y110922D02*
Y114984D01*
G02X1074083Y115186I203J-1D01*
G01X1078933D01*
G02X1079136Y114984I1J-202D01*
G01Y110922D01*
G02X1078933Y110720I-203J1D01*
G01X1074083D01*
G02X1073880Y110922I-1J202D01*
G37*
G36*
G01Y103835D02*
Y107897D01*
G02X1074083Y108100I203J0D01*
G01X1078933D01*
G02X1079136Y107897I0J-203D01*
G01Y103835D01*
G02X1078933Y103632I-203J0D01*
G01X1074083D01*
G02X1073880Y103835I0J203D01*
G37*
G36*
G01Y132182D02*
Y136244D01*
G02X1074083Y136446I203J-1D01*
G01X1078933D01*
G02X1079136Y136244I1J-202D01*
G01Y132182D01*
G02X1078933Y131980I-203J1D01*
G01X1074083D01*
G02X1073880Y132182I-1J202D01*
G37*
G36*
G01Y125095D02*
Y129157D01*
G02X1074083Y129360I203J0D01*
G01X1078933D01*
G02X1079136Y129157I0J-203D01*
G01Y125095D01*
G02X1078933Y124892I-203J0D01*
G01X1074083D01*
G02X1073880Y125095I0J203D01*
G37*
G36*
G01Y118009D02*
Y122071D01*
G02X1074083Y122274I203J0D01*
G01X1078933D01*
G02X1079136Y122071I0J-203D01*
G01Y118009D01*
G02X1078933Y117806I-203J0D01*
G01X1074083D01*
G02X1073880Y118009I0J203D01*
G37*
G36*
G01X183922Y494324D02*
Y490362D01*
G02X183719Y490160I-203J1D01*
G01X179069D01*
G02X178866Y490362I-1J202D01*
G01Y494324D01*
G02X179069Y494526I203J-1D01*
G01X183719D01*
G02X183922Y494324I1J-202D01*
G37*
G36*
G01X1098094Y394678D02*
Y390716D01*
G02X1097892Y390514I-202J0D01*
G01X1093242D01*
G02X1093040Y390716I0J202D01*
G01Y394678D01*
G02X1093242Y394880I202J0D01*
G01X1097892D01*
G02X1098094Y394678I0J-202D01*
G37*
G36*
G01Y401765D02*
Y397803D01*
G02X1097892Y397600I-202J-1D01*
G01X1093242D01*
G02X1093040Y397803I1J203D01*
G01Y401765D01*
G02X1093242Y401968I202J1D01*
G01X1097892D01*
G02X1098094Y401765I-1J-203D01*
G37*
G36*
G01Y408852D02*
Y404890D01*
G02X1097892Y404688I-202J0D01*
G01X1093242D01*
G02X1093040Y404890I0J202D01*
G01Y408852D01*
G02X1093242Y409054I202J0D01*
G01X1097892D01*
G02X1098094Y408852I0J-202D01*
G37*
G36*
G01Y423024D02*
Y419062D01*
G02X1097892Y418860I-202J0D01*
G01X1093242D01*
G02X1093040Y419062I0J202D01*
G01Y423024D01*
G02X1093242Y423226I202J0D01*
G01X1097892D01*
G02X1098094Y423024I0J-202D01*
G37*
G36*
G01Y415938D02*
Y411976D01*
G02X1097892Y411774I-202J0D01*
G01X1093242D01*
G02X1093040Y411976I0J202D01*
G01Y415938D01*
G02X1093242Y416140I202J0D01*
G01X1097892D01*
G02X1098094Y415938I0J-202D01*
G37*
G36*
G01Y430111D02*
Y426149D01*
G02X1097892Y425946I-202J-1D01*
G01X1093242D01*
G02X1093040Y426149I1J203D01*
G01Y430111D01*
G02X1093242Y430314I202J1D01*
G01X1097892D01*
G02X1098094Y430111I-1J-203D01*
G37*
G36*
G01Y437198D02*
Y433236D01*
G02X1097892Y433034I-202J0D01*
G01X1093242D01*
G02X1093040Y433236I0J202D01*
G01Y437198D01*
G02X1093242Y437400I202J0D01*
G01X1097892D01*
G02X1098094Y437198I0J-202D01*
G37*
G36*
G01Y444284D02*
Y440322D01*
G02X1097892Y440120I-202J0D01*
G01X1093242D01*
G02X1093040Y440322I0J202D01*
G01Y444284D01*
G02X1093242Y444486I202J0D01*
G01X1097892D01*
G02X1098094Y444284I0J-202D01*
G37*
G36*
G01Y473064D02*
Y469102D01*
G02X1097892Y468900I-202J0D01*
G01X1093242D01*
G02X1093040Y469102I0J202D01*
G01Y473064D01*
G02X1093242Y473266I202J0D01*
G01X1097892D01*
G02X1098094Y473064I0J-202D01*
G37*
G36*
G01Y480151D02*
Y476189D01*
G02X1097892Y475986I-202J-1D01*
G01X1093242D01*
G02X1093040Y476189I1J203D01*
G01Y480151D01*
G02X1093242Y480354I202J1D01*
G01X1097892D01*
G02X1098094Y480151I-1J-203D01*
G37*
G36*
G01Y487238D02*
Y483276D01*
G02X1097892Y483074I-202J0D01*
G01X1093242D01*
G02X1093040Y483276I0J202D01*
G01Y487238D01*
G02X1093242Y487440I202J0D01*
G01X1097892D01*
G02X1098094Y487238I0J-202D01*
G37*
G36*
G01Y494324D02*
Y490362D01*
G02X1097892Y490160I-202J0D01*
G01X1093242D01*
G02X1093040Y490362I0J202D01*
G01Y494324D01*
G02X1093242Y494526I202J0D01*
G01X1097892D01*
G02X1098094Y494324I0J-202D01*
G37*
G36*
G01Y517198D02*
Y513236D01*
G02X1097892Y513034I-202J0D01*
G01X1093242D01*
G02X1093040Y513236I0J202D01*
G01Y517198D01*
G02X1093242Y517400I202J0D01*
G01X1097892D01*
G02X1098094Y517198I0J-202D01*
G37*
G36*
G01Y524285D02*
Y520323D01*
G02X1097892Y520120I-202J-1D01*
G01X1093242D01*
G02X1093040Y520323I1J203D01*
G01Y524285D01*
G02X1093242Y524488I202J1D01*
G01X1097892D01*
G02X1098094Y524285I-1J-203D01*
G37*
G36*
G01Y531372D02*
Y527410D01*
G02X1097892Y527208I-202J0D01*
G01X1093242D01*
G02X1093040Y527410I0J202D01*
G01Y531372D01*
G02X1093242Y531574I202J0D01*
G01X1097892D01*
G02X1098094Y531372I0J-202D01*
G37*
G36*
G01Y538458D02*
Y534496D01*
G02X1097892Y534294I-202J0D01*
G01X1093242D01*
G02X1093040Y534496I0J202D01*
G01Y538458D01*
G02X1093242Y538660I202J0D01*
G01X1097892D01*
G02X1098094Y538458I0J-202D01*
G37*
G36*
G01X183922Y524285D02*
Y520323D01*
G02X183719Y520120I-203J0D01*
G01X179069D01*
G02X178866Y520323I0J203D01*
G01Y524285D01*
G02X179069Y524488I203J0D01*
G01X183719D01*
G02X183922Y524285I0J-203D01*
G37*
G36*
G01Y517198D02*
Y513236D01*
G02X183719Y513034I-203J1D01*
G01X179069D01*
G02X178866Y513236I-1J202D01*
G01Y517198D01*
G02X179069Y517400I203J-1D01*
G01X183719D01*
G02X183922Y517198I1J-202D01*
G37*
G36*
G01Y531372D02*
Y527410D01*
G02X183719Y527208I-203J1D01*
G01X179069D01*
G02X178866Y527410I-1J202D01*
G01Y531372D01*
G02X179069Y531574I203J-1D01*
G01X183719D01*
G02X183922Y531372I1J-202D01*
G37*
G36*
G01Y538458D02*
Y534496D01*
G02X183719Y534294I-203J1D01*
G01X179069D01*
G02X178866Y534496I-1J202D01*
G01Y538458D01*
G02X179069Y538660I203J-1D01*
G01X183719D01*
G02X183922Y538458I1J-202D01*
G37*
G36*
G01X1176242Y110922D02*
Y114984D01*
G02X1176445Y115186I203J-1D01*
G01X1181295D01*
G02X1181498Y114984I1J-202D01*
G01Y110922D01*
G02X1181295Y110720I-203J1D01*
G01X1176445D01*
G02X1176242Y110922I-1J202D01*
G37*
G36*
G01Y103835D02*
Y107897D01*
G02X1176445Y108100I203J0D01*
G01X1181295D01*
G02X1181498Y107897I0J-203D01*
G01Y103835D01*
G02X1181295Y103632I-203J0D01*
G01X1176445D01*
G02X1176242Y103835I0J203D01*
G37*
G36*
G01Y132182D02*
Y136244D01*
G02X1176445Y136446I203J-1D01*
G01X1181295D01*
G02X1181498Y136244I1J-202D01*
G01Y132182D01*
G02X1181295Y131980I-203J1D01*
G01X1176445D01*
G02X1176242Y132182I-1J202D01*
G37*
G36*
G01Y125095D02*
Y129157D01*
G02X1176445Y129360I203J0D01*
G01X1181295D01*
G02X1181498Y129157I0J-203D01*
G01Y125095D01*
G02X1181295Y124892I-203J0D01*
G01X1176445D01*
G02X1176242Y125095I0J203D01*
G37*
G36*
G01Y118009D02*
Y122071D01*
G02X1176445Y122274I203J0D01*
G01X1181295D01*
G02X1181498Y122071I0J-203D01*
G01Y118009D01*
G02X1181295Y117806I-203J0D01*
G01X1176445D01*
G02X1176242Y118009I0J203D01*
G37*
G36*
G01X1199936Y467054D02*
Y471016D01*
G02X1200139Y471218I203J-1D01*
G01X1204789D01*
G02X1204992Y471016I1J-202D01*
G01Y467054D01*
G02X1204789Y466852I-203J1D01*
G01X1200139D01*
G02X1199936Y467054I-1J202D01*
G37*
G36*
G01Y474141D02*
Y478103D01*
G02X1200139Y478306I203J0D01*
G01X1204789D01*
G02X1204992Y478103I0J-203D01*
G01Y474141D01*
G02X1204789Y473938I-203J0D01*
G01X1200139D01*
G02X1199936Y474141I0J203D01*
G37*
G36*
G01Y481228D02*
Y485190D01*
G02X1200139Y485392I203J-1D01*
G01X1204789D01*
G02X1204992Y485190I1J-202D01*
G01Y481228D01*
G02X1204789Y481026I-203J1D01*
G01X1200139D01*
G02X1199936Y481228I-1J202D01*
G37*
G36*
G01Y488314D02*
Y492276D01*
G02X1200139Y492478I203J-1D01*
G01X1204789D01*
G02X1204992Y492276I1J-202D01*
G01Y488314D01*
G02X1204789Y488112I-203J1D01*
G01X1200139D01*
G02X1199936Y488314I-1J202D01*
G37*
G36*
G01Y518275D02*
Y522237D01*
G02X1200139Y522440I203J0D01*
G01X1204789D01*
G02X1204992Y522237I0J-203D01*
G01Y518275D01*
G02X1204789Y518072I-203J0D01*
G01X1200139D01*
G02X1199936Y518275I0J203D01*
G37*
G36*
G01Y511188D02*
Y515150D01*
G02X1200139Y515352I203J-1D01*
G01X1204789D01*
G02X1204992Y515150I1J-202D01*
G01Y511188D01*
G02X1204789Y510986I-203J1D01*
G01X1200139D01*
G02X1199936Y511188I-1J202D01*
G37*
G36*
G01Y532448D02*
Y536410D01*
G02X1200139Y536612I203J-1D01*
G01X1204789D01*
G02X1204992Y536410I1J-202D01*
G01Y532448D01*
G02X1204789Y532246I-203J1D01*
G01X1200139D01*
G02X1199936Y532448I-1J202D01*
G37*
G36*
G01Y525362D02*
Y529324D01*
G02X1200139Y529526I203J-1D01*
G01X1204789D01*
G02X1204992Y529324I1J-202D01*
G01Y525362D01*
G02X1204789Y525160I-203J1D01*
G01X1200139D01*
G02X1199936Y525362I-1J202D01*
G37*
G36*
G01Y561228D02*
Y565190D01*
G02X1200139Y565392I203J-1D01*
G01X1204789D01*
G02X1204992Y565190I1J-202D01*
G01Y561228D01*
G02X1204789Y561026I-203J1D01*
G01X1200139D01*
G02X1199936Y561228I-1J202D01*
G37*
G36*
G01Y568314D02*
Y572276D01*
G02X1200139Y572478I203J-1D01*
G01X1204789D01*
G02X1204992Y572276I1J-202D01*
G01Y568314D01*
G02X1204789Y568112I-203J1D01*
G01X1200139D01*
G02X1199936Y568314I-1J202D01*
G37*
G36*
G01Y575401D02*
Y579363D01*
G02X1200139Y579566I203J0D01*
G01X1204789D01*
G02X1204992Y579363I0J-203D01*
G01Y575401D01*
G02X1204789Y575198I-203J0D01*
G01X1200139D01*
G02X1199936Y575401I0J203D01*
G37*
G36*
G01Y582488D02*
Y586450D01*
G02X1200139Y586652I203J-1D01*
G01X1204789D01*
G02X1204992Y586450I1J-202D01*
G01Y582488D01*
G02X1204789Y582286I-203J1D01*
G01X1200139D01*
G02X1199936Y582488I-1J202D01*
G37*
G36*
G01Y589574D02*
Y593536D01*
G02X1200139Y593738I203J-1D01*
G01X1204789D01*
G02X1204992Y593536I1J-202D01*
G01Y589574D01*
G02X1204789Y589372I-203J1D01*
G01X1200139D01*
G02X1199936Y589574I-1J202D01*
G37*
G36*
G01Y596661D02*
Y600623D01*
G02X1200139Y600826I203J0D01*
G01X1204789D01*
G02X1204992Y600623I0J-203D01*
G01Y596661D01*
G02X1204789Y596458I-203J0D01*
G01X1200139D01*
G02X1199936Y596661I0J203D01*
G37*
G36*
G01Y603747D02*
Y607709D01*
G02X1200139Y607912I203J0D01*
G01X1204789D01*
G02X1204992Y607709I0J-203D01*
G01Y603747D01*
G02X1204789Y603544I-203J0D01*
G01X1200139D01*
G02X1199936Y603747I0J203D01*
G37*
G36*
G01Y610834D02*
Y614796D01*
G02X1200139Y614998I203J-1D01*
G01X1204789D01*
G02X1204992Y614796I1J-202D01*
G01Y610834D01*
G02X1204789Y610632I-203J1D01*
G01X1200139D01*
G02X1199936Y610834I-1J202D01*
G37*
G36*
G01X1278604Y110922D02*
Y114984D01*
G02X1278807Y115186I203J-1D01*
G01X1283657D01*
G02X1283860Y114984I1J-202D01*
G01Y110922D01*
G02X1283657Y110720I-203J1D01*
G01X1278807D01*
G02X1278604Y110922I-1J202D01*
G37*
G36*
G01Y103835D02*
Y107897D01*
G02X1278807Y108100I203J0D01*
G01X1283657D01*
G02X1283860Y107897I0J-203D01*
G01Y103835D01*
G02X1283657Y103632I-203J0D01*
G01X1278807D01*
G02X1278604Y103835I0J203D01*
G37*
G36*
G01Y132182D02*
Y136244D01*
G02X1278807Y136446I203J-1D01*
G01X1283657D01*
G02X1283860Y136244I1J-202D01*
G01Y132182D01*
G02X1283657Y131980I-203J1D01*
G01X1278807D01*
G02X1278604Y132182I-1J202D01*
G37*
G36*
G01Y125095D02*
Y129157D01*
G02X1278807Y129360I203J0D01*
G01X1283657D01*
G02X1283860Y129157I0J-203D01*
G01Y125095D01*
G02X1283657Y124892I-203J0D01*
G01X1278807D01*
G02X1278604Y125095I0J203D01*
G37*
G36*
G01Y118009D02*
Y122071D01*
G02X1278807Y122274I203J0D01*
G01X1283657D01*
G02X1283860Y122071I0J-203D01*
G01Y118009D01*
G02X1283657Y117806I-203J0D01*
G01X1278807D01*
G02X1278604Y118009I0J203D01*
G37*
G36*
G01X1428606Y110922D02*
Y114984D01*
G02X1428808Y115186I202J0D01*
G01X1433658D01*
G02X1433860Y114984I0J-202D01*
G01Y110922D01*
G02X1433658Y110720I-202J0D01*
G01X1428808D01*
G02X1428606Y110922I0J202D01*
G37*
G36*
G01Y103835D02*
Y107897D01*
G02X1428808Y108100I202J1D01*
G01X1433658D01*
G02X1433860Y107897I-1J-203D01*
G01Y103835D01*
G02X1433658Y103632I-202J-1D01*
G01X1428808D01*
G02X1428606Y103835I1J203D01*
G37*
G36*
G01Y132182D02*
Y136244D01*
G02X1428808Y136446I202J0D01*
G01X1433658D01*
G02X1433860Y136244I0J-202D01*
G01Y132182D01*
G02X1433658Y131980I-202J0D01*
G01X1428808D01*
G02X1428606Y132182I0J202D01*
G37*
G36*
G01Y125095D02*
Y129157D01*
G02X1428808Y129360I202J1D01*
G01X1433658D01*
G02X1433860Y129157I-1J-203D01*
G01Y125095D01*
G02X1433658Y124892I-202J-1D01*
G01X1428808D01*
G02X1428606Y125095I1J203D01*
G37*
G36*
G01Y118009D02*
Y122071D01*
G02X1428808Y122274I202J1D01*
G01X1433658D01*
G02X1433860Y122071I-1J-203D01*
G01Y118009D01*
G02X1433658Y117806I-202J-1D01*
G01X1428808D01*
G02X1428606Y118009I1J203D01*
G37*
G36*
G01X1486990Y17342D02*
G02X1486636Y16487I-1211J1D01*
G01X1486451Y16302D01*
G02X1485597Y15948I-854J853D01*
G01X1460959D01*
G02X1460105Y16302I1J1210D01*
G01X1459860Y16547D01*
G02X1459506Y17401I854J854D01*
G01Y34014D01*
G02X1459860Y34869I1213J-1D01*
G01X1459865Y34874D01*
X1485597D01*
G02X1486452Y34519I0J-1208D01*
G01X1486637Y34334D01*
G02X1486990Y33480I-858J-855D01*
G01Y17342D01*
G37*
G36*
G01X1530968Y110922D02*
Y114984D01*
G02X1531170Y115186I202J0D01*
G01X1536020D01*
G02X1536222Y114984I0J-202D01*
G01Y110922D01*
G02X1536020Y110720I-202J0D01*
G01X1531170D01*
G02X1530968Y110922I0J202D01*
G37*
G36*
G01Y103835D02*
Y107897D01*
G02X1531170Y108100I202J1D01*
G01X1536020D01*
G02X1536222Y107897I-1J-203D01*
G01Y103835D01*
G02X1536020Y103632I-202J-1D01*
G01X1531170D01*
G02X1530968Y103835I1J203D01*
G37*
G36*
G01Y132182D02*
Y136244D01*
G02X1531170Y136446I202J0D01*
G01X1536020D01*
G02X1536222Y136244I0J-202D01*
G01Y132182D01*
G02X1536020Y131980I-202J0D01*
G01X1531170D01*
G02X1530968Y132182I0J202D01*
G37*
G36*
G01Y125095D02*
Y129157D01*
G02X1531170Y129360I202J1D01*
G01X1536020D01*
G02X1536222Y129157I-1J-203D01*
G01Y125095D01*
G02X1536020Y124892I-202J-1D01*
G01X1531170D01*
G02X1530968Y125095I1J203D01*
G37*
G36*
G01Y118009D02*
Y122071D01*
G02X1531170Y122274I202J1D01*
G01X1536020D01*
G02X1536222Y122071I-1J-203D01*
G01Y118009D01*
G02X1536020Y117806I-202J-1D01*
G01X1531170D01*
G02X1530968Y118009I1J203D01*
G37*
G36*
G01X1555182Y394678D02*
Y390716D01*
G02X1554979Y390514I-203J1D01*
G01X1550329D01*
G02X1550126Y390716I-1J202D01*
G01Y394678D01*
G02X1550329Y394880I203J-1D01*
G01X1554979D01*
G02X1555182Y394678I1J-202D01*
G37*
G36*
G01Y401765D02*
Y397803D01*
G02X1554979Y397600I-203J0D01*
G01X1550329D01*
G02X1550126Y397803I0J203D01*
G01Y401765D01*
G02X1550329Y401968I203J0D01*
G01X1554979D01*
G02X1555182Y401765I0J-203D01*
G37*
G36*
G01Y408852D02*
Y404890D01*
G02X1554979Y404688I-203J1D01*
G01X1550329D01*
G02X1550126Y404890I-1J202D01*
G01Y408852D01*
G02X1550329Y409054I203J-1D01*
G01X1554979D01*
G02X1555182Y408852I1J-202D01*
G37*
G36*
G01Y423024D02*
Y419062D01*
G02X1554979Y418860I-203J1D01*
G01X1550329D01*
G02X1550126Y419062I-1J202D01*
G01Y423024D01*
G02X1550329Y423226I203J-1D01*
G01X1554979D01*
G02X1555182Y423024I1J-202D01*
G37*
G36*
G01Y415938D02*
Y411976D01*
G02X1554979Y411774I-203J1D01*
G01X1550329D01*
G02X1550126Y411976I-1J202D01*
G01Y415938D01*
G02X1550329Y416140I203J-1D01*
G01X1554979D01*
G02X1555182Y415938I1J-202D01*
G37*
G36*
G01Y430111D02*
Y426149D01*
G02X1554979Y425946I-203J0D01*
G01X1550329D01*
G02X1550126Y426149I0J203D01*
G01Y430111D01*
G02X1550329Y430314I203J0D01*
G01X1554979D01*
G02X1555182Y430111I0J-203D01*
G37*
G36*
G01Y437198D02*
Y433236D01*
G02X1554979Y433034I-203J1D01*
G01X1550329D01*
G02X1550126Y433236I-1J202D01*
G01Y437198D01*
G02X1550329Y437400I203J-1D01*
G01X1554979D01*
G02X1555182Y437198I1J-202D01*
G37*
G36*
G01Y444284D02*
Y440322D01*
G02X1554979Y440120I-203J1D01*
G01X1550329D01*
G02X1550126Y440322I-1J202D01*
G01Y444284D01*
G02X1550329Y444486I203J-1D01*
G01X1554979D01*
G02X1555182Y444284I1J-202D01*
G37*
G36*
G01Y473064D02*
Y469102D01*
G02X1554979Y468900I-203J1D01*
G01X1550329D01*
G02X1550126Y469102I-1J202D01*
G01Y473064D01*
G02X1550329Y473266I203J-1D01*
G01X1554979D01*
G02X1555182Y473064I1J-202D01*
G37*
G36*
G01Y480151D02*
Y476189D01*
G02X1554979Y475986I-203J0D01*
G01X1550329D01*
G02X1550126Y476189I0J203D01*
G01Y480151D01*
G02X1550329Y480354I203J0D01*
G01X1554979D01*
G02X1555182Y480151I0J-203D01*
G37*
G36*
G01Y487238D02*
Y483276D01*
G02X1554979Y483074I-203J1D01*
G01X1550329D01*
G02X1550126Y483276I-1J202D01*
G01Y487238D01*
G02X1550329Y487440I203J-1D01*
G01X1554979D01*
G02X1555182Y487238I1J-202D01*
G37*
G36*
G01Y494324D02*
Y490362D01*
G02X1554979Y490160I-203J1D01*
G01X1550329D01*
G02X1550126Y490362I-1J202D01*
G01Y494324D01*
G02X1550329Y494526I203J-1D01*
G01X1554979D01*
G02X1555182Y494324I1J-202D01*
G37*
G36*
G01Y517198D02*
Y513236D01*
G02X1554979Y513034I-203J1D01*
G01X1550329D01*
G02X1550126Y513236I-1J202D01*
G01Y517198D01*
G02X1550329Y517400I203J-1D01*
G01X1554979D01*
G02X1555182Y517198I1J-202D01*
G37*
G36*
G01Y524285D02*
Y520323D01*
G02X1554979Y520120I-203J0D01*
G01X1550329D01*
G02X1550126Y520323I0J203D01*
G01Y524285D01*
G02X1550329Y524488I203J0D01*
G01X1554979D01*
G02X1555182Y524285I0J-203D01*
G37*
G36*
G01Y531372D02*
Y527410D01*
G02X1554979Y527208I-203J1D01*
G01X1550329D01*
G02X1550126Y527410I-1J202D01*
G01Y531372D01*
G02X1550329Y531574I203J-1D01*
G01X1554979D01*
G02X1555182Y531372I1J-202D01*
G37*
G36*
G01Y538458D02*
Y534496D01*
G02X1554979Y534294I-203J1D01*
G01X1550329D01*
G02X1550126Y534496I-1J202D01*
G01Y538458D01*
G02X1550329Y538660I203J-1D01*
G01X1554979D01*
G02X1555182Y538458I1J-202D01*
G37*
G36*
G01X1633330Y110922D02*
Y114984D01*
G02X1633532Y115186I202J0D01*
G01X1638382D01*
G02X1638584Y114984I0J-202D01*
G01Y110922D01*
G02X1638382Y110720I-202J0D01*
G01X1633532D01*
G02X1633330Y110922I0J202D01*
G37*
G36*
G01Y103835D02*
Y107897D01*
G02X1633532Y108100I202J1D01*
G01X1638382D01*
G02X1638584Y107897I-1J-203D01*
G01Y103835D01*
G02X1638382Y103632I-202J-1D01*
G01X1633532D01*
G02X1633330Y103835I1J203D01*
G37*
G36*
G01Y132182D02*
Y136244D01*
G02X1633532Y136446I202J0D01*
G01X1638382D01*
G02X1638584Y136244I0J-202D01*
G01Y132182D01*
G02X1638382Y131980I-202J0D01*
G01X1633532D01*
G02X1633330Y132182I0J202D01*
G37*
G36*
G01Y125095D02*
Y129157D01*
G02X1633532Y129360I202J1D01*
G01X1638382D01*
G02X1638584Y129157I-1J-203D01*
G01Y125095D01*
G02X1638382Y124892I-202J-1D01*
G01X1633532D01*
G02X1633330Y125095I1J203D01*
G37*
G36*
G01Y118009D02*
Y122071D01*
G02X1633532Y122274I202J1D01*
G01X1638382D01*
G02X1638584Y122071I-1J-203D01*
G01Y118009D01*
G02X1638382Y117806I-202J-1D01*
G01X1633532D01*
G02X1633330Y118009I1J203D01*
G37*
G36*
G01X1657024Y467054D02*
Y471016D01*
G02X1657226Y471218I202J0D01*
G01X1661876D01*
G02X1662078Y471016I0J-202D01*
G01Y467054D01*
G02X1661876Y466852I-202J0D01*
G01X1657226D01*
G02X1657024Y467054I0J202D01*
G37*
G36*
G01Y474141D02*
Y478103D01*
G02X1657226Y478306I202J1D01*
G01X1661876D01*
G02X1662078Y478103I-1J-203D01*
G01Y474141D01*
G02X1661876Y473938I-202J-1D01*
G01X1657226D01*
G02X1657024Y474141I1J203D01*
G37*
G36*
G01Y481228D02*
Y485190D01*
G02X1657226Y485392I202J0D01*
G01X1661876D01*
G02X1662078Y485190I0J-202D01*
G01Y481228D01*
G02X1661876Y481026I-202J0D01*
G01X1657226D01*
G02X1657024Y481228I0J202D01*
G37*
G36*
G01Y488314D02*
Y492276D01*
G02X1657226Y492478I202J0D01*
G01X1661876D01*
G02X1662078Y492276I0J-202D01*
G01Y488314D01*
G02X1661876Y488112I-202J0D01*
G01X1657226D01*
G02X1657024Y488314I0J202D01*
G37*
G36*
G01Y518275D02*
Y522237D01*
G02X1657226Y522440I202J1D01*
G01X1661876D01*
G02X1662078Y522237I-1J-203D01*
G01Y518275D01*
G02X1661876Y518072I-202J-1D01*
G01X1657226D01*
G02X1657024Y518275I1J203D01*
G37*
G36*
G01Y511188D02*
Y515150D01*
G02X1657226Y515352I202J0D01*
G01X1661876D01*
G02X1662078Y515150I0J-202D01*
G01Y511188D01*
G02X1661876Y510986I-202J0D01*
G01X1657226D01*
G02X1657024Y511188I0J202D01*
G37*
G36*
G01Y532448D02*
Y536410D01*
G02X1657226Y536612I202J0D01*
G01X1661876D01*
G02X1662078Y536410I0J-202D01*
G01Y532448D01*
G02X1661876Y532246I-202J0D01*
G01X1657226D01*
G02X1657024Y532448I0J202D01*
G37*
G36*
G01Y525362D02*
Y529324D01*
G02X1657226Y529526I202J0D01*
G01X1661876D01*
G02X1662078Y529324I0J-202D01*
G01Y525362D01*
G02X1661876Y525160I-202J0D01*
G01X1657226D01*
G02X1657024Y525362I0J202D01*
G37*
G36*
G01Y561228D02*
Y565190D01*
G02X1657226Y565392I202J0D01*
G01X1661876D01*
G02X1662078Y565190I0J-202D01*
G01Y561228D01*
G02X1661876Y561026I-202J0D01*
G01X1657226D01*
G02X1657024Y561228I0J202D01*
G37*
G36*
G01Y568314D02*
Y572276D01*
G02X1657226Y572478I202J0D01*
G01X1661876D01*
G02X1662078Y572276I0J-202D01*
G01Y568314D01*
G02X1661876Y568112I-202J0D01*
G01X1657226D01*
G02X1657024Y568314I0J202D01*
G37*
G36*
G01Y575401D02*
Y579363D01*
G02X1657226Y579566I202J1D01*
G01X1661876D01*
G02X1662078Y579363I-1J-203D01*
G01Y575401D01*
G02X1661876Y575198I-202J-1D01*
G01X1657226D01*
G02X1657024Y575401I1J203D01*
G37*
G36*
G01Y582488D02*
Y586450D01*
G02X1657226Y586652I202J0D01*
G01X1661876D01*
G02X1662078Y586450I0J-202D01*
G01Y582488D01*
G02X1661876Y582286I-202J0D01*
G01X1657226D01*
G02X1657024Y582488I0J202D01*
G37*
G36*
G01Y589574D02*
Y593536D01*
G02X1657226Y593738I202J0D01*
G01X1661876D01*
G02X1662078Y593536I0J-202D01*
G01Y589574D01*
G02X1661876Y589372I-202J0D01*
G01X1657226D01*
G02X1657024Y589574I0J202D01*
G37*
G36*
G01Y596661D02*
Y600623D01*
G02X1657226Y600826I202J1D01*
G01X1661876D01*
G02X1662078Y600623I-1J-203D01*
G01Y596661D01*
G02X1661876Y596458I-202J-1D01*
G01X1657226D01*
G02X1657024Y596661I1J203D01*
G37*
G36*
G01Y603747D02*
Y607709D01*
G02X1657226Y607912I202J1D01*
G01X1661876D01*
G02X1662078Y607709I-1J-203D01*
G01Y603747D01*
G02X1661876Y603544I-202J-1D01*
G01X1657226D01*
G02X1657024Y603747I1J203D01*
G37*
G36*
G01Y610834D02*
Y614796D01*
G02X1657226Y614998I202J0D01*
G01X1661876D01*
G02X1662078Y614796I0J-202D01*
G01Y610834D01*
G02X1661876Y610632I-202J0D01*
G01X1657226D01*
G02X1657024Y610834I0J202D01*
G37*
G36*
G01X1735692Y110922D02*
Y114984D01*
G02X1735894Y115186I202J0D01*
G01X1740744D01*
G02X1740946Y114984I0J-202D01*
G01Y110922D01*
G02X1740744Y110720I-202J0D01*
G01X1735894D01*
G02X1735692Y110922I0J202D01*
G37*
G36*
G01Y103835D02*
Y107897D01*
G02X1735894Y108100I202J1D01*
G01X1740744D01*
G02X1740946Y107897I-1J-203D01*
G01Y103835D01*
G02X1740744Y103632I-202J-1D01*
G01X1735894D01*
G02X1735692Y103835I1J203D01*
G37*
G36*
G01Y132182D02*
Y136244D01*
G02X1735894Y136446I202J0D01*
G01X1740744D01*
G02X1740946Y136244I0J-202D01*
G01Y132182D01*
G02X1740744Y131980I-202J0D01*
G01X1735894D01*
G02X1735692Y132182I0J202D01*
G37*
G36*
G01Y125095D02*
Y129157D01*
G02X1735894Y129360I202J1D01*
G01X1740744D01*
G02X1740946Y129157I-1J-203D01*
G01Y125095D01*
G02X1740744Y124892I-202J-1D01*
G01X1735894D01*
G02X1735692Y125095I1J203D01*
G37*
G36*
G01Y118009D02*
Y122071D01*
G02X1735894Y122274I202J1D01*
G01X1740744D01*
G02X1740946Y122071I-1J-203D01*
G01Y118009D01*
G02X1740744Y117806I-202J-1D01*
G01X1735894D01*
G02X1735692Y118009I1J203D01*
G37*
G36*
G01X1760028Y820093D02*
Y821677D01*
G02X1760230Y821880I202J1D01*
G01X1761831D01*
G02X1762034Y821677I0J-203D01*
G01Y820093D01*
G02X1761831Y819890I-203J0D01*
G01X1760230D01*
G02X1760028Y820093I1J203D01*
G37*
G36*
G01X1764986Y821673D02*
Y820089D01*
G02X1764784Y819886I-202J-1D01*
G01X1763183D01*
G02X1762980Y820089I0J203D01*
G01Y821673D01*
G02X1763183Y821876I203J0D01*
G01X1764784D01*
G02X1764986Y821673I-1J-203D01*
G37*
G36*
G01X1760028Y823593D02*
Y825177D01*
G02X1760230Y825380I202J1D01*
G01X1761831D01*
G02X1762034Y825177I0J-203D01*
G01Y823593D01*
G02X1761831Y823390I-203J0D01*
G01X1760230D01*
G02X1760028Y823593I1J203D01*
G37*
G36*
G01X1764986Y825173D02*
Y823589D01*
G02X1764784Y823386I-202J-1D01*
G01X1763183D01*
G02X1762980Y823589I0J203D01*
G01Y825173D01*
G02X1763183Y825376I203J0D01*
G01X1764784D01*
G02X1764986Y825173I-1J-203D01*
G37*
G36*
G01X1776048Y1628033D02*
Y1602300D01*
G02X1775694Y1601446I-1208J0D01*
G01X1775509Y1601261D01*
G02X1774655Y1600908I-855J858D01*
G01X1758517D01*
G02X1757662Y1601262I1J1211D01*
G01X1757477Y1601447D01*
G02X1757122Y1602301I852J855D01*
G01Y1626937D01*
G02X1757477Y1627793I1210J0D01*
G01X1757722Y1628038D01*
G02X1758576Y1628392I854J-854D01*
G01X1775189D01*
G02X1776044Y1628038I-1J-1213D01*
G01X1776048Y1628033D01*
G37*
G36*
G01X262070Y110922D02*
Y114984D01*
G02X262272Y115186I202J0D01*
G01X267122D01*
G02X267324Y114984I0J-202D01*
G01Y110922D01*
G02X267122Y110720I-202J0D01*
G01X262272D01*
G02X262070Y110922I0J202D01*
G37*
G36*
G01Y103835D02*
Y107897D01*
G02X262272Y108100I202J1D01*
G01X267122D01*
G02X267324Y107897I-1J-203D01*
G01Y103835D01*
G02X267122Y103632I-202J-1D01*
G01X262272D01*
G02X262070Y103835I1J203D01*
G37*
G36*
G01Y132182D02*
Y136244D01*
G02X262272Y136446I202J0D01*
G01X267122D01*
G02X267324Y136244I0J-202D01*
G01Y132182D01*
G02X267122Y131980I-202J0D01*
G01X262272D01*
G02X262070Y132182I0J202D01*
G37*
G36*
G01Y125095D02*
Y129157D01*
G02X262272Y129360I202J1D01*
G01X267122D01*
G02X267324Y129157I-1J-203D01*
G01Y125095D01*
G02X267122Y124892I-202J-1D01*
G01X262272D01*
G02X262070Y125095I1J203D01*
G37*
G36*
G01Y118009D02*
Y122071D01*
G02X262272Y122274I202J1D01*
G01X267122D01*
G02X267324Y122071I-1J-203D01*
G01Y118009D01*
G02X267122Y117806I-202J-1D01*
G01X262272D01*
G02X262070Y118009I1J203D01*
G37*
G36*
G01X905899Y304150D02*
X909299D01*
G02Y300544I0J-1803D01*
G01X905899D01*
G02Y304150I0J1803D01*
G37*
G36*
G01X1033891Y298096D02*
X1037291D01*
G02Y294490I0J-1803D01*
G01X1033891D01*
G02Y298096I0J1803D01*
G37*
G36*
G01X1318363Y312364D02*
X1321763D01*
G02Y308760I0J-1802D01*
G01X1318363D01*
G02Y312364I0J1802D01*
G37*
G36*
G01X1337508Y371598D02*
X1334108D01*
G02Y375204I0J1803D01*
G01X1337508D01*
G02Y371598I0J-1803D01*
G37*
G36*
G01X1326237Y309364D02*
X1329637D01*
G02Y305760I0J-1802D01*
G01X1326237D01*
G02Y309364I0J1802D01*
G37*
G36*
G01X1334111Y312364D02*
X1337511D01*
G02Y308760I0J-1802D01*
G01X1334111D01*
G02Y312364I0J1802D01*
G37*
G36*
G01X319274Y14105D02*
G02X318920Y13250I-1211J1D01*
G01X318735Y13065D01*
G02X317881Y12710I-855J852D01*
G01X293245D01*
G02X292389Y13065I0J1210D01*
G01X292144Y13310D01*
G02X291790Y14164I854J854D01*
G01Y30777D01*
G02X292144Y31632I1213J-1D01*
G01X292149Y31636D01*
X317882D01*
G02X318736Y31282I0J-1208D01*
G01X318921Y31097D01*
G02X319274Y30243I-858J-855D01*
G01Y14105D01*
G37*
G36*
G01X285764Y467054D02*
Y471016D01*
G02X285966Y471218I202J0D01*
G01X290616D01*
G02X290818Y471016I0J-202D01*
G01Y467054D01*
G02X290616Y466852I-202J0D01*
G01X285966D01*
G02X285764Y467054I0J202D01*
G37*
G36*
G01Y488314D02*
Y492276D01*
G02X285966Y492478I202J0D01*
G01X290616D01*
G02X290818Y492276I0J-202D01*
G01Y488314D01*
G02X290616Y488112I-202J0D01*
G01X285966D01*
G02X285764Y488314I0J202D01*
G37*
G36*
G01Y481228D02*
Y485190D01*
G02X285966Y485392I202J0D01*
G01X290616D01*
G02X290818Y485190I0J-202D01*
G01Y481228D01*
G02X290616Y481026I-202J0D01*
G01X285966D01*
G02X285764Y481228I0J202D01*
G37*
G36*
G01Y474141D02*
Y478103D01*
G02X285966Y478306I202J1D01*
G01X290616D01*
G02X290818Y478103I-1J-203D01*
G01Y474141D01*
G02X290616Y473938I-202J-1D01*
G01X285966D01*
G02X285764Y474141I1J203D01*
G37*
G36*
G01Y511188D02*
Y515150D01*
G02X285966Y515352I202J0D01*
G01X290616D01*
G02X290818Y515150I0J-202D01*
G01Y511188D01*
G02X290616Y510986I-202J0D01*
G01X285966D01*
G02X285764Y511188I0J202D01*
G37*
G36*
G01Y518275D02*
Y522237D01*
G02X285966Y522440I202J1D01*
G01X290616D01*
G02X290818Y522237I-1J-203D01*
G01Y518275D01*
G02X290616Y518072I-202J-1D01*
G01X285966D01*
G02X285764Y518275I1J203D01*
G37*
G36*
G01Y525362D02*
Y529324D01*
G02X285966Y529526I202J0D01*
G01X290616D01*
G02X290818Y529324I0J-202D01*
G01Y525362D01*
G02X290616Y525160I-202J0D01*
G01X285966D01*
G02X285764Y525362I0J202D01*
G37*
G36*
G01Y532448D02*
Y536410D01*
G02X285966Y536612I202J0D01*
G01X290616D01*
G02X290818Y536410I0J-202D01*
G01Y532448D01*
G02X290616Y532246I-202J0D01*
G01X285966D01*
G02X285764Y532448I0J202D01*
G37*
G36*
G01Y568314D02*
Y572276D01*
G02X285966Y572478I202J0D01*
G01X290616D01*
G02X290818Y572276I0J-202D01*
G01Y568314D01*
G02X290616Y568112I-202J0D01*
G01X285966D01*
G02X285764Y568314I0J202D01*
G37*
G36*
G01Y561228D02*
Y565190D01*
G02X285966Y565392I202J0D01*
G01X290616D01*
G02X290818Y565190I0J-202D01*
G01Y561228D01*
G02X290616Y561026I-202J0D01*
G01X285966D01*
G02X285764Y561228I0J202D01*
G37*
G36*
G01Y582488D02*
Y586450D01*
G02X285966Y586652I202J0D01*
G01X290616D01*
G02X290818Y586450I0J-202D01*
G01Y582488D01*
G02X290616Y582286I-202J0D01*
G01X285966D01*
G02X285764Y582488I0J202D01*
G37*
G36*
G01Y575401D02*
Y579363D01*
G02X285966Y579566I202J1D01*
G01X290616D01*
G02X290818Y579363I-1J-203D01*
G01Y575401D01*
G02X290616Y575198I-202J-1D01*
G01X285966D01*
G02X285764Y575401I1J203D01*
G37*
G36*
G01Y603747D02*
Y607709D01*
G02X285966Y607912I202J1D01*
G01X290616D01*
G02X290818Y607709I-1J-203D01*
G01Y603747D01*
G02X290616Y603544I-202J-1D01*
G01X285966D01*
G02X285764Y603747I1J203D01*
G37*
G36*
G01Y596661D02*
Y600623D01*
G02X285966Y600826I202J1D01*
G01X290616D01*
G02X290818Y600623I-1J-203D01*
G01Y596661D01*
G02X290616Y596458I-202J-1D01*
G01X285966D01*
G02X285764Y596661I1J203D01*
G37*
G36*
G01Y589574D02*
Y593536D01*
G02X285966Y593738I202J0D01*
G01X290616D01*
G02X290818Y593536I0J-202D01*
G01Y589574D01*
G02X290616Y589372I-202J0D01*
G01X285966D01*
G02X285764Y589574I0J202D01*
G37*
G36*
G01Y610834D02*
Y614796D01*
G02X285966Y614998I202J0D01*
G01X290616D01*
G02X290818Y614796I0J-202D01*
G01Y610834D01*
G02X290616Y610632I-202J0D01*
G01X285966D01*
G02X285764Y610834I0J202D01*
G37*
G36*
G01X364432Y110922D02*
Y114984D01*
G02X364634Y115186I202J0D01*
G01X369484D01*
G02X369686Y114984I0J-202D01*
G01Y110922D01*
G02X369484Y110720I-202J0D01*
G01X364634D01*
G02X364432Y110922I0J202D01*
G37*
G36*
G01Y103835D02*
Y107897D01*
G02X364634Y108100I202J1D01*
G01X369484D01*
G02X369686Y107897I-1J-203D01*
G01Y103835D01*
G02X369484Y103632I-202J-1D01*
G01X364634D01*
G02X364432Y103835I1J203D01*
G37*
G36*
G01Y132182D02*
Y136244D01*
G02X364634Y136446I202J0D01*
G01X369484D01*
G02X369686Y136244I0J-202D01*
G01Y132182D01*
G02X369484Y131980I-202J0D01*
G01X364634D01*
G02X364432Y132182I0J202D01*
G37*
G36*
G01Y125095D02*
Y129157D01*
G02X364634Y129360I202J1D01*
G01X369484D01*
G02X369686Y129157I-1J-203D01*
G01Y125095D01*
G02X369484Y124892I-202J-1D01*
G01X364634D01*
G02X364432Y125095I1J203D01*
G37*
G36*
G01Y118009D02*
Y122071D01*
G02X364634Y122274I202J1D01*
G01X369484D01*
G02X369686Y122071I-1J-203D01*
G01Y118009D01*
G02X369484Y117806I-202J-1D01*
G01X364634D01*
G02X364432Y118009I1J203D01*
G37*
G36*
G01X401403Y1512504D02*
X400403D01*
G02X399900Y1513007I0J503D01*
G01Y1513799D01*
G02X400403Y1514302I503J0D01*
G01X401403D01*
G02X401906Y1513799I0J-503D01*
G01Y1513007D01*
G02X401403Y1512504I-503J0D01*
G37*
G36*
G01X43004Y1503134D02*
X41091D01*
G02X40588Y1503637I0J503D01*
G01Y1504999D01*
G02X41091Y1505502I503J0D01*
G01X43004D01*
G02X43506Y1504999I-1J-503D01*
G01Y1503637D01*
G02X43004Y1503134I-502J-1D01*
G37*
G36*
G01X403570Y1535688D02*
Y1533167D01*
G02X403367Y1532964I-203J0D01*
G01X400780D01*
G02X400578Y1533167I1J203D01*
G01Y1535688D01*
G02X400780Y1535890I202J0D01*
G01X403367D01*
G02X403570Y1535688I1J-202D01*
G37*
G36*
G01X407506D02*
Y1533167D01*
G02X407304Y1532964I-202J-1D01*
G01X404717D01*
G02X404514Y1533167I0J203D01*
G01Y1535688D01*
G02X404717Y1535890I203J-1D01*
G01X407304D01*
G02X407506Y1535688I0J-202D01*
G37*
G36*
G01X413412D02*
Y1533167D01*
G02X413210Y1532964I-202J-1D01*
G01X410623D01*
G02X410420Y1533167I0J203D01*
G01Y1535688D01*
G02X410623Y1535890I203J-1D01*
G01X413210D01*
G02X413412Y1535688I0J-202D01*
G37*
G36*
G01X514432Y110922D02*
Y114984D01*
G02X514635Y115186I203J-1D01*
G01X519485D01*
G02X519688Y114984I1J-202D01*
G01Y110922D01*
G02X519485Y110720I-203J1D01*
G01X514635D01*
G02X514432Y110922I-1J202D01*
G37*
G36*
G01Y103835D02*
Y107897D01*
G02X514635Y108100I203J0D01*
G01X519485D01*
G02X519688Y107897I0J-203D01*
G01Y103835D01*
G02X519485Y103632I-203J0D01*
G01X514635D01*
G02X514432Y103835I0J203D01*
G37*
G36*
G01Y132182D02*
Y136244D01*
G02X514635Y136446I203J-1D01*
G01X519485D01*
G02X519688Y136244I1J-202D01*
G01Y132182D01*
G02X519485Y131980I-203J1D01*
G01X514635D01*
G02X514432Y132182I-1J202D01*
G37*
G36*
G01Y125095D02*
Y129157D01*
G02X514635Y129360I203J0D01*
G01X519485D01*
G02X519688Y129157I0J-203D01*
G01Y125095D01*
G02X519485Y124892I-203J0D01*
G01X514635D01*
G02X514432Y125095I0J203D01*
G37*
G36*
G01Y118009D02*
Y122071D01*
G02X514635Y122274I203J0D01*
G01X519485D01*
G02X519688Y122071I0J-203D01*
G01Y118009D01*
G02X519485Y117806I-203J0D01*
G01X514635D01*
G02X514432Y118009I0J203D01*
G37*
G36*
G01X616794Y110922D02*
Y114984D01*
G02X616997Y115186I203J-1D01*
G01X621847D01*
G02X622050Y114984I1J-202D01*
G01Y110922D01*
G02X621847Y110720I-203J1D01*
G01X616997D01*
G02X616794Y110922I-1J202D01*
G37*
G36*
G01Y103835D02*
Y107897D01*
G02X616997Y108100I203J0D01*
G01X621847D01*
G02X622050Y107897I0J-203D01*
G01Y103835D01*
G02X621847Y103632I-203J0D01*
G01X616997D01*
G02X616794Y103835I0J203D01*
G37*
G36*
G01Y132182D02*
Y136244D01*
G02X616997Y136446I203J-1D01*
G01X621847D01*
G02X622050Y136244I1J-202D01*
G01Y132182D01*
G02X621847Y131980I-203J1D01*
G01X616997D01*
G02X616794Y132182I-1J202D01*
G37*
G36*
G01Y125095D02*
Y129157D01*
G02X616997Y129360I203J0D01*
G01X621847D01*
G02X622050Y129157I0J-203D01*
G01Y125095D01*
G02X621847Y124892I-203J0D01*
G01X616997D01*
G02X616794Y125095I0J203D01*
G37*
G36*
G01Y118009D02*
Y122071D01*
G02X616997Y122274I203J0D01*
G01X621847D01*
G02X622050Y122071I0J-203D01*
G01Y118009D01*
G02X621847Y117806I-203J0D01*
G01X616997D01*
G02X616794Y118009I0J203D01*
G37*
G36*
G01X641008Y394678D02*
Y390716D01*
G02X640805Y390514I-203J1D01*
G01X636155D01*
G02X635952Y390716I-1J202D01*
G01Y394678D01*
G02X636155Y394880I203J-1D01*
G01X640805D01*
G02X641008Y394678I1J-202D01*
G37*
G36*
G01Y401765D02*
Y397803D01*
G02X640805Y397600I-203J0D01*
G01X636155D01*
G02X635952Y397803I0J203D01*
G01Y401765D01*
G02X636155Y401968I203J0D01*
G01X640805D01*
G02X641008Y401765I0J-203D01*
G37*
G36*
G01Y408852D02*
Y404890D01*
G02X640805Y404688I-203J1D01*
G01X636155D01*
G02X635952Y404890I-1J202D01*
G01Y408852D01*
G02X636155Y409054I203J-1D01*
G01X640805D01*
G02X641008Y408852I1J-202D01*
G37*
G36*
G01Y423024D02*
Y419062D01*
G02X640805Y418860I-203J1D01*
G01X636155D01*
G02X635952Y419062I-1J202D01*
G01Y423024D01*
G02X636155Y423226I203J-1D01*
G01X640805D01*
G02X641008Y423024I1J-202D01*
G37*
G36*
G01Y415938D02*
Y411976D01*
G02X640805Y411774I-203J1D01*
G01X636155D01*
G02X635952Y411976I-1J202D01*
G01Y415938D01*
G02X636155Y416140I203J-1D01*
G01X640805D01*
G02X641008Y415938I1J-202D01*
G37*
G36*
G01Y430111D02*
Y426149D01*
G02X640805Y425946I-203J0D01*
G01X636155D01*
G02X635952Y426149I0J203D01*
G01Y430111D01*
G02X636155Y430314I203J0D01*
G01X640805D01*
G02X641008Y430111I0J-203D01*
G37*
G36*
G01Y437198D02*
Y433236D01*
G02X640805Y433034I-203J1D01*
G01X636155D01*
G02X635952Y433236I-1J202D01*
G01Y437198D01*
G02X636155Y437400I203J-1D01*
G01X640805D01*
G02X641008Y437198I1J-202D01*
G37*
G36*
G01Y444284D02*
Y440322D01*
G02X640805Y440120I-203J1D01*
G01X636155D01*
G02X635952Y440322I-1J202D01*
G01Y444284D01*
G02X636155Y444486I203J-1D01*
G01X640805D01*
G02X641008Y444284I1J-202D01*
G37*
G36*
G01Y473064D02*
Y469102D01*
G02X640805Y468900I-203J1D01*
G01X636155D01*
G02X635952Y469102I-1J202D01*
G01Y473064D01*
G02X636155Y473266I203J-1D01*
G01X640805D01*
G02X641008Y473064I1J-202D01*
G37*
G36*
G01Y480151D02*
Y476189D01*
G02X640805Y475986I-203J0D01*
G01X636155D01*
G02X635952Y476189I0J203D01*
G01Y480151D01*
G02X636155Y480354I203J0D01*
G01X640805D01*
G02X641008Y480151I0J-203D01*
G37*
G36*
G01Y487238D02*
Y483276D01*
G02X640805Y483074I-203J1D01*
G01X636155D01*
G02X635952Y483276I-1J202D01*
G01Y487238D01*
G02X636155Y487440I203J-1D01*
G01X640805D01*
G02X641008Y487238I1J-202D01*
G37*
G36*
G01Y494324D02*
Y490362D01*
G02X640805Y490160I-203J1D01*
G01X636155D01*
G02X635952Y490362I-1J202D01*
G01Y494324D01*
G02X636155Y494526I203J-1D01*
G01X640805D01*
G02X641008Y494324I1J-202D01*
G37*
G36*
G01Y517198D02*
Y513236D01*
G02X640805Y513034I-203J1D01*
G01X636155D01*
G02X635952Y513236I-1J202D01*
G01Y517198D01*
G02X636155Y517400I203J-1D01*
G01X640805D01*
G02X641008Y517198I1J-202D01*
G37*
G36*
G01Y524285D02*
Y520323D01*
G02X640805Y520120I-203J0D01*
G01X636155D01*
G02X635952Y520323I0J203D01*
G01Y524285D01*
G02X636155Y524488I203J0D01*
G01X640805D01*
G02X641008Y524285I0J-203D01*
G37*
G36*
G01Y531372D02*
Y527410D01*
G02X640805Y527208I-203J1D01*
G01X636155D01*
G02X635952Y527410I-1J202D01*
G01Y531372D01*
G02X636155Y531574I203J-1D01*
G01X640805D01*
G02X641008Y531372I1J-202D01*
G37*
G36*
G01Y538458D02*
Y534496D01*
G02X640805Y534294I-203J1D01*
G01X636155D01*
G02X635952Y534496I-1J202D01*
G01Y538458D01*
G02X636155Y538660I203J-1D01*
G01X640805D01*
G02X641008Y538458I1J-202D01*
G37*
G36*
G01X1199936Y459969D02*
Y463931D01*
G02X1200139Y464134I203J0D01*
G01X1204789D01*
G02X1204992Y463931I0J-203D01*
G01Y459969D01*
G02X1204789Y459766I-203J0D01*
G01X1200139D01*
G02X1199936Y459969I0J203D01*
G37*
G36*
G01X1518207Y1176748D02*
X1514467D01*
G02Y1179354I0J1303D01*
G01X1518207D01*
G02Y1176748I0J-1303D01*
G37*
G36*
G01Y1169268D02*
X1514467D01*
G02Y1171872I0J1302D01*
G01X1518207D01*
G02Y1169268I0J-1302D01*
G37*
G36*
G01X1513926Y907148D02*
X1510526D01*
G02Y910754I0J1803D01*
G01X1513926D01*
G02Y907148I0J-1803D01*
G37*
G36*
G01X1531299Y1174878D02*
X1527559D01*
G02Y1177482I0J1302D01*
G01X1531299D01*
G02Y1174878I0J-1302D01*
G37*
G36*
G01X146947Y1176748D02*
X143207D01*
G02Y1179354I0J1303D01*
G01X146947D01*
G02Y1176748I0J-1303D01*
G37*
G36*
G01Y1169268D02*
X143207D01*
G02Y1171872I0J1302D01*
G01X146947D01*
G02Y1169268I0J-1302D01*
G37*
G36*
G01X160039Y1174878D02*
X156299D01*
G02Y1177482I0J1302D01*
G01X160039D01*
G02Y1174878I0J-1302D01*
G37*
G36*
G01X604034Y1176748D02*
X600294D01*
G02Y1179354I0J1303D01*
G01X604034D01*
G02Y1176748I0J-1303D01*
G37*
G36*
G01Y1169268D02*
X600294D01*
G02Y1171872I0J1302D01*
G01X604034D01*
G02Y1169268I0J-1302D01*
G37*
G36*
G01X605733Y942940D02*
X609133D01*
G02Y939336I0J-1802D01*
G01X605733D01*
G02Y942940I0J1802D01*
G37*
G36*
G01X615256Y1176748D02*
X611516D01*
G02Y1179354I0J1303D01*
G01X615256D01*
G02Y1176748I0J-1303D01*
G37*
G36*
G01X1061120D02*
X1057380D01*
G02Y1179354I0J1303D01*
G01X1061120D01*
G02Y1176748I0J-1303D01*
G37*
G36*
G01Y1169268D02*
X1057380D01*
G02Y1171872I0J1302D01*
G01X1061120D01*
G02Y1169268I0J-1302D01*
G37*
G36*
G01X401403Y1518804D02*
X400403D01*
G02X399900Y1519307I0J503D01*
G01Y1520099D01*
G02X400403Y1520602I503J0D01*
G01X401403D01*
G02X401906Y1520099I0J-503D01*
G01Y1519307D01*
G02X401403Y1518804I-503J0D01*
G37*
G36*
G01X1769063Y921922D02*
X1765663D01*
G02Y925526I0J1802D01*
G01X1769063D01*
G02Y921922I0J-1802D01*
G37*
G36*
G01X1072342Y1176748D02*
X1068602D01*
G02Y1179354I0J1303D01*
G01X1072342D01*
G02Y1176748I0J-1303D01*
G37*
G36*
G01X900642Y233308D02*
Y236773D01*
G02X900845Y236976I203J0D01*
G01X905746D01*
G02X905948Y236773I-1J-203D01*
G01Y234900D01*
G03X906059Y234721I200J0D01*
G01X906380Y234561D01*
G03X906589Y234580I89J179D01*
G02X905066Y232562I2771J-3675D01*
G01X905084Y232608D01*
X905072Y232706D01*
X904858Y233019D01*
G03X904693Y233106I-165J-113D01*
G01X900845D01*
G02X900642Y233308I-1J202D01*
G37*
G36*
G01X647411Y379065D02*
X647412D01*
G02Y370659I0J-4203D01*
G01X647411D01*
G02Y379065I0J4203D01*
G37*
G36*
G01X392618Y1516843D02*
G02X392805Y1517233I502J-1D01*
G03X392835Y1517263I-126J156D01*
G02X393225Y1517450I391J-315D01*
G01X394020D01*
G02X394419Y1517253I0J-502D01*
G03X394447Y1517223I159J121D01*
G02X394622Y1516841I-329J-382D01*
G01Y1516049D01*
G02X394437Y1515660I-501J0D01*
G03X394408Y1515631I126J-155D01*
G02X394019Y1515446I-389J316D01*
G01X393225D01*
G02X392845Y1515621I1J502D01*
G03X392815Y1515649I-151J-131D01*
G02X392618Y1516048I305J399D01*
G01Y1516843D01*
G37*
G36*
G01X400508Y1517558D02*
X401303D01*
G02X401702Y1517361I0J-502D01*
G03X401730Y1517331I159J121D01*
G02X401906Y1516949I-327J-382D01*
G01Y1516157D01*
G02X401720Y1515768I-502J1D01*
G03X401691Y1515739I126J-155D01*
G02X401302Y1515554I-389J316D01*
G01X400508D01*
G02X400128Y1515729I1J502D01*
G03X400098Y1515757I-151J-131D01*
G02X399900Y1516157I305J400D01*
G01Y1516949D01*
G02X400088Y1517341I503J0D01*
G03X400118Y1517371I-126J156D01*
G02X400508Y1517558I391J-315D01*
G37*
G36*
G01X815062Y1622338D02*
X821185Y1628461D01*
G02X822069Y1628827I884J-885D01*
G01X928166D01*
G02X929050Y1628461I0J-1251D01*
G01X934307Y1623204D01*
G02X934673Y1622320I-885J-884D01*
G01Y1586606D01*
G03X934732Y1586464I200J0D01*
G01X941369Y1579827D01*
G03X941511Y1579768I142J141D01*
G01X956943D01*
G02X957827Y1579402I0J-1251D01*
G01X962023Y1575206D01*
G02X962389Y1574322I-885J-884D01*
G01Y1544281D01*
G03X962448Y1544139I200J0D01*
G01X965638Y1540949D01*
G03X965780Y1540890I142J141D01*
G01X1020507D01*
G02X1021391Y1540524I0J-1251D01*
G01X1033708Y1528207D01*
G02X1034074Y1527323I-885J-884D01*
G01Y1492303D01*
G02X1033708Y1491419I-1251J0D01*
G01X1032711Y1490422D01*
G02X1031827Y1490056I-884J885D01*
G01X946582D01*
G02X945698Y1490422I0J1251D01*
G01X943533Y1492587D01*
G03X943391Y1492646I-142J-141D01*
G01X934180D01*
G03X934038Y1492587I0J-200D01*
G01X919334Y1477883D01*
G03X919275Y1477741I141J-142D01*
G01Y1464419D01*
G02X918909Y1463535I-1251J0D01*
G01X916381Y1461007D01*
G03X916322Y1460865I141J-142D01*
G01Y1460327D01*
G02X915956Y1459443I-1251J0D01*
G01X915720Y1459207D01*
G03X915661Y1459065I141J-142D01*
G01Y1445847D01*
G02X915295Y1444963I-1251J0D01*
G01X914298Y1443966D01*
G02X913414Y1443600I-884J885D01*
G01X899958D01*
G02X899074Y1443966I0J1251D01*
G01X898077Y1444963D01*
G02X897711Y1445847I885J884D01*
G01Y1459039D01*
G03X897652Y1459181I-200J0D01*
G01X897339Y1459494D01*
G02X896973Y1460378I885J884D01*
G01Y1461423D01*
G03X896914Y1461565I-200J0D01*
G01X892210Y1466269D01*
G02X891844Y1467153I885J884D01*
G01Y1472495D01*
G03X891785Y1472637I-200J0D01*
G01X887610Y1476812D01*
G03X887468Y1476871I-142J-141D01*
G01X881105D01*
G03X880963Y1476812I0J-200D01*
G01X874458Y1470307D01*
G03X874399Y1470165I141J-142D01*
G01Y1460390D01*
G02X874033Y1459506I-1251J0D01*
G01X873695Y1459168D01*
G03X873636Y1459026I141J-142D01*
G01Y1445822D01*
G02X873270Y1444938I-1251J0D01*
G01X872311Y1443979D01*
G02X871427Y1443613I-884J885D01*
G01X858101D01*
G02X857217Y1443979I0J1251D01*
G01X855946Y1445250D01*
G02X855580Y1446134I885J884D01*
G01Y1458923D01*
G03X855521Y1459065I-200J0D01*
G01X852317Y1462269D01*
G03X852175Y1462328I-142J-141D01*
G01X829373D01*
G03X829173Y1462128I0J-200D01*
G01Y1461246D01*
G02X828807Y1460362I-1251J0D01*
G01X827914Y1459469D01*
G02X827030Y1459103I-884J885D01*
G01X825637D01*
G03X825495Y1459044I0J-200D01*
G01X822876Y1456425D01*
G02X821992Y1456059I-884J885D01*
G01X821694D01*
G03X821494Y1455859I0J-200D01*
G01Y1445861D01*
G02X821128Y1444977I-1251J0D01*
G01X820169Y1444018D01*
G02X819285Y1443652I-884J885D01*
G01X805792D01*
G02X804908Y1444018I0J1251D01*
G01X803870Y1445056D01*
G02X803504Y1445940I885J884D01*
G01Y1460429D01*
G02X803870Y1461313I1251J0D01*
G01X804002Y1461445D01*
G03X804061Y1461587I-141J142D01*
G01Y1474910D01*
G02X804396Y1475762I1251J0D01*
G03X804450Y1475898I-146J137D01*
G01Y1487743D01*
X804385Y1487842D01*
X804329Y1487866D01*
G02Y1490628I590J1381D01*
G01X804385Y1490652D01*
X804450Y1490751D01*
Y1524316D01*
G02X804816Y1525200I1251J0D01*
G01X814637Y1535021D01*
G03X814696Y1535163I-141J142D01*
G01Y1621454D01*
G02X815062Y1622338I1251J0D01*
G37*
G36*
G01X68503Y115453D02*
G02X68599Y115478I98J-178D01*
G01X71499D01*
G02X71546Y115472I-2J-204D01*
G01X71547D01*
G02X71702Y115274I-49J-198D01*
G01Y114313D01*
X71048Y113315D01*
X70987Y113222D01*
X70860Y113026D01*
G03X70852Y112821I168J-109D01*
G01X71702Y111520D01*
Y110564D01*
G02X71595Y110385I-203J0D01*
G02X71499Y110360I-98J178D01*
G01X68599D01*
G02X68552Y110366I2J204D01*
G01X68551D01*
G02X68396Y110564I49J198D01*
G01Y111520D01*
X68416Y111551D01*
X68418Y111555D01*
X68431Y111577D01*
G02X68448Y111601I170J-103D01*
G01X68667Y111937D01*
X68743Y112054D01*
X69235Y112809D01*
G03X69262Y112910I-173J100D01*
G01Y112937D01*
G03X69229Y113047I-200J0D01*
G01X69212Y113073D01*
X68396Y114318D01*
Y115274D01*
G02X68503Y115453I203J0D01*
G37*
G36*
G01X170811Y115412D02*
G02X170961Y115478I150J-137D01*
G01X173861D01*
G02X173908Y115472I-2J-204D01*
G02X174064Y115274I-48J-198D01*
G01Y114313D01*
X173349Y113222D01*
X173222Y113026D01*
G03X173214Y112821I168J-109D01*
G01X174064Y111520D01*
Y110564D01*
G02X174011Y110426I-203J-1D01*
G02X173861Y110360I-150J137D01*
G01X170961D01*
G02X170914Y110366I2J204D01*
G02X170758Y110564I48J198D01*
G01Y111520D01*
X170784Y111561D01*
X170786Y111564D01*
X170787Y111566D01*
G02X170789Y111569I167J-109D01*
G01X170791Y111572D01*
X170943Y111805D01*
X171600Y112815D01*
G03Y113033I-168J109D01*
G01X171522Y113152D01*
X170758Y114318D01*
Y115274D01*
G02X170811Y115412I203J1D01*
G37*
G36*
G01X273173D02*
G02X273323Y115478I150J-137D01*
G01X276223D01*
G02X276270Y115472I-2J-204D01*
G02X276426Y115274I-48J-198D01*
G01Y114313D01*
X275711Y113222D01*
X275584Y113026D01*
G03X275576Y112821I168J-109D01*
G01X276426Y111520D01*
Y110564D01*
G02X276373Y110426I-203J-1D01*
G02X276223Y110360I-150J137D01*
G01X273323D01*
G02X273276Y110366I2J204D01*
G02X273120Y110564I48J198D01*
G01Y111520D01*
X273146Y111561D01*
X273148Y111564D01*
X273149Y111566D01*
G02X273151Y111569I167J-109D01*
G01X273153Y111572D01*
X273305Y111805D01*
X273962Y112815D01*
G03Y113033I-168J109D01*
G01X273884Y113152D01*
X273120Y114318D01*
Y115274D01*
G02X273173Y115412I203J1D01*
G37*
G36*
G01X375589Y115453D02*
G02X375685Y115478I98J-178D01*
G01X378585D01*
G02X378632Y115472I-2J-204D01*
G01X378633D01*
G02X378788Y115274I-49J-198D01*
G01Y114313D01*
X378134Y113315D01*
X378073Y113222D01*
X377946Y113026D01*
G03X377938Y112821I168J-109D01*
G01X378788Y111520D01*
Y110564D01*
G02X378681Y110385I-203J0D01*
G02X378585Y110360I-98J178D01*
G01X375685D01*
G02X375638Y110366I2J204D01*
G01X375637D01*
G02X375482Y110564I49J198D01*
G01Y111520D01*
X375502Y111551D01*
X375504Y111555D01*
X375517Y111577D01*
G02X375534Y111601I170J-103D01*
G01X375753Y111937D01*
X376324Y112815D01*
G03Y113033I-168J109D01*
G01X376246Y113152D01*
X376052Y113449D01*
X375482Y114318D01*
Y115274D01*
G02X375589Y115453I203J0D01*
G37*
G36*
G01X832568Y115274D02*
G02X832772Y115478I204J0D01*
G01X835672D01*
G02X835876Y115274I0J-204D01*
G01Y114313D01*
X835857Y114284D01*
X835850Y114274D01*
X835845Y114266D01*
X835844Y114264D01*
X835766Y114146D01*
X835756Y114131D01*
X835019Y113007D01*
G03X835029Y112815I180J-87D01*
G01X835034Y112807D01*
X835042Y112796D01*
X835091Y112721D01*
X835300Y112401D01*
X835843Y111570D01*
X835844Y111569D01*
X835860Y111545D01*
X835861Y111543D01*
X835876Y111520D01*
Y110564D01*
G02X835672Y110360I-204J0D01*
G01X832772D01*
G02X832568Y110564I0J204D01*
G01Y111520D01*
X832583Y111543D01*
X832584Y111545D01*
X832592Y111557D01*
G02X832594Y111561I180J-88D01*
G01X833036Y112238D01*
X833073Y112295D01*
X833411Y112815D01*
G03X833410Y113033I-168J108D01*
G01X832600Y114269D01*
X832599Y114271D01*
X832591Y114283D01*
X832590Y114285D01*
X832568Y114318D01*
Y115274D01*
G37*
G36*
G01X1187292D02*
G02X1187496Y115478I204J0D01*
G01X1190396D01*
G02X1190600Y115274I0J-204D01*
G01Y114313D01*
X1190581Y114284D01*
X1190574Y114274D01*
X1190569Y114266D01*
X1190568Y114264D01*
X1190490Y114146D01*
X1190480Y114131D01*
X1189743Y113007D01*
G03X1189753Y112815I180J-87D01*
G01X1189758Y112807D01*
X1189766Y112796D01*
X1189815Y112721D01*
X1190024Y112401D01*
X1190567Y111570D01*
X1190568Y111569D01*
X1190584Y111545D01*
X1190585Y111543D01*
X1190600Y111520D01*
Y110564D01*
G02X1190396Y110360I-204J0D01*
G01X1187496D01*
G02X1187292Y110564I0J204D01*
G01Y111520D01*
X1187307Y111543D01*
X1187308Y111545D01*
X1187316Y111557D01*
G02X1187318Y111561I180J-88D01*
G01X1187760Y112238D01*
X1187797Y112295D01*
X1188135Y112815D01*
G03X1188134Y113033I-168J108D01*
G01X1187324Y114269D01*
X1187323Y114271D01*
X1187315Y114283D01*
X1187314Y114285D01*
X1187292Y114318D01*
Y115274D01*
G37*
G36*
G01X1289654D02*
G02X1289858Y115478I204J0D01*
G01X1292758D01*
G02X1292962Y115274I0J-204D01*
G01Y114313D01*
X1292943Y114284D01*
X1292936Y114274D01*
X1292931Y114266D01*
X1292930Y114264D01*
X1292852Y114146D01*
X1292842Y114131D01*
X1292105Y113007D01*
G03X1292115Y112815I180J-87D01*
G01X1292120Y112807D01*
X1292128Y112796D01*
X1292177Y112721D01*
X1292386Y112401D01*
X1292929Y111570D01*
X1292930Y111569D01*
X1292946Y111545D01*
X1292947Y111543D01*
X1292962Y111520D01*
Y110564D01*
G02X1292758Y110360I-204J0D01*
G01X1289858D01*
G02X1289654Y110564I0J204D01*
G01Y111520D01*
X1289669Y111543D01*
X1289670Y111545D01*
X1289678Y111557D01*
G02X1289680Y111561I180J-88D01*
G01X1290122Y112238D01*
X1290159Y112295D01*
X1290497Y112815D01*
G03X1290496Y113033I-168J108D01*
G01X1289686Y114269D01*
X1289685Y114271D01*
X1289677Y114283D01*
X1289676Y114285D01*
X1289654Y114318D01*
Y115274D01*
G37*
G36*
G01X1439763Y115453D02*
G02X1439859Y115478I98J-178D01*
G01X1442759D01*
G02X1442806Y115472I-2J-204D01*
G01X1442807D01*
G02X1442962Y115274I-49J-198D01*
G01Y114313D01*
X1442308Y113315D01*
X1442247Y113222D01*
X1442120Y113026D01*
G03X1442112Y112821I168J-109D01*
G01X1442962Y111520D01*
Y110564D01*
G02X1442855Y110385I-203J0D01*
G02X1442759Y110360I-98J178D01*
G01X1439859D01*
G02X1439812Y110366I2J204D01*
G01X1439811D01*
G02X1439656Y110564I49J198D01*
G01Y111520D01*
X1439676Y111551D01*
X1439678Y111555D01*
X1439691Y111577D01*
G02X1439708Y111601I171J-103D01*
G01X1439927Y111937D01*
X1440498Y112815D01*
G03Y113033I-168J109D01*
G01X1440420Y113152D01*
X1440226Y113449D01*
X1439656Y114318D01*
Y115274D01*
G02X1439763Y115453I203J0D01*
G37*
G36*
G01X1542071Y115412D02*
G02X1542221Y115478I150J-137D01*
G01X1545121D01*
G02X1545168Y115472I-2J-204D01*
G02X1545324Y115274I-48J-198D01*
G01Y114313D01*
X1544609Y113222D01*
X1544482Y113026D01*
G03X1544474Y112821I168J-109D01*
G01X1545324Y111520D01*
Y110564D01*
G02X1545271Y110426I-203J-1D01*
G02X1545121Y110360I-150J137D01*
G01X1542221D01*
G02X1542174Y110366I2J204D01*
G02X1542018Y110564I48J198D01*
G01Y111520D01*
X1542044Y111561D01*
X1542046Y111564D01*
X1542047Y111566D01*
G02X1542049Y111569I167J-109D01*
G01X1542051Y111572D01*
X1542289Y111937D01*
X1542311Y111971D01*
X1542390Y112093D01*
X1542837Y112778D01*
G03X1542860Y112871I-177J93D01*
G01Y112973D01*
G03X1542827Y113083I-200J0D01*
G01X1542732Y113228D01*
X1542486Y113604D01*
X1542018Y114318D01*
Y115274D01*
G02X1542071Y115412I203J1D01*
G37*
G36*
G01X1644433D02*
G02X1644583Y115478I150J-137D01*
G01X1647483D01*
G02X1647530Y115472I-2J-204D01*
G02X1647686Y115274I-48J-198D01*
G01Y114313D01*
X1646971Y113222D01*
X1646844Y113026D01*
G03X1646836Y112821I168J-109D01*
G01X1647686Y111520D01*
Y110564D01*
G02X1647633Y110426I-203J-1D01*
G02X1647483Y110360I-150J137D01*
G01X1644583D01*
G02X1644536Y110366I2J204D01*
G02X1644380Y110564I48J198D01*
G01Y111520D01*
X1644406Y111561D01*
X1644408Y111564D01*
X1644409Y111566D01*
G02X1644411Y111569I167J-109D01*
G01X1644413Y111572D01*
X1644651Y111937D01*
X1644673Y111971D01*
X1644752Y112093D01*
X1645199Y112778D01*
G03X1645222Y112871I-177J93D01*
G01Y112973D01*
G03X1645189Y113083I-200J0D01*
G01X1645094Y113228D01*
X1644848Y113604D01*
X1644380Y114318D01*
Y115274D01*
G02X1644433Y115412I203J1D01*
G37*
G36*
G01X1746849Y115453D02*
G02X1746945Y115478I98J-178D01*
G01X1749845D01*
G02X1749892Y115472I-2J-204D01*
G01X1749893D01*
G02X1750048Y115274I-49J-198D01*
G01Y114313D01*
X1749394Y113315D01*
X1749333Y113222D01*
X1749206Y113026D01*
G03X1749198Y112821I168J-109D01*
G01X1750048Y111520D01*
Y110564D01*
G02X1749941Y110385I-203J0D01*
G02X1749845Y110360I-98J178D01*
G01X1746945D01*
G02X1746898Y110366I2J204D01*
G01X1746897D01*
G02X1746742Y110564I49J198D01*
G01Y111520D01*
X1746762Y111551D01*
X1746764Y111555D01*
X1746777Y111577D01*
G02X1746794Y111601I171J-103D01*
G01X1747013Y111937D01*
X1747584Y112815D01*
G03Y113033I-168J109D01*
G01X1747506Y113152D01*
X1747312Y113449D01*
X1746742Y114318D01*
Y115274D01*
G02X1746849Y115453I203J0D01*
G37*
G36*
G01X78905Y122565D02*
G02X79001Y122590I98J-178D01*
G01X81901D01*
G02X81948Y122584I-2J-204D01*
G01X81949D01*
G02X82104Y122386I-49J-198D01*
G01Y121425D01*
X81450Y120427D01*
X81389Y120334D01*
X81262Y120138D01*
G03X81254Y119933I168J-109D01*
G01X82104Y118632D01*
Y117676D01*
G02X81997Y117497I-203J0D01*
G02X81901Y117472I-98J178D01*
G01X79001D01*
G02X78954Y117478I2J204D01*
G01X78953D01*
G02X78798Y117676I49J198D01*
G01Y118632D01*
X78818Y118663D01*
X78820Y118667D01*
X78833Y118689D01*
G02X78850Y118713I170J-103D01*
G01X79069Y119049D01*
X79145Y119166D01*
X79637Y119921D01*
G03X79664Y120022I-173J100D01*
G01Y120049D01*
G03X79631Y120159I-200J0D01*
G01X79614Y120185D01*
X78798Y121430D01*
Y122386D01*
G02X78905Y122565I203J0D01*
G37*
G36*
G01X181213Y122524D02*
G02X181363Y122590I150J-137D01*
G01X184263D01*
G02X184310Y122584I-2J-204D01*
G02X184466Y122386I-48J-198D01*
G01Y121425D01*
X183751Y120334D01*
X183624Y120138D01*
G03X183616Y119933I168J-109D01*
G01X184466Y118632D01*
Y117676D01*
G02X184413Y117538I-203J-1D01*
G02X184263Y117472I-150J137D01*
G01X181363D01*
G02X181316Y117478I2J204D01*
G02X181160Y117676I48J198D01*
G01Y118632D01*
X181186Y118673D01*
X181188Y118676D01*
X181189Y118678D01*
G02X181191Y118681I167J-109D01*
G01X181193Y118684D01*
X181345Y118917D01*
X182002Y119927D01*
G03Y120145I-168J109D01*
G01X181924Y120264D01*
X181160Y121430D01*
Y122386D01*
G02X181213Y122524I203J1D01*
G37*
G36*
G01X283575D02*
G02X283725Y122590I150J-137D01*
G01X286625D01*
G02X286672Y122584I-2J-204D01*
G02X286828Y122386I-48J-198D01*
G01Y121425D01*
X286113Y120334D01*
X285986Y120138D01*
G03X285978Y119933I168J-109D01*
G01X286828Y118632D01*
Y117676D01*
G02X286775Y117538I-203J-1D01*
G02X286625Y117472I-150J137D01*
G01X283725D01*
G02X283678Y117478I2J204D01*
G02X283522Y117676I48J198D01*
G01Y118632D01*
X283548Y118673D01*
X283550Y118676D01*
X283551Y118678D01*
G02X283553Y118681I167J-109D01*
G01X283555Y118684D01*
X283707Y118917D01*
X284364Y119927D01*
G03Y120145I-168J109D01*
G01X284286Y120264D01*
X283522Y121430D01*
Y122386D01*
G02X283575Y122524I203J1D01*
G37*
G36*
G01X385937D02*
G02X386087Y122590I150J-137D01*
G01X388987D01*
G02X389034Y122584I-2J-204D01*
G02X389190Y122386I-48J-198D01*
G01Y121425D01*
X388475Y120334D01*
X388348Y120138D01*
G03X388340Y119933I168J-109D01*
G01X389190Y118632D01*
Y117676D01*
G02X389137Y117538I-203J-1D01*
G02X388987Y117472I-150J137D01*
G01X386087D01*
G02X386040Y117478I2J204D01*
G02X385884Y117676I48J198D01*
G01Y118632D01*
X385910Y118673D01*
X385912Y118676D01*
X385913Y118678D01*
G02X385915Y118681I167J-109D01*
G01X385917Y118684D01*
X386155Y119049D01*
X386177Y119083D01*
X386256Y119205D01*
X386703Y119890D01*
G03X386726Y119983I-177J93D01*
G01Y120085D01*
G03X386693Y120195I-200J0D01*
G01X386598Y120340D01*
X386352Y120716D01*
X385884Y121430D01*
Y122386D01*
G02X385937Y122524I203J1D01*
G37*
G36*
G01X535884Y122386D02*
G02X536088Y122590I204J0D01*
G01X538988D01*
G02X539192Y122386I0J-204D01*
G01Y121425D01*
X539173Y121396D01*
X539166Y121386D01*
X539161Y121378D01*
X539160Y121376D01*
X539082Y121258D01*
X539072Y121243D01*
X538335Y120119D01*
G03X538345Y119927I180J-87D01*
G01X538350Y119919D01*
X538358Y119908D01*
X538407Y119833D01*
X538616Y119513D01*
X539159Y118682D01*
X539160Y118681D01*
X539176Y118657D01*
X539177Y118655D01*
X539192Y118632D01*
Y117676D01*
G02X538988Y117472I-204J0D01*
G01X536088D01*
G02X535884Y117676I0J204D01*
G01Y118632D01*
X535899Y118655D01*
X535900Y118657D01*
X535908Y118669D01*
G02X535910Y118673I180J-88D01*
G01X536352Y119350D01*
X536389Y119407D01*
X536727Y119927D01*
G03X536726Y120145I-168J108D01*
G01X535916Y121381D01*
X535915Y121383D01*
X535907Y121395D01*
X535906Y121397D01*
X535884Y121430D01*
Y122386D01*
G37*
G36*
G01X740608D02*
G02X740812Y122590I204J0D01*
G01X743712D01*
G02X743916Y122386I0J-204D01*
G01Y121425D01*
X743897Y121396D01*
X743890Y121386D01*
X743885Y121378D01*
X743884Y121376D01*
X743806Y121258D01*
X743796Y121243D01*
X743059Y120119D01*
G03X743069Y119927I180J-87D01*
G01X743074Y119919D01*
X743082Y119908D01*
X743131Y119833D01*
X743340Y119513D01*
X743883Y118682D01*
X743884Y118681D01*
X743900Y118657D01*
X743901Y118655D01*
X743916Y118632D01*
Y117676D01*
G02X743712Y117472I-204J0D01*
G01X740812D01*
G02X740608Y117676I0J204D01*
G01Y118632D01*
X740623Y118655D01*
X740624Y118657D01*
X740632Y118669D01*
G02X740634Y118673I180J-88D01*
G01X741076Y119350D01*
X741113Y119407D01*
X741451Y119927D01*
G03X741450Y120145I-168J108D01*
G01X740640Y121381D01*
X740639Y121383D01*
X740631Y121395D01*
X740630Y121397D01*
X740608Y121430D01*
Y122386D01*
G37*
G36*
G01X1450165Y122565D02*
G02X1450261Y122590I98J-178D01*
G01X1453161D01*
G02X1453208Y122584I-2J-204D01*
G01X1453209D01*
G02X1453364Y122386I-49J-198D01*
G01Y121425D01*
X1452710Y120427D01*
X1452649Y120334D01*
X1452522Y120138D01*
G03X1452514Y119933I168J-109D01*
G01X1453364Y118632D01*
Y117676D01*
G02X1453257Y117497I-203J0D01*
G02X1453161Y117472I-98J178D01*
G01X1450261D01*
G02X1450214Y117478I2J204D01*
G01X1450213D01*
G02X1450058Y117676I49J198D01*
G01Y118632D01*
X1450078Y118663D01*
X1450080Y118667D01*
X1450093Y118689D01*
G02X1450110Y118713I171J-103D01*
G01X1450329Y119049D01*
X1450900Y119927D01*
G03Y120145I-168J109D01*
G01X1450822Y120264D01*
X1450628Y120561D01*
X1450058Y121430D01*
Y122386D01*
G02X1450165Y122565I203J0D01*
G37*
G36*
G01X1552473Y122524D02*
G02X1552623Y122590I150J-137D01*
G01X1555523D01*
G02X1555570Y122584I-2J-204D01*
G02X1555726Y122386I-48J-198D01*
G01Y121425D01*
X1555011Y120334D01*
X1554884Y120138D01*
G03X1554876Y119933I168J-109D01*
G01X1555726Y118632D01*
Y117676D01*
G02X1555673Y117538I-203J-1D01*
G02X1555523Y117472I-150J137D01*
G01X1552623D01*
G02X1552576Y117478I2J204D01*
G02X1552420Y117676I48J198D01*
G01Y118632D01*
X1552446Y118673D01*
X1552448Y118676D01*
X1552449Y118678D01*
G02X1552451Y118681I167J-109D01*
G01X1552453Y118684D01*
X1552691Y119049D01*
X1552713Y119083D01*
X1552792Y119205D01*
X1553239Y119890D01*
G03X1553262Y119983I-177J93D01*
G01Y120085D01*
G03X1553229Y120195I-200J0D01*
G01X1553134Y120340D01*
X1552888Y120716D01*
X1552420Y121430D01*
Y122386D01*
G02X1552473Y122524I203J1D01*
G37*
G36*
G01X1654835D02*
G02X1654985Y122590I150J-137D01*
G01X1657885D01*
G02X1657932Y122584I-2J-204D01*
G02X1658088Y122386I-48J-198D01*
G01Y121425D01*
X1657373Y120334D01*
X1657246Y120138D01*
G03X1657238Y119933I168J-109D01*
G01X1658088Y118632D01*
Y117676D01*
G02X1658035Y117538I-203J-1D01*
G02X1657885Y117472I-150J137D01*
G01X1654985D01*
G02X1654938Y117478I2J204D01*
G02X1654782Y117676I48J198D01*
G01Y118632D01*
X1654808Y118673D01*
X1654810Y118676D01*
X1654811Y118678D01*
G02X1654813Y118681I167J-109D01*
G01X1654815Y118684D01*
X1655053Y119049D01*
X1655075Y119083D01*
X1655154Y119205D01*
X1655601Y119890D01*
G03X1655624Y119983I-177J93D01*
G01Y120085D01*
G03X1655591Y120195I-200J0D01*
G01X1655496Y120340D01*
X1655250Y120716D01*
X1654782Y121430D01*
Y122386D01*
G02X1654835Y122524I203J1D01*
G37*
G36*
G01X1757197D02*
G02X1757347Y122590I150J-137D01*
G01X1760247D01*
G02X1760294Y122584I-2J-204D01*
G02X1760450Y122386I-48J-198D01*
G01Y121425D01*
X1759735Y120334D01*
X1759608Y120138D01*
G03X1759600Y119933I168J-109D01*
G01X1760450Y118632D01*
Y117676D01*
G02X1760397Y117538I-203J-1D01*
G02X1760247Y117472I-150J137D01*
G01X1757347D01*
G02X1757300Y117478I2J204D01*
G02X1757144Y117676I48J198D01*
G01Y118632D01*
X1757170Y118673D01*
X1757172Y118676D01*
X1757173Y118678D01*
G02X1757175Y118681I167J-109D01*
G01X1757177Y118684D01*
X1757415Y119049D01*
X1757437Y119083D01*
X1757516Y119205D01*
X1757963Y119890D01*
G03X1757986Y119983I-177J93D01*
G01Y120085D01*
G03X1757953Y120195I-200J0D01*
G01X1757858Y120340D01*
X1757612Y120716D01*
X1757144Y121430D01*
Y122386D01*
G02X1757197Y122524I203J1D01*
G37*
G36*
G01X68396Y129447D02*
G02X68599Y129650I203J0D01*
G01X71499D01*
G02X71702Y129447I0J-203D01*
G01Y128486D01*
X70987Y127395D01*
X70860Y127199D01*
G03X70852Y126994I168J-109D01*
G01X71702Y125693D01*
Y124737D01*
G02X71499Y124534I-203J0D01*
G01X68599D01*
G02X68396Y124737I0J203D01*
G01Y125693D01*
X68422Y125734D01*
X68424Y125737D01*
X68425Y125739D01*
G02X68427Y125742I167J-109D01*
G01X68429Y125745D01*
X68581Y125978D01*
X69238Y126988D01*
G03Y127206I-168J109D01*
G01X69160Y127325D01*
X68396Y128491D01*
Y129447D01*
G37*
G36*
G01X170758D02*
G02X170961Y129650I203J0D01*
G01X173861D01*
G02X174064Y129447I0J-203D01*
G01Y128486D01*
X173349Y127395D01*
X173222Y127199D01*
G03X173214Y126994I168J-109D01*
G01X174064Y125693D01*
Y124737D01*
G02X173861Y124534I-203J0D01*
G01X170961D01*
G02X170758Y124737I0J203D01*
G01Y125693D01*
X170784Y125734D01*
X170786Y125737D01*
X170787Y125739D01*
G02X170789Y125742I167J-109D01*
G01X170791Y125745D01*
X170943Y125978D01*
X171600Y126988D01*
G03Y127206I-168J109D01*
G01X171522Y127325D01*
X170758Y128491D01*
Y129447D01*
G37*
G36*
G01X273120D02*
G02X273323Y129650I203J0D01*
G01X276223D01*
G02X276426Y129447I0J-203D01*
G01Y128486D01*
X275711Y127395D01*
X275584Y127199D01*
G03X275576Y126994I168J-109D01*
G01X276426Y125693D01*
Y124737D01*
G02X276223Y124534I-203J0D01*
G01X273323D01*
G02X273120Y124737I0J203D01*
G01Y125693D01*
X273146Y125734D01*
X273148Y125737D01*
X273149Y125739D01*
G02X273151Y125742I167J-109D01*
G01X273153Y125745D01*
X273305Y125978D01*
X273962Y126988D01*
G03Y127206I-168J109D01*
G01X273884Y127325D01*
X273120Y128491D01*
Y129447D01*
G37*
G36*
G01X375482D02*
G02X375685Y129650I203J0D01*
G01X378585D01*
G02X378788Y129447I0J-203D01*
G01Y128486D01*
X378073Y127395D01*
X377946Y127199D01*
G03X377938Y126994I168J-109D01*
G01X378788Y125693D01*
Y124737D01*
G02X378585Y124534I-203J0D01*
G01X375685D01*
G02X375482Y124737I0J203D01*
G01Y125693D01*
X375508Y125734D01*
X375510Y125737D01*
X375511Y125739D01*
G02X375513Y125742I167J-109D01*
G01X375515Y125745D01*
X375753Y126110D01*
X375775Y126144D01*
X375854Y126266D01*
X376301Y126951D01*
G03X376324Y127044I-177J93D01*
G01Y127146D01*
G03X376291Y127256I-200J0D01*
G01X376196Y127401D01*
X375950Y127777D01*
X375482Y128491D01*
Y129447D01*
G37*
G36*
G01X1439656D02*
G02X1439859Y129650I203J0D01*
G01X1442759D01*
G02X1442962Y129447I0J-203D01*
G01Y128486D01*
X1442247Y127395D01*
X1442120Y127199D01*
G03X1442112Y126994I168J-109D01*
G01X1442962Y125693D01*
Y124737D01*
G02X1442759Y124534I-203J0D01*
G01X1439859D01*
G02X1439656Y124737I0J203D01*
G01Y125693D01*
X1439682Y125734D01*
X1439684Y125737D01*
X1439685Y125739D01*
G02X1439687Y125742I167J-109D01*
G01X1439689Y125745D01*
X1439927Y126110D01*
X1439949Y126144D01*
X1440028Y126266D01*
X1440475Y126951D01*
G03X1440498Y127044I-177J93D01*
G01Y127146D01*
G03X1440465Y127256I-200J0D01*
G01X1440370Y127401D01*
X1440124Y127777D01*
X1439656Y128491D01*
Y129447D01*
G37*
G36*
G01X1542018D02*
G02X1542221Y129650I203J0D01*
G01X1545121D01*
G02X1545324Y129447I0J-203D01*
G01Y128486D01*
X1544609Y127395D01*
X1544482Y127199D01*
G03X1544474Y126994I168J-109D01*
G01X1545324Y125693D01*
Y124737D01*
G02X1545121Y124534I-203J0D01*
G01X1542221D01*
G02X1542018Y124737I0J203D01*
G01Y125693D01*
X1542044Y125734D01*
X1542046Y125737D01*
X1542047Y125739D01*
G02X1542049Y125742I167J-109D01*
G01X1542051Y125745D01*
X1542289Y126110D01*
X1542311Y126144D01*
X1542390Y126266D01*
X1542837Y126951D01*
G03X1542860Y127044I-177J93D01*
G01Y127146D01*
G03X1542827Y127256I-200J0D01*
G01X1542732Y127401D01*
X1542486Y127777D01*
X1542018Y128491D01*
Y129447D01*
G37*
G36*
G01X1644380D02*
G02X1644583Y129650I203J0D01*
G01X1647483D01*
G02X1647686Y129447I0J-203D01*
G01Y128486D01*
X1646971Y127395D01*
X1646844Y127199D01*
G03X1646836Y126994I168J-109D01*
G01X1647686Y125693D01*
Y124737D01*
G02X1647483Y124534I-203J0D01*
G01X1644583D01*
G02X1644380Y124737I0J203D01*
G01Y125693D01*
X1644406Y125734D01*
X1644408Y125737D01*
X1644409Y125739D01*
G02X1644411Y125742I167J-109D01*
G01X1644413Y125745D01*
X1644651Y126110D01*
X1644673Y126144D01*
X1644752Y126266D01*
X1645199Y126951D01*
G03X1645222Y127044I-177J93D01*
G01Y127146D01*
G03X1645189Y127256I-200J0D01*
G01X1645094Y127401D01*
X1644848Y127777D01*
X1644380Y128491D01*
Y129447D01*
G37*
G36*
G01X1746742D02*
G02X1746945Y129650I203J0D01*
G01X1749845D01*
G02X1750048Y129447I0J-203D01*
G01Y128486D01*
X1749333Y127395D01*
X1749206Y127199D01*
G03X1749198Y126994I168J-109D01*
G01X1750048Y125693D01*
Y124737D01*
G02X1749845Y124534I-203J0D01*
G01X1746945D01*
G02X1746742Y124737I0J203D01*
G01Y125693D01*
X1746768Y125734D01*
X1746770Y125737D01*
X1746771Y125739D01*
G02X1746773Y125742I167J-109D01*
G01X1746775Y125745D01*
X1747013Y126110D01*
X1747035Y126144D01*
X1747114Y126266D01*
X1747561Y126951D01*
G03X1747584Y127044I-177J93D01*
G01Y127146D01*
G03X1747551Y127256I-200J0D01*
G01X1747456Y127401D01*
X1747210Y127777D01*
X1746742Y128491D01*
Y129447D01*
G37*
G36*
G01X78851Y136698D02*
G02X79001Y136764I150J-137D01*
G01X81901D01*
G02X81948Y136758I-2J-204D01*
G02X82104Y136560I-48J-198D01*
G01Y135599D01*
X81389Y134508D01*
X81262Y134312D01*
G03X81254Y134107I168J-109D01*
G01X82104Y132806D01*
Y131850D01*
G02X82051Y131712I-203J-1D01*
G02X81901Y131646I-150J137D01*
G01X79001D01*
G02X78954Y131652I2J204D01*
G02X78798Y131850I48J198D01*
G01Y132806D01*
X78824Y132847D01*
X78826Y132850D01*
X78827Y132852D01*
G02X78829Y132855I167J-109D01*
G01X78831Y132858D01*
X78983Y133091D01*
X79640Y134101D01*
G03Y134319I-168J109D01*
G01X79562Y134438D01*
X78798Y135604D01*
Y136560D01*
G02X78851Y136698I203J1D01*
G37*
G36*
G01X181213D02*
G02X181363Y136764I150J-137D01*
G01X184263D01*
G02X184310Y136758I-2J-204D01*
G02X184466Y136560I-48J-198D01*
G01Y135599D01*
X183751Y134508D01*
X183624Y134312D01*
G03X183616Y134107I168J-109D01*
G01X184466Y132806D01*
Y131850D01*
G02X184413Y131712I-203J-1D01*
G02X184263Y131646I-150J137D01*
G01X181363D01*
G02X181316Y131652I2J204D01*
G02X181160Y131850I48J198D01*
G01Y132806D01*
X181186Y132847D01*
X181188Y132850D01*
X181189Y132852D01*
G02X181191Y132855I167J-109D01*
G01X181193Y132858D01*
X181345Y133091D01*
X182002Y134101D01*
G03Y134319I-168J109D01*
G01X181924Y134438D01*
X181160Y135604D01*
Y136560D01*
G02X181213Y136698I203J1D01*
G37*
G36*
G01X283575D02*
G02X283725Y136764I150J-137D01*
G01X286625D01*
G02X286672Y136758I-2J-204D01*
G02X286828Y136560I-48J-198D01*
G01Y135599D01*
X286113Y134508D01*
X285986Y134312D01*
G03X285978Y134107I168J-109D01*
G01X286828Y132806D01*
Y131850D01*
G02X286775Y131712I-203J-1D01*
G02X286625Y131646I-150J137D01*
G01X283725D01*
G02X283678Y131652I2J204D01*
G02X283522Y131850I48J198D01*
G01Y132806D01*
X283548Y132847D01*
X283550Y132850D01*
X283551Y132852D01*
G02X283553Y132855I167J-109D01*
G01X283555Y132858D01*
X283707Y133091D01*
X284364Y134101D01*
G03Y134319I-168J109D01*
G01X284286Y134438D01*
X283522Y135604D01*
Y136560D01*
G02X283575Y136698I203J1D01*
G37*
G36*
G01X385937D02*
G02X386087Y136764I150J-137D01*
G01X388987D01*
G02X389034Y136758I-2J-204D01*
G02X389190Y136560I-48J-198D01*
G01Y135599D01*
X388475Y134508D01*
X388348Y134312D01*
G03X388340Y134107I168J-109D01*
G01X389190Y132806D01*
Y131850D01*
G02X389137Y131712I-203J-1D01*
G02X388987Y131646I-150J137D01*
G01X386087D01*
G02X386040Y131652I2J204D01*
G02X385884Y131850I48J198D01*
G01Y132806D01*
X385910Y132847D01*
X385912Y132850D01*
X385913Y132852D01*
G02X385915Y132855I167J-109D01*
G01X385917Y132858D01*
X386155Y133223D01*
X386177Y133257D01*
X386256Y133379D01*
X386703Y134064D01*
G03X386726Y134157I-177J93D01*
G01Y134259D01*
G03X386693Y134369I-200J0D01*
G01X386598Y134514D01*
X386352Y134890D01*
X385884Y135604D01*
Y136560D01*
G02X385937Y136698I203J1D01*
G37*
G36*
G01X535884Y136560D02*
G02X536088Y136764I204J0D01*
G01X538988D01*
G02X539192Y136560I0J-204D01*
G01Y135599D01*
X539173Y135570D01*
X539166Y135560D01*
X539161Y135552D01*
X539160Y135550D01*
X539082Y135432D01*
X539072Y135417D01*
X538335Y134293D01*
G03X538345Y134101I180J-87D01*
G01X538350Y134093D01*
X538358Y134082D01*
X538407Y134007D01*
X538616Y133687D01*
X539159Y132856D01*
X539160Y132855D01*
X539176Y132831D01*
X539177Y132829D01*
X539192Y132806D01*
Y131850D01*
G02X538988Y131646I-204J0D01*
G01X536088D01*
G02X535884Y131850I0J204D01*
G01Y132806D01*
X535899Y132829D01*
X535900Y132831D01*
X535908Y132843D01*
G02X535910Y132847I180J-88D01*
G01X536352Y133524D01*
X536389Y133581D01*
X536727Y134101D01*
G03X536726Y134319I-168J108D01*
G01X535916Y135555D01*
X535915Y135557D01*
X535907Y135569D01*
X535906Y135571D01*
X535884Y135604D01*
Y136560D01*
G37*
G36*
G01X1095332D02*
G02X1095536Y136764I204J0D01*
G01X1098436D01*
G02X1098640Y136560I0J-204D01*
G01Y135599D01*
X1098621Y135570D01*
X1098614Y135560D01*
X1098609Y135552D01*
X1098608Y135550D01*
X1098530Y135432D01*
X1098520Y135417D01*
X1097783Y134293D01*
G03X1097793Y134101I180J-87D01*
G01X1097798Y134093D01*
X1097806Y134082D01*
X1097855Y134007D01*
X1098064Y133687D01*
X1098607Y132856D01*
X1098608Y132855D01*
X1098624Y132831D01*
X1098625Y132829D01*
X1098640Y132806D01*
Y131850D01*
G02X1098436Y131646I-204J0D01*
G01X1095536D01*
G02X1095332Y131850I0J204D01*
G01Y132806D01*
X1095347Y132829D01*
X1095348Y132831D01*
X1095356Y132843D01*
G02X1095358Y132847I180J-88D01*
G01X1095800Y133524D01*
X1095837Y133581D01*
X1096175Y134101D01*
G03X1096174Y134319I-168J108D01*
G01X1095364Y135555D01*
X1095363Y135557D01*
X1095355Y135569D01*
X1095354Y135571D01*
X1095332Y135604D01*
Y136560D01*
G37*
G36*
G01X1450111Y136698D02*
G02X1450261Y136764I150J-137D01*
G01X1453161D01*
G02X1453208Y136758I-2J-204D01*
G02X1453364Y136560I-48J-198D01*
G01Y135599D01*
X1452649Y134508D01*
X1452522Y134312D01*
G03X1452514Y134107I168J-109D01*
G01X1453364Y132806D01*
Y131850D01*
G02X1453311Y131712I-203J-1D01*
G02X1453161Y131646I-150J137D01*
G01X1450261D01*
G02X1450214Y131652I2J204D01*
G02X1450058Y131850I48J198D01*
G01Y132806D01*
X1450084Y132847D01*
X1450086Y132850D01*
X1450087Y132852D01*
G02X1450089Y132855I167J-109D01*
G01X1450091Y132858D01*
X1450329Y133223D01*
X1450351Y133257D01*
X1450430Y133379D01*
X1450877Y134064D01*
G03X1450900Y134157I-177J93D01*
G01Y134259D01*
G03X1450867Y134369I-200J0D01*
G01X1450772Y134514D01*
X1450526Y134890D01*
X1450058Y135604D01*
Y136560D01*
G02X1450111Y136698I203J1D01*
G37*
G36*
G01X1552473D02*
G02X1552623Y136764I150J-137D01*
G01X1555523D01*
G02X1555570Y136758I-2J-204D01*
G02X1555726Y136560I-48J-198D01*
G01Y135599D01*
X1555011Y134508D01*
X1554884Y134312D01*
G03X1554876Y134107I168J-109D01*
G01X1555726Y132806D01*
Y131850D01*
G02X1555673Y131712I-203J-1D01*
G02X1555523Y131646I-150J137D01*
G01X1552623D01*
G02X1552576Y131652I2J204D01*
G02X1552420Y131850I48J198D01*
G01Y132806D01*
X1552446Y132847D01*
X1552448Y132850D01*
X1552449Y132852D01*
G02X1552451Y132855I167J-109D01*
G01X1552453Y132858D01*
X1552691Y133223D01*
X1552713Y133257D01*
X1552792Y133379D01*
X1553239Y134064D01*
G03X1553262Y134157I-177J93D01*
G01Y134259D01*
G03X1553229Y134369I-200J0D01*
G01X1553134Y134514D01*
X1552888Y134890D01*
X1552420Y135604D01*
Y136560D01*
G02X1552473Y136698I203J1D01*
G37*
G36*
G01X1654889Y136739D02*
G02X1654985Y136764I98J-178D01*
G01X1657885D01*
G02X1657932Y136758I-2J-204D01*
G01X1657933D01*
G02X1658088Y136560I-49J-198D01*
G01Y135599D01*
X1657434Y134601D01*
X1657373Y134508D01*
X1657246Y134312D01*
G03X1657238Y134107I168J-109D01*
G01X1658088Y132806D01*
Y131850D01*
G02X1657981Y131671I-203J0D01*
G02X1657885Y131646I-98J178D01*
G01X1654985D01*
G02X1654938Y131652I2J204D01*
G01X1654937D01*
G02X1654782Y131850I49J198D01*
G01Y132806D01*
X1654802Y132837D01*
X1654804Y132841D01*
X1654817Y132863D01*
G02X1654834Y132887I171J-103D01*
G01X1655053Y133223D01*
X1655624Y134101D01*
G03Y134319I-168J109D01*
G01X1655546Y134438D01*
X1655352Y134735D01*
X1654782Y135604D01*
Y136560D01*
G02X1654889Y136739I203J0D01*
G37*
G36*
G01X1757251D02*
G02X1757347Y136764I98J-178D01*
G01X1760247D01*
G02X1760294Y136758I-2J-204D01*
G01X1760295D01*
G02X1760450Y136560I-49J-198D01*
G01Y135599D01*
X1759796Y134601D01*
X1759735Y134508D01*
X1759608Y134312D01*
G03X1759600Y134107I168J-109D01*
G01X1760450Y132806D01*
Y131850D01*
G02X1760343Y131671I-203J0D01*
G02X1760247Y131646I-98J178D01*
G01X1757347D01*
G02X1757300Y131652I2J204D01*
G01X1757299D01*
G02X1757144Y131850I49J198D01*
G01Y132806D01*
X1757164Y132837D01*
X1757166Y132841D01*
X1757179Y132863D01*
G02X1757196Y132887I171J-103D01*
G01X1757415Y133223D01*
X1757986Y134101D01*
G03Y134319I-168J109D01*
G01X1757908Y134438D01*
X1757714Y134735D01*
X1757144Y135604D01*
Y136560D01*
G02X1757251Y136739I203J0D01*
G37*
G36*
G01X1067221Y395190D02*
G02X1067371Y395256I150J-137D01*
G01X1070271D01*
G02X1070318Y395250I-2J-204D01*
G02X1070474Y395052I-48J-198D01*
G01Y394091D01*
X1069759Y393000D01*
X1069632Y392804D01*
G03X1069624Y392599I168J-109D01*
G01X1070474Y391298D01*
Y390342D01*
G02X1070421Y390204I-203J-1D01*
G02X1070271Y390138I-150J137D01*
G01X1067371D01*
G02X1067324Y390144I2J204D01*
G02X1067168Y390342I48J198D01*
G01Y391298D01*
X1067194Y391339D01*
X1067196Y391342D01*
X1067197Y391344D01*
G02X1067199Y391347I167J-109D01*
G01X1067201Y391350D01*
X1067439Y391715D01*
X1067461Y391749D01*
X1067540Y391871D01*
X1067987Y392556D01*
G03X1068010Y392649I-177J93D01*
G01Y392751D01*
G03X1067977Y392861I-200J0D01*
G01X1067882Y393006D01*
X1067636Y393382D01*
X1067168Y394096D01*
Y395052D01*
G02X1067221Y395190I203J1D01*
G37*
G36*
G01X1059219Y402302D02*
G02X1059369Y402368I150J-137D01*
G01X1062269D01*
G02X1062316Y402362I-2J-204D01*
G02X1062472Y402164I-48J-198D01*
G01Y401203D01*
X1061757Y400112D01*
X1061630Y399916D01*
G03X1061622Y399711I168J-109D01*
G01X1062472Y398410D01*
Y397454D01*
G02X1062419Y397316I-203J-1D01*
G02X1062269Y397250I-150J137D01*
G01X1059369D01*
G02X1059322Y397256I2J204D01*
G02X1059166Y397454I48J198D01*
G01Y398410D01*
X1059192Y398451D01*
X1059194Y398454D01*
X1059195Y398456D01*
G02X1059197Y398459I167J-109D01*
G01X1059199Y398462D01*
X1059437Y398827D01*
X1059459Y398861D01*
X1059538Y398983D01*
X1059985Y399668D01*
G03X1060008Y399761I-177J93D01*
G01Y399863D01*
G03X1059975Y399973I-200J0D01*
G01X1059880Y400118D01*
X1059634Y400494D01*
X1059166Y401208D01*
Y402164D01*
G02X1059219Y402302I203J1D01*
G37*
G36*
G01X1067168Y409225D02*
G02X1067371Y409428I203J0D01*
G01X1070271D01*
G02X1070474Y409225I0J-203D01*
G01Y408264D01*
X1069820Y407266D01*
X1069759Y407173D01*
X1069632Y406977D01*
G03X1069624Y406772I168J-109D01*
G01X1070474Y405471D01*
Y404515D01*
G02X1070271Y404312I-203J0D01*
G01X1067371D01*
G02X1067168Y404515I0J203D01*
G01Y405471D01*
X1067188Y405502D01*
X1067190Y405506D01*
X1067203Y405528D01*
G02X1067220Y405552I171J-103D01*
G01X1067439Y405888D01*
X1068010Y406766D01*
G03Y406984I-168J109D01*
G01X1067932Y407103D01*
X1067738Y407400D01*
X1067168Y408269D01*
Y409225D01*
G37*
G36*
G01X1056819Y416476D02*
G02X1056969Y416542I150J-137D01*
G01X1059869D01*
G02X1059916Y416536I-2J-204D01*
G02X1060072Y416338I-48J-198D01*
G01Y415377D01*
X1059357Y414286D01*
X1059230Y414090D01*
G03X1059222Y413885I168J-109D01*
G01X1060072Y412584D01*
Y411628D01*
G02X1060019Y411490I-203J-1D01*
G02X1059869Y411424I-150J137D01*
G01X1056969D01*
G02X1056922Y411430I2J204D01*
G02X1056766Y411628I48J198D01*
G01Y412584D01*
X1056792Y412625D01*
X1056794Y412628D01*
X1056795Y412630D01*
G02X1056797Y412633I167J-109D01*
G01X1056799Y412636D01*
X1057037Y413001D01*
X1057059Y413035D01*
X1057138Y413157D01*
X1057585Y413842D01*
G03X1057608Y413935I-177J93D01*
G01Y414037D01*
G03X1057575Y414147I-200J0D01*
G01X1057480Y414292D01*
X1057234Y414668D01*
X1056766Y415382D01*
Y416338D01*
G02X1056819Y416476I203J1D01*
G37*
G36*
G01X1067221Y423536D02*
G02X1067371Y423602I150J-137D01*
G01X1070271D01*
G02X1070318Y423596I-2J-204D01*
G02X1070474Y423398I-48J-198D01*
G01Y422437D01*
X1069759Y421346D01*
X1069632Y421150D01*
G03X1069624Y420945I168J-109D01*
G01X1070474Y419644D01*
Y418688D01*
G02X1070421Y418550I-203J-1D01*
G02X1070271Y418484I-150J137D01*
G01X1067371D01*
G02X1067324Y418490I2J204D01*
G02X1067168Y418688I48J198D01*
G01Y419644D01*
X1067194Y419685D01*
X1067196Y419688D01*
X1067197Y419690D01*
G02X1067199Y419693I167J-109D01*
G01X1067201Y419696D01*
X1067439Y420061D01*
X1067461Y420095D01*
X1067540Y420217D01*
X1067987Y420902D01*
G03X1068010Y420995I-177J93D01*
G01Y421097D01*
G03X1067977Y421207I-200J0D01*
G01X1067882Y421352D01*
X1067636Y421728D01*
X1067168Y422442D01*
Y423398D01*
G02X1067221Y423536I203J1D01*
G37*
G36*
G01X599684Y430559D02*
G02X599882Y430714I198J-49D01*
G01X602782D01*
G02X602961Y430607I0J-203D01*
G02X602986Y430511I-178J-98D01*
G01Y429550D01*
X602967Y429521D01*
X602960Y429511D01*
X602955Y429503D01*
X602954Y429501D01*
X602876Y429383D01*
X602866Y429368D01*
X602129Y428244D01*
G03X602139Y428052I180J-87D01*
G01X602144Y428044D01*
X602152Y428033D01*
X602201Y427958D01*
X602410Y427638D01*
X602953Y426807D01*
X602954Y426806D01*
X602970Y426782D01*
X602971Y426780D01*
X602986Y426757D01*
Y425801D01*
G02X602980Y425754I-204J2D01*
G01Y425753D01*
G02X602782Y425598I-198J49D01*
G01X599882D01*
G02X599703Y425705I0J203D01*
G02X599678Y425801I178J98D01*
G01Y426757D01*
X599693Y426780D01*
X599694Y426782D01*
X599702Y426794D01*
G02X599704Y426798I180J-88D01*
G01X600146Y427475D01*
X600183Y427532D01*
X600521Y428052D01*
G03X600520Y428270I-168J108D01*
G01X599710Y429506D01*
X599709Y429508D01*
X599701Y429520D01*
X599700Y429522D01*
X599678Y429555D01*
Y430511D01*
G02X599684Y430558I204J-2D01*
G01Y430559D01*
G37*
G36*
G01X1056766Y430511D02*
G02X1056969Y430714I203J0D01*
G01X1059869D01*
G02X1060072Y430511I0J-203D01*
G01Y429550D01*
X1059357Y428459D01*
X1059230Y428263D01*
G03X1059222Y428058I168J-109D01*
G01X1060072Y426757D01*
Y425801D01*
G02X1059869Y425598I-203J0D01*
G01X1056969D01*
G02X1056766Y425801I0J203D01*
G01Y426757D01*
X1056792Y426798D01*
X1056794Y426801D01*
X1056795Y426803D01*
G02X1056797Y426806I167J-109D01*
G01X1056799Y426809D01*
X1057037Y427174D01*
X1057059Y427208D01*
X1057138Y427330D01*
X1057585Y428015D01*
G03X1057608Y428108I-177J93D01*
G01Y428210D01*
G03X1057575Y428320I-200J0D01*
G01X1057480Y428465D01*
X1057234Y428841D01*
X1056766Y429555D01*
Y430511D01*
G37*
G36*
G01X1513858Y430559D02*
G02X1514056Y430714I198J-49D01*
G01X1516956D01*
G02X1517135Y430607I0J-203D01*
G02X1517160Y430511I-178J-98D01*
G01Y429550D01*
X1517141Y429521D01*
X1517134Y429511D01*
X1517129Y429503D01*
X1517128Y429501D01*
X1517050Y429383D01*
X1517040Y429368D01*
X1516303Y428244D01*
G03X1516313Y428052I180J-87D01*
G01X1516318Y428044D01*
X1516326Y428033D01*
X1516375Y427958D01*
X1516584Y427638D01*
X1517127Y426807D01*
X1517128Y426806D01*
X1517144Y426782D01*
X1517145Y426780D01*
X1517160Y426757D01*
Y425801D01*
G02X1517154Y425754I-204J2D01*
G01Y425753D01*
G02X1516956Y425598I-198J49D01*
G01X1514056D01*
G02X1513877Y425705I0J203D01*
G02X1513852Y425801I178J98D01*
G01Y426757D01*
X1513867Y426780D01*
X1513868Y426782D01*
X1513876Y426794D01*
G02X1513878Y426798I180J-88D01*
G01X1514320Y427475D01*
X1514357Y427532D01*
X1514695Y428052D01*
G03X1514694Y428270I-168J108D01*
G01X1513884Y429506D01*
X1513883Y429508D01*
X1513875Y429520D01*
X1513874Y429522D01*
X1513852Y429555D01*
Y430511D01*
G02X1513858Y430558I204J-2D01*
G01Y430559D01*
G37*
G36*
G01X1067221Y437710D02*
G02X1067371Y437776I150J-137D01*
G01X1070271D01*
G02X1070318Y437770I-2J-204D01*
G02X1070474Y437572I-48J-198D01*
G01Y436611D01*
X1069759Y435520D01*
X1069632Y435324D01*
G03X1069624Y435119I168J-109D01*
G01X1070474Y433818D01*
Y432862D01*
G02X1070421Y432724I-203J-1D01*
G02X1070271Y432658I-150J137D01*
G01X1067371D01*
G02X1067324Y432664I2J204D01*
G02X1067168Y432862I48J198D01*
G01Y433818D01*
X1067194Y433859D01*
X1067196Y433862D01*
X1067197Y433864D01*
G02X1067199Y433867I167J-109D01*
G01X1067201Y433870D01*
X1067439Y434235D01*
X1067461Y434269D01*
X1067540Y434391D01*
X1067987Y435076D01*
G03X1068010Y435169I-177J93D01*
G01Y435271D01*
G03X1067977Y435381I-200J0D01*
G01X1067882Y435526D01*
X1067636Y435902D01*
X1067168Y436616D01*
Y437572D01*
G02X1067221Y437710I203J1D01*
G37*
G36*
G01X599678Y444684D02*
G02X599882Y444888I204J0D01*
G01X602782D01*
G02X602986Y444684I0J-204D01*
G01Y443723D01*
X602967Y443694D01*
X602960Y443684D01*
X602955Y443676D01*
X602954Y443674D01*
X602876Y443556D01*
X602866Y443541D01*
X602129Y442417D01*
G03X602139Y442225I180J-87D01*
G01X602144Y442217D01*
X602152Y442206D01*
X602201Y442131D01*
X602410Y441811D01*
X602953Y440980D01*
X602954Y440979D01*
X602970Y440955D01*
X602971Y440953D01*
X602986Y440930D01*
Y439974D01*
G02X602782Y439770I-204J0D01*
G01X599882D01*
G02X599678Y439974I0J204D01*
G01Y440930D01*
X599693Y440953D01*
X599694Y440955D01*
X599702Y440967D01*
G02X599704Y440971I180J-88D01*
G01X600146Y441648D01*
X600183Y441705D01*
X600521Y442225D01*
G03X600520Y442443I-168J108D01*
G01X599710Y443679D01*
X599709Y443681D01*
X599701Y443693D01*
X599700Y443695D01*
X599678Y443728D01*
Y444684D01*
G37*
G36*
G01X1056819Y444822D02*
G02X1056969Y444888I150J-137D01*
G01X1059869D01*
G02X1059916Y444882I-2J-204D01*
G02X1060072Y444684I-48J-198D01*
G01Y443723D01*
X1059357Y442632D01*
X1059230Y442436D01*
G03X1059222Y442231I168J-109D01*
G01X1060072Y440930D01*
Y439974D01*
G02X1060019Y439836I-203J-1D01*
G02X1059869Y439770I-150J137D01*
G01X1056969D01*
G02X1056922Y439776I2J204D01*
G02X1056766Y439974I48J198D01*
G01Y440930D01*
X1056792Y440971D01*
X1056794Y440974D01*
X1056795Y440976D01*
G02X1056797Y440979I167J-109D01*
G01X1056799Y440982D01*
X1057037Y441347D01*
X1057059Y441381D01*
X1057138Y441503D01*
X1057585Y442188D01*
G03X1057608Y442281I-177J93D01*
G01Y442383D01*
G03X1057575Y442493I-200J0D01*
G01X1057480Y442638D01*
X1057234Y443014D01*
X1056766Y443728D01*
Y444684D01*
G02X1056819Y444822I203J1D01*
G37*
G36*
G01X313384Y471357D02*
G02X313587Y471560I203J0D01*
G01X316487D01*
G02X316690Y471357I0J-203D01*
G01Y470396D01*
X316036Y469398D01*
X315975Y469305D01*
X315848Y469109D01*
G03X315840Y468904I168J-109D01*
G01X316690Y467603D01*
Y466647D01*
G02X316487Y466444I-203J0D01*
G01X313587D01*
G02X313384Y466647I0J203D01*
G01Y467603D01*
X313404Y467634D01*
X313406Y467638D01*
X313419Y467660D01*
G02X313436Y467684I170J-103D01*
G01X313655Y468020D01*
X314226Y468898D01*
G03Y469116I-168J109D01*
G01X314148Y469235D01*
X313954Y469532D01*
X313384Y470401D01*
Y471357D01*
G37*
G36*
G01X770470D02*
G02X770673Y471560I203J0D01*
G01X773573D01*
G02X773776Y471357I0J-203D01*
G01Y470396D01*
X773061Y469305D01*
X772934Y469109D01*
G03X772926Y468904I168J-109D01*
G01X773776Y467603D01*
Y466647D01*
G02X773573Y466444I-203J0D01*
G01X770673D01*
G02X770470Y466647I0J203D01*
G01Y467603D01*
X770496Y467644D01*
X770498Y467647D01*
X770499Y467649D01*
G02X770501Y467652I167J-109D01*
G01X770503Y467655D01*
X770741Y468020D01*
X770763Y468054D01*
X770842Y468176D01*
X771289Y468861D01*
G03X771312Y468954I-177J93D01*
G01Y469056D01*
G03X771279Y469166I-200J0D01*
G01X771184Y469311D01*
X770938Y469687D01*
X770470Y470401D01*
Y471357D01*
G37*
G36*
G01X1684644D02*
G02X1684847Y471560I203J0D01*
G01X1687747D01*
G02X1687950Y471357I0J-203D01*
G01Y470396D01*
X1687296Y469398D01*
X1687235Y469305D01*
X1687108Y469109D01*
G03X1687100Y468904I168J-109D01*
G01X1687950Y467603D01*
Y466647D01*
G02X1687747Y466444I-203J0D01*
G01X1684847D01*
G02X1684644Y466647I0J203D01*
G01Y467603D01*
X1684664Y467634D01*
X1684666Y467638D01*
X1684679Y467660D01*
G02X1684696Y467684I171J-103D01*
G01X1684915Y468020D01*
X1685486Y468898D01*
G03Y469116I-168J109D01*
G01X1685408Y469235D01*
X1685214Y469532D01*
X1684644Y470401D01*
Y471357D01*
G37*
G36*
G01X142592Y473438D02*
G02X142796Y473642I204J0D01*
G01X145696D01*
G02X145900Y473438I0J-204D01*
G01Y472477D01*
X145881Y472448D01*
X145874Y472438D01*
X145869Y472430D01*
X145868Y472428D01*
X145790Y472310D01*
X145780Y472295D01*
X145043Y471171D01*
G03X145053Y470979I180J-87D01*
G01X145058Y470971D01*
X145066Y470960D01*
X145115Y470885D01*
X145324Y470565D01*
X145867Y469734D01*
X145868Y469733D01*
X145884Y469709D01*
X145885Y469707D01*
X145900Y469684D01*
Y468728D01*
G02X145696Y468524I-204J0D01*
G01X142796D01*
G02X142592Y468728I0J204D01*
G01Y469684D01*
X142607Y469707D01*
X142608Y469709D01*
X142616Y469721D01*
G02X142618Y469725I180J-88D01*
G01X143060Y470402D01*
X143097Y470459D01*
X143435Y470979D01*
G03X143434Y471197I-168J108D01*
G01X142624Y472433D01*
X142623Y472435D01*
X142615Y472447D01*
X142614Y472449D01*
X142592Y472482D01*
Y473438D01*
G37*
G36*
G01X1056819Y473576D02*
G02X1056969Y473642I150J-137D01*
G01X1059869D01*
G02X1059916Y473636I-2J-204D01*
G02X1060072Y473438I-48J-198D01*
G01Y472477D01*
X1059357Y471386D01*
X1059230Y471190D01*
G03X1059222Y470985I168J-109D01*
G01X1060072Y469684D01*
Y468728D01*
G02X1060019Y468590I-203J-1D01*
G02X1059869Y468524I-150J137D01*
G01X1056969D01*
G02X1056922Y468530I2J204D01*
G02X1056766Y468728I48J198D01*
G01Y469684D01*
X1056792Y469725D01*
X1056794Y469728D01*
X1056795Y469730D01*
G02X1056797Y469733I167J-109D01*
G01X1056799Y469736D01*
X1057037Y470101D01*
X1057059Y470135D01*
X1057138Y470257D01*
X1057585Y470942D01*
G03X1057608Y471035I-177J93D01*
G01Y471137D01*
G03X1057575Y471247I-200J0D01*
G01X1057480Y471392D01*
X1057234Y471768D01*
X1056766Y472482D01*
Y473438D01*
G02X1056819Y473576I203J1D01*
G37*
G36*
G01X1513852Y473438D02*
G02X1514056Y473642I204J0D01*
G01X1516956D01*
G02X1517160Y473438I0J-204D01*
G01Y472477D01*
X1517141Y472448D01*
X1517134Y472438D01*
X1517129Y472430D01*
X1517128Y472428D01*
X1517050Y472310D01*
X1517040Y472295D01*
X1516303Y471171D01*
G03X1516313Y470979I180J-87D01*
G01X1516318Y470971D01*
X1516326Y470960D01*
X1516375Y470885D01*
X1516584Y470565D01*
X1517127Y469734D01*
X1517128Y469733D01*
X1517144Y469709D01*
X1517145Y469707D01*
X1517160Y469684D01*
Y468728D01*
G02X1516956Y468524I-204J0D01*
G01X1514056D01*
G02X1513852Y468728I0J204D01*
G01Y469684D01*
X1513867Y469707D01*
X1513868Y469709D01*
X1513876Y469721D01*
G02X1513878Y469725I180J-88D01*
G01X1514320Y470402D01*
X1514357Y470459D01*
X1514695Y470979D01*
G03X1514694Y471197I-168J108D01*
G01X1513884Y472433D01*
X1513883Y472435D01*
X1513875Y472447D01*
X1513874Y472449D01*
X1513852Y472482D01*
Y473438D01*
G37*
G36*
G01X323786Y478469D02*
G02X323989Y478672I203J0D01*
G01X326889D01*
G02X327092Y478469I0J-203D01*
G01Y477508D01*
X326377Y476417D01*
X326250Y476221D01*
G03X326242Y476016I168J-109D01*
G01X327092Y474715D01*
Y473759D01*
G02X326889Y473556I-203J0D01*
G01X323989D01*
G02X323786Y473759I0J203D01*
G01Y474715D01*
X323812Y474756D01*
X323814Y474759D01*
X323815Y474761D01*
G02X323817Y474764I167J-109D01*
G01X323819Y474767D01*
X324057Y475132D01*
X324079Y475166D01*
X324158Y475288D01*
X324605Y475973D01*
G03X324628Y476066I-177J93D01*
G01Y476168D01*
G03X324595Y476278I-200J0D01*
G01X324500Y476423D01*
X324254Y476799D01*
X323786Y477513D01*
Y478469D01*
G37*
G36*
G01X780872D02*
G02X781075Y478672I203J0D01*
G01X783975D01*
G02X784178Y478469I0J-203D01*
G01Y477508D01*
X783463Y476417D01*
X783336Y476221D01*
G03X783328Y476016I168J-109D01*
G01X784178Y474715D01*
Y473759D01*
G02X783975Y473556I-203J0D01*
G01X781075D01*
G02X780872Y473759I0J203D01*
G01Y474715D01*
X780898Y474756D01*
X780900Y474759D01*
X780901Y474761D01*
G02X780903Y474764I167J-109D01*
G01X780905Y474767D01*
X781143Y475132D01*
X781165Y475166D01*
X781244Y475288D01*
X781691Y475973D01*
G03X781714Y476066I-177J93D01*
G01Y476168D01*
G03X781681Y476278I-200J0D01*
G01X781586Y476423D01*
X781340Y476799D01*
X780872Y477513D01*
Y478469D01*
G37*
G36*
G01X1695046D02*
G02X1695249Y478672I203J0D01*
G01X1698149D01*
G02X1698352Y478469I0J-203D01*
G01Y477508D01*
X1697637Y476417D01*
X1697510Y476221D01*
G03X1697502Y476016I168J-109D01*
G01X1698352Y474715D01*
Y473759D01*
G02X1698149Y473556I-203J0D01*
G01X1695249D01*
G02X1695046Y473759I0J203D01*
G01Y474715D01*
X1695072Y474756D01*
X1695074Y474759D01*
X1695075Y474761D01*
G02X1695077Y474764I167J-109D01*
G01X1695079Y474767D01*
X1695317Y475132D01*
X1695339Y475166D01*
X1695418Y475288D01*
X1695865Y475973D01*
G03X1695888Y476066I-177J93D01*
G01Y476168D01*
G03X1695855Y476278I-200J0D01*
G01X1695760Y476423D01*
X1695514Y476799D01*
X1695046Y477513D01*
Y478469D01*
G37*
G36*
G01X1067221Y480688D02*
G02X1067371Y480754I150J-137D01*
G01X1070271D01*
G02X1070318Y480748I-2J-204D01*
G02X1070474Y480550I-48J-198D01*
G01Y479589D01*
X1069759Y478498D01*
X1069632Y478302D01*
G03X1069624Y478097I168J-109D01*
G01X1070474Y476796D01*
Y475840D01*
G02X1070421Y475702I-203J-1D01*
G02X1070271Y475636I-150J137D01*
G01X1067371D01*
G02X1067324Y475642I2J204D01*
G02X1067168Y475840I48J198D01*
G01Y476796D01*
X1067194Y476837D01*
X1067196Y476840D01*
X1067197Y476842D01*
G02X1067199Y476845I167J-109D01*
G01X1067201Y476848D01*
X1067439Y477213D01*
X1067461Y477247D01*
X1067540Y477369D01*
X1067987Y478054D01*
G03X1068010Y478147I-177J93D01*
G01Y478249D01*
G03X1067977Y478359I-200J0D01*
G01X1067882Y478504D01*
X1067636Y478880D01*
X1067168Y479594D01*
Y480550D01*
G02X1067221Y480688I203J1D01*
G37*
G36*
G01X313437Y485668D02*
G02X313587Y485734I150J-137D01*
G01X316487D01*
G02X316534Y485728I-2J-204D01*
G02X316690Y485530I-48J-198D01*
G01Y484569D01*
X315975Y483478D01*
X315848Y483282D01*
G03X315840Y483077I168J-109D01*
G01X316690Y481776D01*
Y480820D01*
G02X316637Y480682I-203J-1D01*
G02X316487Y480616I-150J137D01*
G01X313587D01*
G02X313540Y480622I2J204D01*
G02X313384Y480820I48J198D01*
G01Y481776D01*
X313410Y481817D01*
X313412Y481820D01*
X313413Y481822D01*
G02X313415Y481825I167J-109D01*
G01X313417Y481828D01*
X313655Y482193D01*
X313677Y482227D01*
X313756Y482349D01*
X314203Y483034D01*
G03X314226Y483127I-177J93D01*
G01Y483229D01*
G03X314193Y483339I-200J0D01*
G01X314098Y483484D01*
X313852Y483860D01*
X313384Y484574D01*
Y485530D01*
G02X313437Y485668I203J1D01*
G37*
G36*
G01X770523D02*
G02X770673Y485734I150J-137D01*
G01X773573D01*
G02X773620Y485728I-2J-204D01*
G02X773776Y485530I-48J-198D01*
G01Y484569D01*
X773061Y483478D01*
X772934Y483282D01*
G03X772926Y483077I168J-109D01*
G01X773776Y481776D01*
Y480820D01*
G02X773723Y480682I-203J-1D01*
G02X773573Y480616I-150J137D01*
G01X770673D01*
G02X770626Y480622I2J204D01*
G02X770470Y480820I48J198D01*
G01Y481776D01*
X770496Y481817D01*
X770498Y481820D01*
X770499Y481822D01*
G02X770501Y481825I167J-109D01*
G01X770503Y481828D01*
X770741Y482193D01*
X770763Y482227D01*
X770842Y482349D01*
X771289Y483034D01*
G03X771312Y483127I-177J93D01*
G01Y483229D01*
G03X771279Y483339I-200J0D01*
G01X771184Y483484D01*
X770938Y483860D01*
X770470Y484574D01*
Y485530D01*
G02X770523Y485668I203J1D01*
G37*
G36*
G01X1684697D02*
G02X1684847Y485734I150J-137D01*
G01X1687747D01*
G02X1687794Y485728I-2J-204D01*
G02X1687950Y485530I-48J-198D01*
G01Y484569D01*
X1687235Y483478D01*
X1687108Y483282D01*
G03X1687100Y483077I168J-109D01*
G01X1687950Y481776D01*
Y480820D01*
G02X1687897Y480682I-203J-1D01*
G02X1687747Y480616I-150J137D01*
G01X1684847D01*
G02X1684800Y480622I2J204D01*
G02X1684644Y480820I48J198D01*
G01Y481776D01*
X1684670Y481817D01*
X1684672Y481820D01*
X1684673Y481822D01*
G02X1684675Y481825I167J-109D01*
G01X1684677Y481828D01*
X1684915Y482193D01*
X1684937Y482227D01*
X1685016Y482349D01*
X1685463Y483034D01*
G03X1685486Y483127I-177J93D01*
G01Y483229D01*
G03X1685453Y483339I-200J0D01*
G01X1685358Y483484D01*
X1685112Y483860D01*
X1684644Y484574D01*
Y485530D01*
G02X1684697Y485668I203J1D01*
G37*
G36*
G01X1056766Y487611D02*
G02X1056969Y487814I203J0D01*
G01X1059869D01*
G02X1060072Y487611I0J-203D01*
G01Y486650D01*
X1059357Y485559D01*
X1059230Y485363D01*
G03X1059222Y485158I168J-109D01*
G01X1060072Y483857D01*
Y482901D01*
G02X1059869Y482698I-203J0D01*
G01X1056969D01*
G02X1056766Y482901I0J203D01*
G01Y483857D01*
X1056792Y483898D01*
X1056794Y483901D01*
X1056795Y483903D01*
G02X1056797Y483906I167J-109D01*
G01X1056799Y483909D01*
X1057037Y484274D01*
X1057059Y484308D01*
X1057138Y484430D01*
X1057585Y485115D01*
G03X1057608Y485208I-177J93D01*
G01Y485310D01*
G03X1057575Y485420I-200J0D01*
G01X1057480Y485565D01*
X1057234Y485941D01*
X1056766Y486655D01*
Y487611D01*
G37*
G36*
G01X1513858Y487659D02*
G02X1514056Y487814I198J-49D01*
G01X1516956D01*
G02X1517135Y487707I0J-203D01*
G02X1517160Y487611I-178J-98D01*
G01Y486650D01*
X1517141Y486621D01*
X1517134Y486611D01*
X1517129Y486603D01*
X1517128Y486601D01*
X1517050Y486483D01*
X1517040Y486468D01*
X1516303Y485344D01*
G03X1516313Y485152I180J-87D01*
G01X1516318Y485144D01*
X1516326Y485133D01*
X1516375Y485058D01*
X1516584Y484738D01*
X1517127Y483907D01*
X1517128Y483906D01*
X1517144Y483882D01*
X1517145Y483880D01*
X1517160Y483857D01*
Y482901D01*
G02X1517154Y482854I-204J2D01*
G01Y482853D01*
G02X1516956Y482698I-198J49D01*
G01X1514056D01*
G02X1513877Y482805I0J203D01*
G02X1513852Y482901I178J98D01*
G01Y483857D01*
X1513867Y483880D01*
X1513868Y483882D01*
X1513876Y483894D01*
G02X1513878Y483898I180J-88D01*
G01X1514320Y484575D01*
X1514357Y484632D01*
X1514695Y485152D01*
G03X1514694Y485370I-168J108D01*
G01X1513884Y486606D01*
X1513883Y486608D01*
X1513875Y486620D01*
X1513874Y486622D01*
X1513852Y486655D01*
Y487611D01*
G02X1513858Y487658I204J-2D01*
G01Y487659D01*
G37*
G36*
G01X323839Y492780D02*
G02X323989Y492846I150J-137D01*
G01X326889D01*
G02X326936Y492840I-2J-204D01*
G02X327092Y492642I-48J-198D01*
G01Y491681D01*
X326377Y490590D01*
X326250Y490394D01*
G03X326242Y490189I168J-109D01*
G01X327092Y488888D01*
Y487932D01*
G02X327039Y487794I-203J-1D01*
G02X326889Y487728I-150J137D01*
G01X323989D01*
G02X323942Y487734I2J204D01*
G02X323786Y487932I48J198D01*
G01Y488888D01*
X323812Y488929D01*
X323814Y488932D01*
X323815Y488934D01*
G02X323817Y488937I167J-109D01*
G01X323819Y488940D01*
X324057Y489305D01*
X324079Y489339D01*
X324158Y489461D01*
X324605Y490146D01*
G03X324628Y490239I-177J93D01*
G01Y490341D01*
G03X324595Y490451I-200J0D01*
G01X324500Y490596D01*
X324254Y490972D01*
X323786Y491686D01*
Y492642D01*
G02X323839Y492780I203J1D01*
G37*
G36*
G01X780925D02*
G02X781075Y492846I150J-137D01*
G01X783975D01*
G02X784022Y492840I-2J-204D01*
G02X784178Y492642I-48J-198D01*
G01Y491681D01*
X783463Y490590D01*
X783336Y490394D01*
G03X783328Y490189I168J-109D01*
G01X784178Y488888D01*
Y487932D01*
G02X784125Y487794I-203J-1D01*
G02X783975Y487728I-150J137D01*
G01X781075D01*
G02X781028Y487734I2J204D01*
G02X780872Y487932I48J198D01*
G01Y488888D01*
X780898Y488929D01*
X780900Y488932D01*
X780901Y488934D01*
G02X780903Y488937I167J-109D01*
G01X780905Y488940D01*
X781143Y489305D01*
X781165Y489339D01*
X781244Y489461D01*
X781691Y490146D01*
G03X781714Y490239I-177J93D01*
G01Y490341D01*
G03X781681Y490451I-200J0D01*
G01X781586Y490596D01*
X781340Y490972D01*
X780872Y491686D01*
Y492642D01*
G02X780925Y492780I203J1D01*
G37*
G36*
G01X1695153Y492821D02*
G02X1695249Y492846I98J-178D01*
G01X1698149D01*
G02X1698196Y492840I-2J-204D01*
G01X1698197D01*
G02X1698352Y492642I-49J-198D01*
G01Y491681D01*
X1697698Y490683D01*
X1697637Y490590D01*
X1697510Y490394D01*
G03X1697502Y490189I168J-109D01*
G01X1698352Y488888D01*
Y487932D01*
G02X1698245Y487753I-203J0D01*
G02X1698149Y487728I-98J178D01*
G01X1695249D01*
G02X1695202Y487734I2J204D01*
G01X1695201D01*
G02X1695046Y487932I49J198D01*
G01Y488888D01*
X1695066Y488919D01*
X1695068Y488923D01*
X1695081Y488945D01*
G02X1695098Y488969I171J-103D01*
G01X1695317Y489305D01*
X1695888Y490183D01*
G03Y490401I-168J109D01*
G01X1695810Y490520D01*
X1695616Y490817D01*
X1695046Y491686D01*
Y492642D01*
G02X1695153Y492821I203J0D01*
G37*
G36*
G01X610080Y494724D02*
G02X610284Y494928I204J0D01*
G01X613184D01*
G02X613388Y494724I0J-204D01*
G01Y493763D01*
X613369Y493734D01*
X613362Y493724D01*
X613357Y493716D01*
X613356Y493714D01*
X613278Y493596D01*
X613268Y493581D01*
X612531Y492457D01*
G03X612541Y492265I180J-87D01*
G01X612546Y492257D01*
X612554Y492246D01*
X612603Y492171D01*
X612812Y491851D01*
X613355Y491020D01*
X613356Y491019D01*
X613372Y490995D01*
X613373Y490993D01*
X613388Y490970D01*
Y490014D01*
G02X613184Y489810I-204J0D01*
G01X610284D01*
G02X610080Y490014I0J204D01*
G01Y490970D01*
X610095Y490993D01*
X610096Y490995D01*
X610104Y491007D01*
G02X610106Y491011I180J-88D01*
G01X610548Y491688D01*
X610585Y491745D01*
X610923Y492265D01*
G03X610922Y492483I-168J108D01*
G01X610112Y493719D01*
X610111Y493721D01*
X610103Y493733D01*
X610102Y493735D01*
X610080Y493768D01*
Y494724D01*
G37*
G36*
G01X1067221Y494862D02*
G02X1067371Y494928I150J-137D01*
G01X1070271D01*
G02X1070318Y494922I-2J-204D01*
G02X1070474Y494724I-48J-198D01*
G01Y493763D01*
X1069759Y492672D01*
X1069632Y492476D01*
G03X1069624Y492271I168J-109D01*
G01X1070474Y490970D01*
Y490014D01*
G02X1070421Y489876I-203J-1D01*
G02X1070271Y489810I-150J137D01*
G01X1067371D01*
G02X1067324Y489816I2J204D01*
G02X1067168Y490014I48J198D01*
G01Y490970D01*
X1067194Y491011D01*
X1067196Y491014D01*
X1067197Y491016D01*
G02X1067199Y491019I167J-109D01*
G01X1067201Y491022D01*
X1067439Y491387D01*
X1067461Y491421D01*
X1067540Y491543D01*
X1067987Y492228D01*
G03X1068010Y492321I-177J93D01*
G01Y492423D01*
G03X1067977Y492533I-200J0D01*
G01X1067882Y492678D01*
X1067636Y493054D01*
X1067168Y493768D01*
Y494724D01*
G02X1067221Y494862I203J1D01*
G37*
G36*
G01X313437Y515628D02*
G02X313587Y515694I150J-137D01*
G01X316487D01*
G02X316534Y515688I-2J-204D01*
G02X316690Y515490I-48J-198D01*
G01Y514529D01*
X315975Y513438D01*
X315848Y513242D01*
G03X315840Y513037I168J-109D01*
G01X316690Y511736D01*
Y510780D01*
G02X316637Y510642I-203J-1D01*
G02X316487Y510576I-150J137D01*
G01X313587D01*
G02X313540Y510582I2J204D01*
G02X313384Y510780I48J198D01*
G01Y511736D01*
X313410Y511777D01*
X313412Y511780D01*
X313413Y511782D01*
G02X313415Y511785I167J-109D01*
G01X313417Y511788D01*
X313655Y512153D01*
X313677Y512187D01*
X313756Y512309D01*
X314203Y512994D01*
G03X314226Y513087I-177J93D01*
G01Y513189D01*
G03X314193Y513299I-200J0D01*
G01X314098Y513444D01*
X313852Y513820D01*
X313384Y514534D01*
Y515490D01*
G02X313437Y515628I203J1D01*
G37*
G36*
G01X770523D02*
G02X770673Y515694I150J-137D01*
G01X773573D01*
G02X773620Y515688I-2J-204D01*
G02X773776Y515490I-48J-198D01*
G01Y514529D01*
X773061Y513438D01*
X772934Y513242D01*
G03X772926Y513037I168J-109D01*
G01X773776Y511736D01*
Y510780D01*
G02X773723Y510642I-203J-1D01*
G02X773573Y510576I-150J137D01*
G01X770673D01*
G02X770626Y510582I2J204D01*
G02X770470Y510780I48J198D01*
G01Y511736D01*
X770496Y511777D01*
X770498Y511780D01*
X770499Y511782D01*
G02X770501Y511785I167J-109D01*
G01X770503Y511788D01*
X770741Y512153D01*
X770763Y512187D01*
X770842Y512309D01*
X771289Y512994D01*
G03X771312Y513087I-177J93D01*
G01Y513189D01*
G03X771279Y513299I-200J0D01*
G01X771184Y513444D01*
X770938Y513820D01*
X770470Y514534D01*
Y515490D01*
G02X770523Y515628I203J1D01*
G37*
G36*
G01X1684697D02*
G02X1684847Y515694I150J-137D01*
G01X1687747D01*
G02X1687794Y515688I-2J-204D01*
G02X1687950Y515490I-48J-198D01*
G01Y514529D01*
X1687235Y513438D01*
X1687108Y513242D01*
G03X1687100Y513037I168J-109D01*
G01X1687950Y511736D01*
Y510780D01*
G02X1687897Y510642I-203J-1D01*
G02X1687747Y510576I-150J137D01*
G01X1684847D01*
G02X1684800Y510582I2J204D01*
G02X1684644Y510780I48J198D01*
G01Y511736D01*
X1684670Y511777D01*
X1684672Y511780D01*
X1684673Y511782D01*
G02X1684675Y511785I167J-109D01*
G01X1684677Y511788D01*
X1684915Y512153D01*
X1684937Y512187D01*
X1685016Y512309D01*
X1685463Y512994D01*
G03X1685486Y513087I-177J93D01*
G01Y513189D01*
G03X1685453Y513299I-200J0D01*
G01X1685358Y513444D01*
X1685112Y513820D01*
X1684644Y514534D01*
Y515490D01*
G02X1684697Y515628I203J1D01*
G37*
G36*
G01X1056819Y517710D02*
G02X1056969Y517776I150J-137D01*
G01X1059869D01*
G02X1059916Y517770I-2J-204D01*
G02X1060072Y517572I-48J-198D01*
G01Y516611D01*
X1059357Y515520D01*
X1059230Y515324D01*
G03X1059222Y515119I168J-109D01*
G01X1060072Y513818D01*
Y512862D01*
G02X1060019Y512724I-203J-1D01*
G02X1059869Y512658I-150J137D01*
G01X1056969D01*
G02X1056922Y512664I2J204D01*
G02X1056766Y512862I48J198D01*
G01Y513818D01*
X1056792Y513859D01*
X1056794Y513862D01*
X1056795Y513864D01*
G02X1056797Y513867I167J-109D01*
G01X1056799Y513870D01*
X1057037Y514235D01*
X1057059Y514269D01*
X1057138Y514391D01*
X1057585Y515076D01*
G03X1057608Y515169I-177J93D01*
G01Y515271D01*
G03X1057575Y515381I-200J0D01*
G01X1057480Y515526D01*
X1057234Y515902D01*
X1056766Y516616D01*
Y517572D01*
G02X1056819Y517710I203J1D01*
G37*
G36*
G01X323786Y522603D02*
G02X323989Y522806I203J0D01*
G01X326889D01*
G02X327092Y522603I0J-203D01*
G01Y521642D01*
X326438Y520644D01*
X326377Y520551D01*
X326250Y520355D01*
G03X326242Y520150I168J-109D01*
G01X327092Y518849D01*
Y517893D01*
G02X326889Y517690I-203J0D01*
G01X323989D01*
G02X323786Y517893I0J203D01*
G01Y518849D01*
X323806Y518880D01*
X323808Y518884D01*
X323821Y518906D01*
G02X323838Y518930I170J-103D01*
G01X324057Y519266D01*
X324628Y520144D01*
G03Y520362I-168J109D01*
G01X324550Y520481D01*
X324356Y520778D01*
X323786Y521647D01*
Y522603D01*
G37*
G36*
G01X780872D02*
G02X781075Y522806I203J0D01*
G01X783975D01*
G02X784178Y522603I0J-203D01*
G01Y521642D01*
X783463Y520551D01*
X783336Y520355D01*
G03X783328Y520150I168J-109D01*
G01X784178Y518849D01*
Y517893D01*
G02X783975Y517690I-203J0D01*
G01X781075D01*
G02X780872Y517893I0J203D01*
G01Y518849D01*
X780898Y518890D01*
X780900Y518893D01*
X780901Y518895D01*
G02X780903Y518898I167J-109D01*
G01X780905Y518901D01*
X781143Y519266D01*
X781165Y519300D01*
X781244Y519422D01*
X781691Y520107D01*
G03X781714Y520200I-177J93D01*
G01Y520302D01*
G03X781681Y520412I-200J0D01*
G01X781586Y520557D01*
X781340Y520933D01*
X780872Y521647D01*
Y522603D01*
G37*
G36*
G01X1695046D02*
G02X1695249Y522806I203J0D01*
G01X1698149D01*
G02X1698352Y522603I0J-203D01*
G01Y521642D01*
X1697637Y520551D01*
X1697510Y520355D01*
G03X1697502Y520150I168J-109D01*
G01X1698352Y518849D01*
Y517893D01*
G02X1698149Y517690I-203J0D01*
G01X1695249D01*
G02X1695046Y517893I0J203D01*
G01Y518849D01*
X1695072Y518890D01*
X1695074Y518893D01*
X1695075Y518895D01*
G02X1695077Y518898I167J-109D01*
G01X1695079Y518901D01*
X1695317Y519266D01*
X1695339Y519300D01*
X1695418Y519422D01*
X1695865Y520107D01*
G03X1695888Y520200I-177J93D01*
G01Y520302D01*
G03X1695855Y520412I-200J0D01*
G01X1695760Y520557D01*
X1695514Y520933D01*
X1695046Y521647D01*
Y522603D01*
G37*
G36*
G01X1067275Y524863D02*
G02X1067371Y524888I98J-178D01*
G01X1070271D01*
G02X1070318Y524882I-2J-204D01*
G01X1070319D01*
G02X1070474Y524684I-49J-198D01*
G01Y523723D01*
X1069820Y522725D01*
X1069759Y522632D01*
X1069632Y522436D01*
G03X1069624Y522231I168J-109D01*
G01X1070474Y520930D01*
Y519974D01*
G02X1070367Y519795I-203J0D01*
G02X1070271Y519770I-98J178D01*
G01X1067371D01*
G02X1067324Y519776I2J204D01*
G01X1067323D01*
G02X1067168Y519974I49J198D01*
G01Y520930D01*
X1067188Y520961D01*
X1067190Y520965D01*
X1067203Y520987D01*
G02X1067220Y521011I171J-103D01*
G01X1067439Y521347D01*
X1068010Y522225D01*
G03Y522443I-168J109D01*
G01X1067932Y522562D01*
X1067738Y522859D01*
X1067168Y523728D01*
Y524684D01*
G02X1067275Y524863I203J0D01*
G37*
G36*
G01X313437Y529802D02*
G02X313587Y529868I150J-137D01*
G01X316487D01*
G02X316534Y529862I-2J-204D01*
G02X316690Y529664I-48J-198D01*
G01Y528703D01*
X315975Y527612D01*
X315848Y527416D01*
G03X315840Y527211I168J-109D01*
G01X316690Y525910D01*
Y524954D01*
G02X316637Y524816I-203J-1D01*
G02X316487Y524750I-150J137D01*
G01X313587D01*
G02X313540Y524756I2J204D01*
G02X313384Y524954I48J198D01*
G01Y525910D01*
X313410Y525951D01*
X313412Y525954D01*
X313413Y525956D01*
G02X313415Y525959I167J-109D01*
G01X313417Y525962D01*
X313655Y526327D01*
X313677Y526361D01*
X313756Y526483D01*
X314203Y527168D01*
G03X314226Y527261I-177J93D01*
G01Y527363D01*
G03X314193Y527473I-200J0D01*
G01X314098Y527618D01*
X313852Y527994D01*
X313384Y528708D01*
Y529664D01*
G02X313437Y529802I203J1D01*
G37*
G36*
G01X770523D02*
G02X770673Y529868I150J-137D01*
G01X773573D01*
G02X773620Y529862I-2J-204D01*
G02X773776Y529664I-48J-198D01*
G01Y528703D01*
X773061Y527612D01*
X772934Y527416D01*
G03X772926Y527211I168J-109D01*
G01X773776Y525910D01*
Y524954D01*
G02X773723Y524816I-203J-1D01*
G02X773573Y524750I-150J137D01*
G01X770673D01*
G02X770626Y524756I2J204D01*
G02X770470Y524954I48J198D01*
G01Y525910D01*
X770496Y525951D01*
X770498Y525954D01*
X770499Y525956D01*
G02X770501Y525959I167J-109D01*
G01X770503Y525962D01*
X770741Y526327D01*
X770763Y526361D01*
X770842Y526483D01*
X771289Y527168D01*
G03X771312Y527261I-177J93D01*
G01Y527363D01*
G03X771279Y527473I-200J0D01*
G01X771184Y527618D01*
X770938Y527994D01*
X770470Y528708D01*
Y529664D01*
G02X770523Y529802I203J1D01*
G37*
G36*
G01X1684697D02*
G02X1684847Y529868I150J-137D01*
G01X1687747D01*
G02X1687794Y529862I-2J-204D01*
G02X1687950Y529664I-48J-198D01*
G01Y528703D01*
X1687235Y527612D01*
X1687108Y527416D01*
G03X1687100Y527211I168J-109D01*
G01X1687950Y525910D01*
Y524954D01*
G02X1687897Y524816I-203J-1D01*
G02X1687747Y524750I-150J137D01*
G01X1684847D01*
G02X1684800Y524756I2J204D01*
G02X1684644Y524954I48J198D01*
G01Y525910D01*
X1684670Y525951D01*
X1684672Y525954D01*
X1684673Y525956D01*
G02X1684675Y525959I167J-109D01*
G01X1684677Y525962D01*
X1684915Y526327D01*
X1684937Y526361D01*
X1685016Y526483D01*
X1685463Y527168D01*
G03X1685486Y527261I-177J93D01*
G01Y527363D01*
G03X1685453Y527473I-200J0D01*
G01X1685358Y527618D01*
X1685112Y527994D01*
X1684644Y528708D01*
Y529664D01*
G02X1684697Y529802I203J1D01*
G37*
G36*
G01X1056766Y531745D02*
G02X1056969Y531948I203J0D01*
G01X1059869D01*
G02X1060072Y531745I0J-203D01*
G01Y530784D01*
X1059357Y529693D01*
X1059230Y529497D01*
G03X1059222Y529292I168J-109D01*
G01X1060072Y527991D01*
Y527035D01*
G02X1059869Y526832I-203J0D01*
G01X1056969D01*
G02X1056766Y527035I0J203D01*
G01Y527991D01*
X1056792Y528032D01*
X1056794Y528035D01*
X1056795Y528037D01*
G02X1056797Y528040I167J-109D01*
G01X1056799Y528043D01*
X1057037Y528408D01*
X1057059Y528442D01*
X1057138Y528564D01*
X1057585Y529249D01*
G03X1057608Y529342I-177J93D01*
G01Y529444D01*
G03X1057575Y529554I-200J0D01*
G01X1057480Y529699D01*
X1057234Y530075D01*
X1056766Y530789D01*
Y531745D01*
G37*
G36*
G01X323893Y536955D02*
G02X323989Y536980I98J-178D01*
G01X326889D01*
G02X326936Y536974I-2J-204D01*
G01X326937D01*
G02X327092Y536776I-49J-198D01*
G01Y535815D01*
X326438Y534817D01*
X326377Y534724D01*
X326250Y534528D01*
G03X326242Y534323I168J-109D01*
G01X327092Y533022D01*
Y532066D01*
G02X326985Y531887I-203J0D01*
G02X326889Y531862I-98J178D01*
G01X323989D01*
G02X323942Y531868I2J204D01*
G01X323941D01*
G02X323786Y532066I49J198D01*
G01Y533022D01*
X323806Y533053D01*
X323808Y533057D01*
X323821Y533079D01*
G02X323838Y533103I171J-103D01*
G01X324057Y533439D01*
X324628Y534317D01*
G03Y534535I-168J109D01*
G01X324550Y534654D01*
X324356Y534951D01*
X323786Y535820D01*
Y536776D01*
G02X323893Y536955I203J0D01*
G37*
G36*
G01X780979D02*
G02X781075Y536980I98J-178D01*
G01X783975D01*
G02X784022Y536974I-2J-204D01*
G01X784023D01*
G02X784178Y536776I-49J-198D01*
G01Y535815D01*
X783524Y534817D01*
X783463Y534724D01*
X783336Y534528D01*
G03X783328Y534323I168J-109D01*
G01X784178Y533022D01*
Y532066D01*
G02X784071Y531887I-203J0D01*
G02X783975Y531862I-98J178D01*
G01X781075D01*
G02X781028Y531868I2J204D01*
G01X781027D01*
G02X780872Y532066I49J198D01*
G01Y533022D01*
X780892Y533053D01*
X780894Y533057D01*
X780907Y533079D01*
G02X780924Y533103I171J-103D01*
G01X781143Y533439D01*
X781714Y534317D01*
G03Y534535I-168J109D01*
G01X781636Y534654D01*
X781442Y534951D01*
X780872Y535820D01*
Y536776D01*
G02X780979Y536955I203J0D01*
G37*
G36*
G01X1237958Y536776D02*
G02X1238162Y536980I204J0D01*
G01X1241062D01*
G02X1241266Y536776I0J-204D01*
G01Y535815D01*
X1241247Y535786D01*
X1241240Y535776D01*
X1241235Y535768D01*
X1241234Y535766D01*
X1241156Y535648D01*
X1241146Y535633D01*
X1240409Y534509D01*
G03X1240419Y534317I180J-87D01*
G01X1240424Y534309D01*
X1240432Y534298D01*
X1240481Y534223D01*
X1240690Y533903D01*
X1241233Y533072D01*
X1241234Y533071D01*
X1241250Y533047D01*
X1241251Y533045D01*
X1241266Y533022D01*
Y532066D01*
G02X1241062Y531862I-204J0D01*
G01X1238162D01*
G02X1237958Y532066I0J204D01*
G01Y533022D01*
X1237973Y533045D01*
X1237974Y533047D01*
X1237982Y533059D01*
G02X1237984Y533063I180J-88D01*
G01X1238426Y533740D01*
X1238463Y533797D01*
X1238801Y534317D01*
G03X1238800Y534535I-168J108D01*
G01X1237990Y535771D01*
X1237989Y535773D01*
X1237981Y535785D01*
X1237980Y535787D01*
X1237958Y535820D01*
Y536776D01*
G37*
G36*
G01X1695099Y536914D02*
G02X1695249Y536980I150J-137D01*
G01X1698149D01*
G02X1698196Y536974I-2J-204D01*
G02X1698352Y536776I-48J-198D01*
G01Y535815D01*
X1697637Y534724D01*
X1697510Y534528D01*
G03X1697502Y534323I168J-109D01*
G01X1698352Y533022D01*
Y532066D01*
G02X1698299Y531928I-203J-1D01*
G02X1698149Y531862I-150J137D01*
G01X1695249D01*
G02X1695202Y531868I2J204D01*
G02X1695046Y532066I48J198D01*
G01Y533022D01*
X1695072Y533063D01*
X1695074Y533066D01*
X1695075Y533068D01*
G02X1695077Y533071I167J-109D01*
G01X1695079Y533074D01*
X1695317Y533439D01*
X1695339Y533473D01*
X1695418Y533595D01*
X1695865Y534280D01*
G03X1695888Y534373I-177J93D01*
G01Y534475D01*
G03X1695855Y534585I-200J0D01*
G01X1695760Y534730D01*
X1695514Y535106D01*
X1695046Y535820D01*
Y536776D01*
G02X1695099Y536914I203J1D01*
G37*
G36*
G01X1067168Y538857D02*
G02X1067371Y539060I203J0D01*
G01X1070271D01*
G02X1070474Y538857I0J-203D01*
G01Y537896D01*
X1069759Y536805D01*
X1069632Y536609D01*
G03X1069624Y536404I168J-109D01*
G01X1070474Y535103D01*
Y534147D01*
G02X1070271Y533944I-203J0D01*
G01X1067371D01*
G02X1067168Y534147I0J203D01*
G01Y535103D01*
X1067194Y535144D01*
X1067196Y535147D01*
X1067197Y535149D01*
G02X1067199Y535152I167J-109D01*
G01X1067201Y535155D01*
X1067439Y535520D01*
X1067461Y535554D01*
X1067540Y535676D01*
X1067987Y536361D01*
G03X1068010Y536454I-177J93D01*
G01Y536556D01*
G03X1067977Y536666I-200J0D01*
G01X1067882Y536811D01*
X1067636Y537187D01*
X1067168Y537901D01*
Y538857D01*
G37*
G36*
G01X313491Y565709D02*
G02X313587Y565734I98J-178D01*
G01X316487D01*
G02X316534Y565728I-2J-204D01*
G01X316535D01*
G02X316690Y565530I-49J-198D01*
G01Y564569D01*
X316036Y563571D01*
X315975Y563478D01*
X315848Y563282D01*
G03X315840Y563077I168J-109D01*
G01X316690Y561776D01*
Y560820D01*
G02X316583Y560641I-203J0D01*
G02X316487Y560616I-98J178D01*
G01X313587D01*
G02X313540Y560622I2J204D01*
G01X313539D01*
G02X313384Y560820I49J198D01*
G01Y561776D01*
X313404Y561807D01*
X313406Y561811D01*
X313419Y561833D01*
G02X313436Y561857I171J-103D01*
G01X313655Y562193D01*
X314226Y563071D01*
G03Y563289I-168J109D01*
G01X314148Y563408D01*
X313954Y563705D01*
X313384Y564574D01*
Y565530D01*
G02X313491Y565709I203J0D01*
G37*
G36*
G01X770577D02*
G02X770673Y565734I98J-178D01*
G01X773573D01*
G02X773620Y565728I-2J-204D01*
G01X773621D01*
G02X773776Y565530I-49J-198D01*
G01Y564569D01*
X773122Y563571D01*
X773061Y563478D01*
X772934Y563282D01*
G03X772926Y563077I168J-109D01*
G01X773776Y561776D01*
Y560820D01*
G02X773669Y560641I-203J0D01*
G02X773573Y560616I-98J178D01*
G01X770673D01*
G02X770626Y560622I2J204D01*
G01X770625D01*
G02X770470Y560820I49J198D01*
G01Y561776D01*
X770490Y561807D01*
X770492Y561811D01*
X770505Y561833D01*
G02X770522Y561857I171J-103D01*
G01X770741Y562193D01*
X771312Y563071D01*
G03Y563289I-168J109D01*
G01X771234Y563408D01*
X771040Y563705D01*
X770470Y564574D01*
Y565530D01*
G02X770577Y565709I203J0D01*
G37*
G36*
G01X1684751D02*
G02X1684847Y565734I98J-178D01*
G01X1687747D01*
G02X1687794Y565728I-2J-204D01*
G01X1687795D01*
G02X1687950Y565530I-49J-198D01*
G01Y564569D01*
X1687296Y563571D01*
X1687235Y563478D01*
X1687108Y563282D01*
G03X1687100Y563077I168J-109D01*
G01X1687950Y561776D01*
Y560820D01*
G02X1687843Y560641I-203J0D01*
G02X1687747Y560616I-98J178D01*
G01X1684847D01*
G02X1684800Y560622I2J204D01*
G01X1684799D01*
G02X1684644Y560820I49J198D01*
G01Y561776D01*
X1684664Y561807D01*
X1684666Y561811D01*
X1684679Y561833D01*
G02X1684696Y561857I171J-103D01*
G01X1684915Y562193D01*
X1685486Y563071D01*
G03Y563289I-168J109D01*
G01X1685408Y563408D01*
X1685214Y563705D01*
X1684644Y564574D01*
Y565530D01*
G02X1684751Y565709I203J0D01*
G37*
G36*
G01X323839Y572780D02*
G02X323989Y572846I150J-137D01*
G01X326889D01*
G02X326936Y572840I-2J-204D01*
G02X327092Y572642I-48J-198D01*
G01Y571681D01*
X326377Y570590D01*
X326250Y570394D01*
G03X326242Y570189I168J-109D01*
G01X327092Y568888D01*
Y567932D01*
G02X327039Y567794I-203J-1D01*
G02X326889Y567728I-150J137D01*
G01X323989D01*
G02X323942Y567734I2J204D01*
G02X323786Y567932I48J198D01*
G01Y568888D01*
X323812Y568929D01*
X323814Y568932D01*
X323815Y568934D01*
G02X323817Y568937I167J-109D01*
G01X323819Y568940D01*
X324057Y569305D01*
X324079Y569339D01*
X324158Y569461D01*
X324605Y570146D01*
G03X324628Y570239I-177J93D01*
G01Y570341D01*
G03X324595Y570451I-200J0D01*
G01X324500Y570596D01*
X324254Y570972D01*
X323786Y571686D01*
Y572642D01*
G02X323839Y572780I203J1D01*
G37*
G36*
G01X780979Y572821D02*
G02X781075Y572846I98J-178D01*
G01X783975D01*
G02X784022Y572840I-2J-204D01*
G01X784023D01*
G02X784178Y572642I-49J-198D01*
G01Y571681D01*
X783524Y570683D01*
X783463Y570590D01*
X783336Y570394D01*
G03X783328Y570189I168J-109D01*
G01X784178Y568888D01*
Y567932D01*
G02X784071Y567753I-203J0D01*
G02X783975Y567728I-98J178D01*
G01X781075D01*
G02X781028Y567734I2J204D01*
G01X781027D01*
G02X780872Y567932I49J198D01*
G01Y568888D01*
X780892Y568919D01*
X780894Y568923D01*
X780907Y568945D01*
G02X780924Y568969I171J-103D01*
G01X781143Y569305D01*
X781714Y570183D01*
G03Y570401I-168J109D01*
G01X781636Y570520D01*
X781442Y570817D01*
X780872Y571686D01*
Y572642D01*
G02X780979Y572821I203J0D01*
G37*
G36*
G01X1237958Y572642D02*
G02X1238162Y572846I204J0D01*
G01X1241062D01*
G02X1241266Y572642I0J-204D01*
G01Y571681D01*
X1241247Y571652D01*
X1241240Y571642D01*
X1241235Y571634D01*
X1241234Y571632D01*
X1241156Y571514D01*
X1241146Y571499D01*
X1240409Y570375D01*
G03X1240419Y570183I180J-87D01*
G01X1240424Y570175D01*
X1240432Y570164D01*
X1240481Y570089D01*
X1240690Y569769D01*
X1241233Y568938D01*
X1241234Y568937D01*
X1241250Y568913D01*
X1241251Y568911D01*
X1241266Y568888D01*
Y567932D01*
G02X1241062Y567728I-204J0D01*
G01X1238162D01*
G02X1237958Y567932I0J204D01*
G01Y568888D01*
X1237973Y568911D01*
X1237974Y568913D01*
X1237982Y568925D01*
G02X1237984Y568929I180J-88D01*
G01X1238426Y569606D01*
X1238463Y569663D01*
X1238801Y570183D01*
G03X1238800Y570401I-168J108D01*
G01X1237990Y571637D01*
X1237989Y571639D01*
X1237981Y571651D01*
X1237980Y571653D01*
X1237958Y571686D01*
Y572642D01*
G37*
G36*
G01X1695153Y572821D02*
G02X1695249Y572846I98J-178D01*
G01X1698149D01*
G02X1698196Y572840I-2J-204D01*
G01X1698197D01*
G02X1698352Y572642I-49J-198D01*
G01Y571681D01*
X1697698Y570683D01*
X1697637Y570590D01*
X1697510Y570394D01*
G03X1697502Y570189I168J-109D01*
G01X1698352Y568888D01*
Y567932D01*
G02X1698245Y567753I-203J0D01*
G02X1698149Y567728I-98J178D01*
G01X1695249D01*
G02X1695202Y567734I2J204D01*
G01X1695201D01*
G02X1695046Y567932I49J198D01*
G01Y568888D01*
X1695066Y568919D01*
X1695068Y568923D01*
X1695081Y568945D01*
G02X1695098Y568969I171J-103D01*
G01X1695317Y569305D01*
X1695888Y570183D01*
G03Y570401I-168J109D01*
G01X1695810Y570520D01*
X1695616Y570817D01*
X1695046Y571686D01*
Y572642D01*
G02X1695153Y572821I203J0D01*
G37*
G36*
G01X313384Y579703D02*
G02X313587Y579906I203J0D01*
G01X316487D01*
G02X316690Y579703I0J-203D01*
G01Y578742D01*
X316036Y577744D01*
X315975Y577651D01*
X315848Y577455D01*
G03X315840Y577250I168J-109D01*
G01X316690Y575949D01*
Y574993D01*
G02X316487Y574790I-203J0D01*
G01X313587D01*
G02X313384Y574993I0J203D01*
G01Y575949D01*
X313404Y575980D01*
X313406Y575984D01*
X313419Y576006D01*
G02X313436Y576030I171J-103D01*
G01X313655Y576366D01*
X314226Y577244D01*
G03Y577462I-168J109D01*
G01X314148Y577581D01*
X313954Y577878D01*
X313384Y578747D01*
Y579703D01*
G37*
G36*
G01X770470D02*
G02X770673Y579906I203J0D01*
G01X773573D01*
G02X773776Y579703I0J-203D01*
G01Y578742D01*
X773061Y577651D01*
X772934Y577455D01*
G03X772926Y577250I168J-109D01*
G01X773776Y575949D01*
Y574993D01*
G02X773573Y574790I-203J0D01*
G01X770673D01*
G02X770470Y574993I0J203D01*
G01Y575949D01*
X770496Y575990D01*
X770498Y575993D01*
X770499Y575995D01*
G02X770501Y575998I167J-109D01*
G01X770503Y576001D01*
X770741Y576366D01*
X770763Y576400D01*
X770842Y576522D01*
X771289Y577207D01*
G03X771312Y577300I-177J93D01*
G01Y577402D01*
G03X771279Y577512I-200J0D01*
G01X771184Y577657D01*
X770938Y578033D01*
X770470Y578747D01*
Y579703D01*
G37*
G36*
G01X1684644D02*
G02X1684847Y579906I203J0D01*
G01X1687747D01*
G02X1687950Y579703I0J-203D01*
G01Y578742D01*
X1687296Y577744D01*
X1687235Y577651D01*
X1687108Y577455D01*
G03X1687100Y577250I168J-109D01*
G01X1687950Y575949D01*
Y574993D01*
G02X1687747Y574790I-203J0D01*
G01X1684847D01*
G02X1684644Y574993I0J203D01*
G01Y575949D01*
X1684664Y575980D01*
X1684666Y575984D01*
X1684679Y576006D01*
G02X1684696Y576030I171J-103D01*
G01X1684915Y576366D01*
X1685486Y577244D01*
G03Y577462I-168J109D01*
G01X1685408Y577581D01*
X1685214Y577878D01*
X1684644Y578747D01*
Y579703D01*
G37*
G36*
G01X323839Y586954D02*
G02X323989Y587020I150J-137D01*
G01X326889D01*
G02X326936Y587014I-2J-204D01*
G02X327092Y586816I-48J-198D01*
G01Y585855D01*
X326377Y584764D01*
X326250Y584568D01*
G03X326242Y584363I168J-109D01*
G01X327092Y583062D01*
Y582106D01*
G02X327039Y581968I-203J-1D01*
G02X326889Y581902I-150J137D01*
G01X323989D01*
G02X323942Y581908I2J204D01*
G02X323786Y582106I48J198D01*
G01Y583062D01*
X323812Y583103D01*
X323814Y583106D01*
X323815Y583108D01*
G02X323817Y583111I167J-109D01*
G01X323819Y583114D01*
X324057Y583479D01*
X324079Y583513D01*
X324158Y583635D01*
X324605Y584320D01*
G03X324628Y584413I-177J93D01*
G01Y584515D01*
G03X324595Y584625I-200J0D01*
G01X324500Y584770D01*
X324254Y585146D01*
X323786Y585860D01*
Y586816D01*
G02X323839Y586954I203J1D01*
G37*
G36*
G01X780925D02*
G02X781075Y587020I150J-137D01*
G01X783975D01*
G02X784022Y587014I-2J-204D01*
G02X784178Y586816I-48J-198D01*
G01Y585855D01*
X783463Y584764D01*
X783336Y584568D01*
G03X783328Y584363I168J-109D01*
G01X784178Y583062D01*
Y582106D01*
G02X784125Y581968I-203J-1D01*
G02X783975Y581902I-150J137D01*
G01X781075D01*
G02X781028Y581908I2J204D01*
G02X780872Y582106I48J198D01*
G01Y583062D01*
X780898Y583103D01*
X780900Y583106D01*
X780901Y583108D01*
G02X780903Y583111I167J-109D01*
G01X780905Y583114D01*
X781143Y583479D01*
X781165Y583513D01*
X781244Y583635D01*
X781691Y584320D01*
G03X781714Y584413I-177J93D01*
G01Y584515D01*
G03X781681Y584625I-200J0D01*
G01X781586Y584770D01*
X781340Y585146D01*
X780872Y585860D01*
Y586816D01*
G02X780925Y586954I203J1D01*
G37*
G36*
G01X1695099D02*
G02X1695249Y587020I150J-137D01*
G01X1698149D01*
G02X1698196Y587014I-2J-204D01*
G02X1698352Y586816I-48J-198D01*
G01Y585855D01*
X1697637Y584764D01*
X1697510Y584568D01*
G03X1697502Y584363I168J-109D01*
G01X1698352Y583062D01*
Y582106D01*
G02X1698299Y581968I-203J-1D01*
G02X1698149Y581902I-150J137D01*
G01X1695249D01*
G02X1695202Y581908I2J204D01*
G02X1695046Y582106I48J198D01*
G01Y583062D01*
X1695072Y583103D01*
X1695074Y583106D01*
X1695075Y583108D01*
G02X1695077Y583111I167J-109D01*
G01X1695079Y583114D01*
X1695317Y583479D01*
X1695339Y583513D01*
X1695418Y583635D01*
X1695865Y584320D01*
G03X1695888Y584413I-177J93D01*
G01Y584515D01*
G03X1695855Y584625I-200J0D01*
G01X1695760Y584770D01*
X1695514Y585146D01*
X1695046Y585860D01*
Y586816D01*
G02X1695099Y586954I203J1D01*
G37*
G36*
G01X313437Y594014D02*
G02X313587Y594080I150J-137D01*
G01X316487D01*
G02X316534Y594074I-2J-204D01*
G02X316690Y593876I-48J-198D01*
G01Y592915D01*
X315975Y591824D01*
X315848Y591628D01*
G03X315840Y591423I168J-109D01*
G01X316690Y590122D01*
Y589166D01*
G02X316637Y589028I-203J-1D01*
G02X316487Y588962I-150J137D01*
G01X313587D01*
G02X313540Y588968I2J204D01*
G02X313384Y589166I48J198D01*
G01Y590122D01*
X313410Y590163D01*
X313412Y590166D01*
X313413Y590168D01*
G02X313415Y590171I167J-109D01*
G01X313417Y590174D01*
X313655Y590539D01*
X313677Y590573D01*
X313756Y590695D01*
X314203Y591380D01*
G03X314226Y591473I-177J93D01*
G01Y591575D01*
G03X314193Y591685I-200J0D01*
G01X314098Y591830D01*
X313852Y592206D01*
X313384Y592920D01*
Y593876D01*
G02X313437Y594014I203J1D01*
G37*
G36*
G01X770523D02*
G02X770673Y594080I150J-137D01*
G01X773573D01*
G02X773620Y594074I-2J-204D01*
G02X773776Y593876I-48J-198D01*
G01Y592915D01*
X773061Y591824D01*
X772934Y591628D01*
G03X772926Y591423I168J-109D01*
G01X773776Y590122D01*
Y589166D01*
G02X773723Y589028I-203J-1D01*
G02X773573Y588962I-150J137D01*
G01X770673D01*
G02X770626Y588968I2J204D01*
G02X770470Y589166I48J198D01*
G01Y590122D01*
X770496Y590163D01*
X770498Y590166D01*
X770499Y590168D01*
G02X770501Y590171I167J-109D01*
G01X770503Y590174D01*
X770741Y590539D01*
X770763Y590573D01*
X770842Y590695D01*
X771289Y591380D01*
G03X771312Y591473I-177J93D01*
G01Y591575D01*
G03X771279Y591685I-200J0D01*
G01X771184Y591830D01*
X770938Y592206D01*
X770470Y592920D01*
Y593876D01*
G02X770523Y594014I203J1D01*
G37*
G36*
G01X1684697D02*
G02X1684847Y594080I150J-137D01*
G01X1687747D01*
G02X1687794Y594074I-2J-204D01*
G02X1687950Y593876I-48J-198D01*
G01Y592915D01*
X1687235Y591824D01*
X1687108Y591628D01*
G03X1687100Y591423I168J-109D01*
G01X1687950Y590122D01*
Y589166D01*
G02X1687897Y589028I-203J-1D01*
G02X1687747Y588962I-150J137D01*
G01X1684847D01*
G02X1684800Y588968I2J204D01*
G02X1684644Y589166I48J198D01*
G01Y590122D01*
X1684670Y590163D01*
X1684672Y590166D01*
X1684673Y590168D01*
G02X1684675Y590171I167J-109D01*
G01X1684677Y590174D01*
X1684915Y590539D01*
X1684937Y590573D01*
X1685016Y590695D01*
X1685463Y591380D01*
G03X1685486Y591473I-177J93D01*
G01Y591575D01*
G03X1685453Y591685I-200J0D01*
G01X1685358Y591830D01*
X1685112Y592206D01*
X1684644Y592920D01*
Y593876D01*
G02X1684697Y594014I203J1D01*
G37*
G36*
G01X323786Y600989D02*
G02X323989Y601192I203J0D01*
G01X326889D01*
G02X327092Y600989I0J-203D01*
G01Y600028D01*
X326377Y598937D01*
X326250Y598741D01*
G03X326242Y598536I168J-109D01*
G01X327092Y597235D01*
Y596279D01*
G02X326889Y596076I-203J0D01*
G01X323989D01*
G02X323786Y596279I0J203D01*
G01Y597235D01*
X323812Y597276D01*
X323814Y597279D01*
X323815Y597281D01*
G02X323817Y597284I167J-109D01*
G01X323819Y597287D01*
X324057Y597652D01*
X324079Y597686D01*
X324158Y597808D01*
X324605Y598493D01*
G03X324628Y598586I-177J93D01*
G01Y598688D01*
G03X324595Y598798I-200J0D01*
G01X324500Y598943D01*
X324254Y599319D01*
X323786Y600033D01*
Y600989D01*
G37*
G36*
G01X780872D02*
G02X781075Y601192I203J0D01*
G01X783975D01*
G02X784178Y600989I0J-203D01*
G01Y600028D01*
X783463Y598937D01*
X783336Y598741D01*
G03X783328Y598536I168J-109D01*
G01X784178Y597235D01*
Y596279D01*
G02X783975Y596076I-203J0D01*
G01X781075D01*
G02X780872Y596279I0J203D01*
G01Y597235D01*
X780898Y597276D01*
X780900Y597279D01*
X780901Y597281D01*
G02X780903Y597284I167J-109D01*
G01X780905Y597287D01*
X781143Y597652D01*
X781165Y597686D01*
X781244Y597808D01*
X781691Y598493D01*
G03X781714Y598586I-177J93D01*
G01Y598688D01*
G03X781681Y598798I-200J0D01*
G01X781586Y598943D01*
X781340Y599319D01*
X780872Y600033D01*
Y600989D01*
G37*
G36*
G01X1695046D02*
G02X1695249Y601192I203J0D01*
G01X1698149D01*
G02X1698352Y600989I0J-203D01*
G01Y600028D01*
X1697637Y598937D01*
X1697510Y598741D01*
G03X1697502Y598536I168J-109D01*
G01X1698352Y597235D01*
Y596279D01*
G02X1698149Y596076I-203J0D01*
G01X1695249D01*
G02X1695046Y596279I0J203D01*
G01Y597235D01*
X1695072Y597276D01*
X1695074Y597279D01*
X1695075Y597281D01*
G02X1695077Y597284I167J-109D01*
G01X1695079Y597287D01*
X1695317Y597652D01*
X1695339Y597686D01*
X1695418Y597808D01*
X1695865Y598493D01*
G03X1695888Y598586I-177J93D01*
G01Y598688D01*
G03X1695855Y598798I-200J0D01*
G01X1695760Y598943D01*
X1695514Y599319D01*
X1695046Y600033D01*
Y600989D01*
G37*
G36*
G01X313437Y608188D02*
G02X313587Y608254I150J-137D01*
G01X316487D01*
G02X316534Y608248I-2J-204D01*
G02X316690Y608050I-48J-198D01*
G01Y607089D01*
X315975Y605998D01*
X315848Y605802D01*
G03X315840Y605597I168J-109D01*
G01X316690Y604296D01*
Y603340D01*
G02X316637Y603202I-203J-1D01*
G02X316487Y603136I-150J137D01*
G01X313587D01*
G02X313540Y603142I2J204D01*
G02X313384Y603340I48J198D01*
G01Y604296D01*
X313410Y604337D01*
X313412Y604340D01*
X313413Y604342D01*
G02X313415Y604345I167J-109D01*
G01X313417Y604348D01*
X313655Y604713D01*
X313677Y604747D01*
X313756Y604869D01*
X314203Y605554D01*
G03X314226Y605647I-177J93D01*
G01Y605749D01*
G03X314193Y605859I-200J0D01*
G01X314098Y606004D01*
X313852Y606380D01*
X313384Y607094D01*
Y608050D01*
G02X313437Y608188I203J1D01*
G37*
G36*
G01X770523D02*
G02X770673Y608254I150J-137D01*
G01X773573D01*
G02X773620Y608248I-2J-204D01*
G02X773776Y608050I-48J-198D01*
G01Y607089D01*
X773061Y605998D01*
X772934Y605802D01*
G03X772926Y605597I168J-109D01*
G01X773776Y604296D01*
Y603340D01*
G02X773723Y603202I-203J-1D01*
G02X773573Y603136I-150J137D01*
G01X770673D01*
G02X770626Y603142I2J204D01*
G02X770470Y603340I48J198D01*
G01Y604296D01*
X770496Y604337D01*
X770498Y604340D01*
X770499Y604342D01*
G02X770501Y604345I167J-109D01*
G01X770503Y604348D01*
X770741Y604713D01*
X770763Y604747D01*
X770842Y604869D01*
X771289Y605554D01*
G03X771312Y605647I-177J93D01*
G01Y605749D01*
G03X771279Y605859I-200J0D01*
G01X771184Y606004D01*
X770938Y606380D01*
X770470Y607094D01*
Y608050D01*
G02X770523Y608188I203J1D01*
G37*
G36*
G01X1684697D02*
G02X1684847Y608254I150J-137D01*
G01X1687747D01*
G02X1687794Y608248I-2J-204D01*
G02X1687950Y608050I-48J-198D01*
G01Y607089D01*
X1687235Y605998D01*
X1687108Y605802D01*
G03X1687100Y605597I168J-109D01*
G01X1687950Y604296D01*
Y603340D01*
G02X1687897Y603202I-203J-1D01*
G02X1687747Y603136I-150J137D01*
G01X1684847D01*
G02X1684800Y603142I2J204D01*
G02X1684644Y603340I48J198D01*
G01Y604296D01*
X1684670Y604337D01*
X1684672Y604340D01*
X1684673Y604342D01*
G02X1684675Y604345I167J-109D01*
G01X1684677Y604348D01*
X1684915Y604713D01*
X1684937Y604747D01*
X1685016Y604869D01*
X1685463Y605554D01*
G03X1685486Y605647I-177J93D01*
G01Y605749D01*
G03X1685453Y605859I-200J0D01*
G01X1685358Y606004D01*
X1685112Y606380D01*
X1684644Y607094D01*
Y608050D01*
G02X1684697Y608188I203J1D01*
G37*
G36*
G01X323839Y615300D02*
G02X323989Y615366I150J-137D01*
G01X326889D01*
G02X326936Y615360I-2J-204D01*
G02X327092Y615162I-48J-198D01*
G01Y614201D01*
X326377Y613110D01*
X326250Y612914D01*
G03X326242Y612709I168J-109D01*
G01X327092Y611408D01*
Y610452D01*
G02X327039Y610314I-203J-1D01*
G02X326889Y610248I-150J137D01*
G01X323989D01*
G02X323942Y610254I2J204D01*
G02X323786Y610452I48J198D01*
G01Y611408D01*
X323812Y611449D01*
X323814Y611452D01*
X323815Y611454D01*
G02X323817Y611457I167J-109D01*
G01X323819Y611460D01*
X324057Y611825D01*
X324079Y611859D01*
X324158Y611981D01*
X324605Y612666D01*
G03X324628Y612759I-177J93D01*
G01Y612861D01*
G03X324595Y612971I-200J0D01*
G01X324500Y613116D01*
X324254Y613492D01*
X323786Y614206D01*
Y615162D01*
G02X323839Y615300I203J1D01*
G37*
G36*
G01X780925D02*
G02X781075Y615366I150J-137D01*
G01X783975D01*
G02X784022Y615360I-2J-204D01*
G02X784178Y615162I-48J-198D01*
G01Y614201D01*
X783463Y613110D01*
X783336Y612914D01*
G03X783328Y612709I168J-109D01*
G01X784178Y611408D01*
Y610452D01*
G02X784125Y610314I-203J-1D01*
G02X783975Y610248I-150J137D01*
G01X781075D01*
G02X781028Y610254I2J204D01*
G02X780872Y610452I48J198D01*
G01Y611408D01*
X780898Y611449D01*
X780900Y611452D01*
X780901Y611454D01*
G02X780903Y611457I167J-109D01*
G01X780905Y611460D01*
X781143Y611825D01*
X781165Y611859D01*
X781244Y611981D01*
X781691Y612666D01*
G03X781714Y612759I-177J93D01*
G01Y612861D01*
G03X781681Y612971I-200J0D01*
G01X781586Y613116D01*
X781340Y613492D01*
X780872Y614206D01*
Y615162D01*
G02X780925Y615300I203J1D01*
G37*
G36*
G01X1695099D02*
G02X1695249Y615366I150J-137D01*
G01X1698149D01*
G02X1698196Y615360I-2J-204D01*
G02X1698352Y615162I-48J-198D01*
G01Y614201D01*
X1697637Y613110D01*
X1697510Y612914D01*
G03X1697502Y612709I168J-109D01*
G01X1698352Y611408D01*
Y610452D01*
G02X1698299Y610314I-203J-1D01*
G02X1698149Y610248I-150J137D01*
G01X1695249D01*
G02X1695202Y610254I2J204D01*
G02X1695046Y610452I48J198D01*
G01Y611408D01*
X1695072Y611449D01*
X1695074Y611452D01*
X1695075Y611454D01*
G02X1695077Y611457I167J-109D01*
G01X1695079Y611460D01*
X1695317Y611825D01*
X1695339Y611859D01*
X1695418Y611981D01*
X1695865Y612666D01*
G03X1695888Y612759I-177J93D01*
G01Y612861D01*
G03X1695855Y612971I-200J0D01*
G01X1695760Y613116D01*
X1695514Y613492D01*
X1695046Y614206D01*
Y615162D01*
G02X1695099Y615300I203J1D01*
G37*
G36*
G01X111494Y1456412D02*
G02X111292Y1456210I-202J0D01*
G01X108472D01*
G02X108270Y1456413I1J203D01*
G01Y1457032D01*
G03X108220Y1457164I-200J0D01*
G02Y1460080I1661J1458D01*
G03X108270Y1460212I-150J132D01*
G01Y1462151D01*
G03X108220Y1462283I-200J0D01*
G02Y1465199I1661J1458D01*
G03X108270Y1465331I-150J132D01*
G01Y1465952D01*
G02X108472Y1466154I202J0D01*
G01X111292D01*
G02X111494Y1465951I-1J-203D01*
G01Y1465331D01*
G03X111544Y1465199I200J0D01*
G02Y1462283I-1661J-1458D01*
G03X111494Y1462151I150J-132D01*
G01Y1460212D01*
G03X111544Y1460080I200J0D01*
G02Y1457164I-1661J-1458D01*
G03X111494Y1457032I150J-132D01*
G01Y1456412D01*
G37*
G36*
G01X319368D02*
G02X319166Y1456210I-202J0D01*
G01X316346D01*
G02X316144Y1456413I1J203D01*
G01Y1457032D01*
G03X316094Y1457164I-200J0D01*
G02Y1460080I1661J1458D01*
G03X316144Y1460212I-150J132D01*
G01Y1462151D01*
G03X316094Y1462283I-200J0D01*
G02Y1465199I1661J1458D01*
G03X316144Y1465331I-150J132D01*
G01Y1465952D01*
G02X316346Y1466154I202J0D01*
G01X319166D01*
G02X319368Y1465951I-1J-203D01*
G01Y1465331D01*
G03X319418Y1465199I200J0D01*
G02Y1462283I-1661J-1458D01*
G03X319368Y1462151I150J-132D01*
G01Y1460212D01*
G03X319418Y1460080I200J0D01*
G02Y1457164I-1661J-1458D01*
G03X319368Y1457032I150J-132D01*
G01Y1456412D01*
G37*
G36*
G01X336690D02*
G02X336488Y1456210I-202J0D01*
G01X333668D01*
G02X333466Y1456413I1J203D01*
G01Y1457032D01*
G03X333416Y1457164I-200J0D01*
G02Y1460080I1661J1458D01*
G03X333466Y1460212I-150J132D01*
G01Y1462151D01*
G03X333416Y1462283I-200J0D01*
G02Y1465199I1661J1458D01*
G03X333466Y1465331I-150J132D01*
G01Y1465952D01*
G02X333668Y1466154I202J0D01*
G01X336488D01*
G02X336690Y1465951I-1J-203D01*
G01Y1465331D01*
G03X336740Y1465199I200J0D01*
G02Y1462283I-1661J-1458D01*
G03X336690Y1462151I150J-132D01*
G01Y1460212D01*
G03X336740Y1460080I200J0D01*
G02Y1457164I-1661J-1458D01*
G03X336690Y1457032I150J-132D01*
G01Y1456412D01*
G37*
G36*
G01X628157Y1466154D02*
X630977D01*
G02X631180Y1465951I0J-203D01*
G01Y1465329D01*
G03X631230Y1465197I200J0D01*
G02Y1462285I-1664J-1456D01*
G03X631180Y1462153I150J-132D01*
G01Y1460210D01*
G03X631230Y1460078I200J0D01*
G02Y1457166I-1664J-1456D01*
G03X631180Y1457034I150J-132D01*
G01Y1456413D01*
G02X630977Y1456210I-203J0D01*
G01X628157D01*
G02X627954Y1456413I0J203D01*
G01Y1457034D01*
G03X627904Y1457166I-200J0D01*
G02Y1460078I1664J1456D01*
G03X627954Y1460210I-150J132D01*
G01Y1462153D01*
G03X627904Y1462285I-200J0D01*
G02Y1465197I1664J1456D01*
G03X627954Y1465329I-150J132D01*
G01Y1465951D01*
G02X628157Y1466154I203J0D01*
G37*
G36*
G01X1133462Y1456412D02*
G02X1133260Y1456210I-202J0D01*
G01X1130440D01*
G02X1130238Y1456413I1J203D01*
G01Y1457032D01*
G03X1130188Y1457164I-200J0D01*
G02Y1460080I1661J1458D01*
G03X1130238Y1460212I-150J132D01*
G01Y1462151D01*
G03X1130188Y1462283I-200J0D01*
G02Y1465199I1661J1458D01*
G03X1130238Y1465331I-150J132D01*
G01Y1465952D01*
G02X1130440Y1466154I202J0D01*
G01X1133260D01*
G02X1133462Y1465951I-1J-203D01*
G01Y1465331D01*
G03X1133512Y1465199I200J0D01*
G02Y1462283I-1661J-1458D01*
G03X1133462Y1462151I150J-132D01*
G01Y1460212D01*
G03X1133512Y1460080I200J0D01*
G02Y1457164I-1661J-1458D01*
G03X1133462Y1457032I150J-132D01*
G01Y1456412D01*
G37*
G36*
G01X1147763Y1466154D02*
X1150583D01*
G02X1150786Y1465951I0J-203D01*
G01Y1465329D01*
G03X1150836Y1465197I200J0D01*
G02Y1462285I-1664J-1456D01*
G03X1150786Y1462153I150J-132D01*
G01Y1460210D01*
G03X1150836Y1460078I200J0D01*
G02Y1457166I-1664J-1456D01*
G03X1150786Y1457034I150J-132D01*
G01Y1456413D01*
G02X1150583Y1456210I-203J0D01*
G01X1147763D01*
G02X1147560Y1456413I0J203D01*
G01Y1457034D01*
G03X1147510Y1457166I-200J0D01*
G02Y1460078I1664J1456D01*
G03X1147560Y1460210I-150J132D01*
G01Y1462153D01*
G03X1147510Y1462285I-200J0D01*
G02Y1465197I1664J1456D01*
G03X1147560Y1465329I-150J132D01*
G01Y1465951D01*
G02X1147763Y1466154I203J0D01*
G37*
G36*
G01X1650125D02*
X1652945D01*
G02X1653148Y1465951I0J-203D01*
G01Y1465329D01*
G03X1653198Y1465197I200J0D01*
G02Y1462285I-1664J-1456D01*
G03X1653148Y1462153I150J-132D01*
G01Y1460210D01*
G03X1653198Y1460078I200J0D01*
G02Y1457166I-1664J-1456D01*
G03X1653148Y1457034I150J-132D01*
G01Y1456413D01*
G02X1652945Y1456210I-203J0D01*
G01X1650125D01*
G02X1649922Y1456413I0J203D01*
G01Y1457034D01*
G03X1649872Y1457166I-200J0D01*
G02Y1460078I1664J1456D01*
G03X1649922Y1460210I-150J132D01*
G01Y1462153D01*
G03X1649872Y1462285I-200J0D01*
G02Y1465197I1664J1456D01*
G03X1649922Y1465329I-150J132D01*
G01Y1465951D01*
G02X1650125Y1466154I203J0D01*
G37*
G36*
G01X1670470Y1456412D02*
G02X1670268Y1456210I-202J0D01*
G01X1667448D01*
G02X1667246Y1456413I1J203D01*
G01Y1457032D01*
G03X1667196Y1457164I-200J0D01*
G02Y1460080I1661J1458D01*
G03X1667246Y1460212I-150J132D01*
G01Y1462151D01*
G03X1667196Y1462283I-200J0D01*
G02Y1465199I1661J1458D01*
G03X1667246Y1465331I-150J132D01*
G01Y1465952D01*
G02X1667448Y1466154I202J0D01*
G01X1670268D01*
G02X1670470Y1465951I-1J-203D01*
G01Y1465331D01*
G03X1670520Y1465199I200J0D01*
G02Y1462283I-1661J-1458D01*
G03X1670470Y1462151I150J-132D01*
G01Y1460212D01*
G03X1670520Y1460080I200J0D01*
G02Y1457164I-1661J-1458D01*
G03X1670470Y1457032I150J-132D01*
G01Y1456412D01*
G37*
G36*
G01X117133Y1470484D02*
X119953D01*
G02X120156Y1470281I0J-203D01*
G01Y1469659D01*
G03X120206Y1469527I200J0D01*
G02Y1466615I-1664J-1456D01*
G03X120156Y1466483I150J-132D01*
G01Y1464541D01*
G03X120206Y1464409I200J0D01*
G02Y1461497I-1664J-1456D01*
G03X120156Y1461365I150J-132D01*
G01Y1460743D01*
G02X119953Y1460540I-203J0D01*
G01X117133D01*
G02X116930Y1460743I0J203D01*
G01Y1461365D01*
G03X116880Y1461497I-200J0D01*
G02Y1464409I1664J1456D01*
G03X116930Y1464541I-150J132D01*
G01Y1466483D01*
G03X116880Y1466615I-200J0D01*
G02Y1469527I1664J1456D01*
G03X116930Y1469659I-150J132D01*
G01Y1470281D01*
G02X117133Y1470484I203J0D01*
G37*
G36*
G01X310706Y1460742D02*
G02X310504Y1460540I-202J0D01*
G01X307684D01*
G02X307482Y1460743I1J203D01*
G01Y1461363D01*
G03X307432Y1461495I-200J0D01*
G02Y1464411I1661J1458D01*
G03X307482Y1464543I-150J132D01*
G01Y1466481D01*
G03X307432Y1466613I-200J0D01*
G02Y1469529I1661J1458D01*
G03X307482Y1469661I-150J132D01*
G01Y1470282D01*
G02X307684Y1470484I202J0D01*
G01X310504D01*
G02X310706Y1470281I-1J-203D01*
G01Y1469661D01*
G03X310756Y1469529I200J0D01*
G02Y1466613I-1661J-1458D01*
G03X310706Y1466481I150J-132D01*
G01Y1464543D01*
G03X310756Y1464411I200J0D01*
G02Y1461495I-1661J-1458D01*
G03X310706Y1461363I150J-132D01*
G01Y1460742D01*
G37*
G36*
G01X325007Y1470484D02*
X327827D01*
G02X328030Y1470281I0J-203D01*
G01Y1469659D01*
G03X328080Y1469527I200J0D01*
G02Y1466615I-1664J-1456D01*
G03X328030Y1466483I150J-132D01*
G01Y1464541D01*
G03X328080Y1464409I200J0D01*
G02Y1461497I-1664J-1456D01*
G03X328030Y1461365I150J-132D01*
G01Y1460743D01*
G02X327827Y1460540I-203J0D01*
G01X325007D01*
G02X324804Y1460743I0J203D01*
G01Y1461365D01*
G03X324754Y1461497I-200J0D01*
G02Y1464409I1664J1456D01*
G03X324804Y1464541I-150J132D01*
G01Y1466483D01*
G03X324754Y1466615I-200J0D01*
G02Y1469527I1664J1456D01*
G03X324804Y1469659I-150J132D01*
G01Y1470281D01*
G02X325007Y1470484I203J0D01*
G37*
G36*
G01X345352Y1460742D02*
G02X345150Y1460540I-202J0D01*
G01X342330D01*
G02X342128Y1460743I1J203D01*
G01Y1461363D01*
G03X342078Y1461495I-200J0D01*
G02Y1464411I1661J1458D01*
G03X342128Y1464543I-150J132D01*
G01Y1466481D01*
G03X342078Y1466613I-200J0D01*
G02Y1469529I1661J1458D01*
G03X342128Y1469661I-150J132D01*
G01Y1470282D01*
G02X342330Y1470484I202J0D01*
G01X345150D01*
G02X345352Y1470281I-1J-203D01*
G01Y1469661D01*
G03X345402Y1469529I200J0D01*
G02Y1466613I-1661J-1458D01*
G03X345352Y1466481I150J-132D01*
G01Y1464543D01*
G03X345402Y1464411I200J0D01*
G02Y1461495I-1661J-1458D01*
G03X345352Y1461363I150J-132D01*
G01Y1460742D01*
G37*
G36*
G01X639840D02*
G02X639638Y1460540I-202J0D01*
G01X636818D01*
G02X636616Y1460743I1J203D01*
G01Y1461363D01*
G03X636566Y1461495I-200J0D01*
G02Y1464411I1661J1458D01*
G03X636616Y1464543I-150J132D01*
G01Y1466481D01*
G03X636566Y1466613I-200J0D01*
G02Y1469529I1661J1458D01*
G03X636616Y1469661I-150J132D01*
G01Y1470282D01*
G02X636818Y1470484I202J0D01*
G01X639638D01*
G02X639840Y1470281I-1J-203D01*
G01Y1469661D01*
G03X639890Y1469529I200J0D01*
G02Y1466613I-1661J-1458D01*
G03X639840Y1466481I150J-132D01*
G01Y1464543D01*
G03X639890Y1464411I200J0D01*
G02Y1461495I-1661J-1458D01*
G03X639840Y1461363I150J-132D01*
G01Y1460742D01*
G37*
G36*
G01X1139101Y1470484D02*
X1141921D01*
G02X1142124Y1470281I0J-203D01*
G01Y1469659D01*
G03X1142174Y1469527I200J0D01*
G02Y1466615I-1664J-1456D01*
G03X1142124Y1466483I150J-132D01*
G01Y1464541D01*
G03X1142174Y1464409I200J0D01*
G02Y1461497I-1664J-1456D01*
G03X1142124Y1461365I150J-132D01*
G01Y1460743D01*
G02X1141921Y1460540I-203J0D01*
G01X1139101D01*
G02X1138898Y1460743I0J203D01*
G01Y1461365D01*
G03X1138848Y1461497I-200J0D01*
G02Y1464409I1664J1456D01*
G03X1138898Y1464541I-150J132D01*
G01Y1466483D01*
G03X1138848Y1466615I-200J0D01*
G02Y1469527I1664J1456D01*
G03X1138898Y1469659I-150J132D01*
G01Y1470281D01*
G02X1139101Y1470484I203J0D01*
G37*
G36*
G01X1159446Y1460742D02*
G02X1159244Y1460540I-202J0D01*
G01X1156424D01*
G02X1156222Y1460743I1J203D01*
G01Y1461363D01*
G03X1156172Y1461495I-200J0D01*
G02Y1464411I1661J1458D01*
G03X1156222Y1464543I-150J132D01*
G01Y1466481D01*
G03X1156172Y1466613I-200J0D01*
G02Y1469529I1661J1458D01*
G03X1156222Y1469661I-150J132D01*
G01Y1470282D01*
G02X1156424Y1470484I202J0D01*
G01X1159244D01*
G02X1159446Y1470281I-1J-203D01*
G01Y1469661D01*
G03X1159496Y1469529I200J0D01*
G02Y1466613I-1661J-1458D01*
G03X1159446Y1466481I150J-132D01*
G01Y1464543D01*
G03X1159496Y1464411I200J0D01*
G02Y1461495I-1661J-1458D01*
G03X1159446Y1461363I150J-132D01*
G01Y1460742D01*
G37*
G36*
G01X1661808D02*
G02X1661606Y1460540I-202J0D01*
G01X1658786D01*
G02X1658584Y1460743I1J203D01*
G01Y1461363D01*
G03X1658534Y1461495I-200J0D01*
G02Y1464411I1661J1458D01*
G03X1658584Y1464543I-150J132D01*
G01Y1466481D01*
G03X1658534Y1466613I-200J0D01*
G02Y1469529I1661J1458D01*
G03X1658584Y1469661I-150J132D01*
G01Y1470282D01*
G02X1658786Y1470484I202J0D01*
G01X1661606D01*
G02X1661808Y1470281I-1J-203D01*
G01Y1469661D01*
G03X1661858Y1469529I200J0D01*
G02Y1466613I-1661J-1458D01*
G03X1661808Y1466481I150J-132D01*
G01Y1464543D01*
G03X1661858Y1464411I200J0D01*
G02Y1461495I-1661J-1458D01*
G03X1661808Y1461363I150J-132D01*
G01Y1460742D01*
G37*
G36*
G01X1676109Y1470484D02*
X1678929D01*
G02X1679132Y1470281I0J-203D01*
G01Y1469659D01*
G03X1679182Y1469527I200J0D01*
G02Y1466615I-1664J-1456D01*
G03X1679132Y1466483I150J-132D01*
G01Y1464541D01*
G03X1679182Y1464409I200J0D01*
G02Y1461497I-1664J-1456D01*
G03X1679132Y1461365I150J-132D01*
G01Y1460743D01*
G02X1678929Y1460540I-203J0D01*
G01X1676109D01*
G02X1675906Y1460743I0J203D01*
G01Y1461365D01*
G03X1675856Y1461497I-200J0D01*
G02Y1464409I1664J1456D01*
G03X1675906Y1464541I-150J132D01*
G01Y1466483D01*
G03X1675856Y1466615I-200J0D01*
G02Y1469527I1664J1456D01*
G03X1675906Y1469659I-150J132D01*
G01Y1470281D01*
G02X1676109Y1470484I203J0D01*
G37*
G36*
G01X111494Y1471766D02*
G02X111292Y1471564I-202J0D01*
G01X108472D01*
G02X108270Y1471767I1J203D01*
G01Y1472387D01*
G03X108220Y1472519I-200J0D01*
G02Y1475435I1661J1458D01*
G03X108270Y1475567I-150J132D01*
G01Y1477505D01*
G03X108220Y1477637I-200J0D01*
G02Y1480553I1661J1458D01*
G03X108270Y1480685I-150J132D01*
G01Y1481306D01*
G02X108472Y1481508I202J0D01*
G01X111292D01*
G02X111494Y1481305I-1J-203D01*
G01Y1480685D01*
G03X111544Y1480553I200J0D01*
G02Y1477637I-1661J-1458D01*
G03X111494Y1477505I150J-132D01*
G01Y1475567D01*
G03X111544Y1475435I200J0D01*
G02Y1472519I-1661J-1458D01*
G03X111494Y1472387I150J-132D01*
G01Y1471766D01*
G37*
G36*
G01X319368D02*
G02X319166Y1471564I-202J0D01*
G01X316346D01*
G02X316144Y1471767I1J203D01*
G01Y1472387D01*
G03X316094Y1472519I-200J0D01*
G02Y1475435I1661J1458D01*
G03X316144Y1475567I-150J132D01*
G01Y1477505D01*
G03X316094Y1477637I-200J0D01*
G02Y1480553I1661J1458D01*
G03X316144Y1480685I-150J132D01*
G01Y1481306D01*
G02X316346Y1481508I202J0D01*
G01X319166D01*
G02X319368Y1481305I-1J-203D01*
G01Y1480685D01*
G03X319418Y1480553I200J0D01*
G02Y1477637I-1661J-1458D01*
G03X319368Y1477505I150J-132D01*
G01Y1475567D01*
G03X319418Y1475435I200J0D01*
G02Y1472519I-1661J-1458D01*
G03X319368Y1472387I150J-132D01*
G01Y1471766D01*
G37*
G36*
G01X336690D02*
G02X336488Y1471564I-202J0D01*
G01X333668D01*
G02X333466Y1471767I1J203D01*
G01Y1472387D01*
G03X333416Y1472519I-200J0D01*
G02Y1475435I1661J1458D01*
G03X333466Y1475567I-150J132D01*
G01Y1477505D01*
G03X333416Y1477637I-200J0D01*
G02Y1480553I1661J1458D01*
G03X333466Y1480685I-150J132D01*
G01Y1481306D01*
G02X333668Y1481508I202J0D01*
G01X336488D01*
G02X336690Y1481305I-1J-203D01*
G01Y1480685D01*
G03X336740Y1480553I200J0D01*
G02Y1477637I-1661J-1458D01*
G03X336690Y1477505I150J-132D01*
G01Y1475567D01*
G03X336740Y1475435I200J0D01*
G02Y1472519I-1661J-1458D01*
G03X336690Y1472387I150J-132D01*
G01Y1471766D01*
G37*
G36*
G01X628157Y1481508D02*
X630977D01*
G02X631180Y1481305I0J-203D01*
G01Y1480683D01*
G03X631230Y1480551I200J0D01*
G02Y1477639I-1664J-1456D01*
G03X631180Y1477507I150J-132D01*
G01Y1475565D01*
G03X631230Y1475433I200J0D01*
G02Y1472521I-1664J-1456D01*
G03X631180Y1472389I150J-132D01*
G01Y1471767D01*
G02X630977Y1471564I-203J0D01*
G01X628157D01*
G02X627954Y1471767I0J203D01*
G01Y1472389D01*
G03X627904Y1472521I-200J0D01*
G02Y1475433I1664J1456D01*
G03X627954Y1475565I-150J132D01*
G01Y1477507D01*
G03X627904Y1477639I-200J0D01*
G02Y1480551I1664J1456D01*
G03X627954Y1480683I-150J132D01*
G01Y1481305D01*
G02X628157Y1481508I203J0D01*
G37*
G36*
G01X1133462Y1471766D02*
G02X1133260Y1471564I-202J0D01*
G01X1130440D01*
G02X1130238Y1471767I1J203D01*
G01Y1472387D01*
G03X1130188Y1472519I-200J0D01*
G02Y1475435I1661J1458D01*
G03X1130238Y1475567I-150J132D01*
G01Y1477505D01*
G03X1130188Y1477637I-200J0D01*
G02Y1480553I1661J1458D01*
G03X1130238Y1480685I-150J132D01*
G01Y1481306D01*
G02X1130440Y1481508I202J0D01*
G01X1133260D01*
G02X1133462Y1481305I-1J-203D01*
G01Y1480685D01*
G03X1133512Y1480553I200J0D01*
G02Y1477637I-1661J-1458D01*
G03X1133462Y1477505I150J-132D01*
G01Y1475567D01*
G03X1133512Y1475435I200J0D01*
G02Y1472519I-1661J-1458D01*
G03X1133462Y1472387I150J-132D01*
G01Y1471766D01*
G37*
G36*
G01X1147763Y1481508D02*
X1150583D01*
G02X1150786Y1481305I0J-203D01*
G01Y1480683D01*
G03X1150836Y1480551I200J0D01*
G02Y1477639I-1664J-1456D01*
G03X1150786Y1477507I150J-132D01*
G01Y1475565D01*
G03X1150836Y1475433I200J0D01*
G02Y1472521I-1664J-1456D01*
G03X1150786Y1472389I150J-132D01*
G01Y1471767D01*
G02X1150583Y1471564I-203J0D01*
G01X1147763D01*
G02X1147560Y1471767I0J203D01*
G01Y1472389D01*
G03X1147510Y1472521I-200J0D01*
G02Y1475433I1664J1456D01*
G03X1147560Y1475565I-150J132D01*
G01Y1477507D01*
G03X1147510Y1477639I-200J0D01*
G02Y1480551I1664J1456D01*
G03X1147560Y1480683I-150J132D01*
G01Y1481305D01*
G02X1147763Y1481508I203J0D01*
G37*
G36*
G01X1650125D02*
X1652945D01*
G02X1653148Y1481305I0J-203D01*
G01Y1480683D01*
G03X1653198Y1480551I200J0D01*
G02Y1477639I-1664J-1456D01*
G03X1653148Y1477507I150J-132D01*
G01Y1475565D01*
G03X1653198Y1475433I200J0D01*
G02Y1472521I-1664J-1456D01*
G03X1653148Y1472389I150J-132D01*
G01Y1471767D01*
G02X1652945Y1471564I-203J0D01*
G01X1650125D01*
G02X1649922Y1471767I0J203D01*
G01Y1472389D01*
G03X1649872Y1472521I-200J0D01*
G02Y1475433I1664J1456D01*
G03X1649922Y1475565I-150J132D01*
G01Y1477507D01*
G03X1649872Y1477639I-200J0D01*
G02Y1480551I1664J1456D01*
G03X1649922Y1480683I-150J132D01*
G01Y1481305D01*
G02X1650125Y1481508I203J0D01*
G37*
G36*
G01X1670470Y1471766D02*
G02X1670268Y1471564I-202J0D01*
G01X1667448D01*
G02X1667246Y1471767I1J203D01*
G01Y1472387D01*
G03X1667196Y1472519I-200J0D01*
G02Y1475435I1661J1458D01*
G03X1667246Y1475567I-150J132D01*
G01Y1477505D01*
G03X1667196Y1477637I-200J0D01*
G02Y1480553I1661J1458D01*
G03X1667246Y1480685I-150J132D01*
G01Y1481306D01*
G02X1667448Y1481508I202J0D01*
G01X1670268D01*
G02X1670470Y1481305I-1J-203D01*
G01Y1480685D01*
G03X1670520Y1480553I200J0D01*
G02Y1477637I-1661J-1458D01*
G03X1670470Y1477505I150J-132D01*
G01Y1475567D01*
G03X1670520Y1475435I200J0D01*
G02Y1472519I-1661J-1458D01*
G03X1670470Y1472387I150J-132D01*
G01Y1471766D01*
G37*
G36*
G01X117133Y1485838D02*
X119953D01*
G02X120156Y1485635I0J-203D01*
G01Y1485014D01*
G03X120206Y1484882I200J0D01*
G02Y1481970I-1664J-1456D01*
G03X120156Y1481838I150J-132D01*
G01Y1479896D01*
G03X120206Y1479764I200J0D01*
G02Y1476852I-1664J-1456D01*
G03X120156Y1476720I150J-132D01*
G01Y1476097D01*
G02X119953Y1475894I-203J0D01*
G01X117133D01*
G02X116930Y1476097I0J203D01*
G01Y1476720D01*
G03X116880Y1476852I-200J0D01*
G02Y1479764I1664J1456D01*
G03X116930Y1479896I-150J132D01*
G01Y1481838D01*
G03X116880Y1481970I-200J0D01*
G02Y1484882I1664J1456D01*
G03X116930Y1485014I-150J132D01*
G01Y1485635D01*
G02X117133Y1485838I203J0D01*
G37*
G36*
G01X310706Y1476096D02*
G02X310504Y1475894I-202J0D01*
G01X307684D01*
G02X307482Y1476097I1J203D01*
G01Y1476718D01*
G03X307432Y1476850I-200J0D01*
G02Y1479766I1661J1458D01*
G03X307482Y1479898I-150J132D01*
G01Y1481836D01*
G03X307432Y1481968I-200J0D01*
G02Y1484884I1661J1458D01*
G03X307482Y1485016I-150J132D01*
G01Y1485636D01*
G02X307684Y1485838I202J0D01*
G01X310504D01*
G02X310706Y1485635I-1J-203D01*
G01Y1485016D01*
G03X310756Y1484884I200J0D01*
G02Y1481968I-1661J-1458D01*
G03X310706Y1481836I150J-132D01*
G01Y1479898D01*
G03X310756Y1479766I200J0D01*
G02Y1476850I-1661J-1458D01*
G03X310706Y1476718I150J-132D01*
G01Y1476096D01*
G37*
G36*
G01X325007Y1485838D02*
X327827D01*
G02X328030Y1485635I0J-203D01*
G01Y1485014D01*
G03X328080Y1484882I200J0D01*
G02Y1481970I-1664J-1456D01*
G03X328030Y1481838I150J-132D01*
G01Y1479896D01*
G03X328080Y1479764I200J0D01*
G02Y1476852I-1664J-1456D01*
G03X328030Y1476720I150J-132D01*
G01Y1476097D01*
G02X327827Y1475894I-203J0D01*
G01X325007D01*
G02X324804Y1476097I0J203D01*
G01Y1476720D01*
G03X324754Y1476852I-200J0D01*
G02Y1479764I1664J1456D01*
G03X324804Y1479896I-150J132D01*
G01Y1481838D01*
G03X324754Y1481970I-200J0D01*
G02Y1484882I1664J1456D01*
G03X324804Y1485014I-150J132D01*
G01Y1485635D01*
G02X325007Y1485838I203J0D01*
G37*
G36*
G01X345352Y1476096D02*
G02X345150Y1475894I-202J0D01*
G01X342330D01*
G02X342128Y1476097I1J203D01*
G01Y1476718D01*
G03X342078Y1476850I-200J0D01*
G02Y1479766I1661J1458D01*
G03X342128Y1479898I-150J132D01*
G01Y1481836D01*
G03X342078Y1481968I-200J0D01*
G02Y1484884I1661J1458D01*
G03X342128Y1485016I-150J132D01*
G01Y1485636D01*
G02X342330Y1485838I202J0D01*
G01X345150D01*
G02X345352Y1485635I-1J-203D01*
G01Y1485016D01*
G03X345402Y1484884I200J0D01*
G02Y1481968I-1661J-1458D01*
G03X345352Y1481836I150J-132D01*
G01Y1479898D01*
G03X345402Y1479766I200J0D01*
G02Y1476850I-1661J-1458D01*
G03X345352Y1476718I150J-132D01*
G01Y1476096D01*
G37*
G36*
G01X639840D02*
G02X639638Y1475894I-202J0D01*
G01X636818D01*
G02X636616Y1476097I1J203D01*
G01Y1476718D01*
G03X636566Y1476850I-200J0D01*
G02Y1479766I1661J1458D01*
G03X636616Y1479898I-150J132D01*
G01Y1481836D01*
G03X636566Y1481968I-200J0D01*
G02Y1484884I1661J1458D01*
G03X636616Y1485016I-150J132D01*
G01Y1485636D01*
G02X636818Y1485838I202J0D01*
G01X639638D01*
G02X639840Y1485635I-1J-203D01*
G01Y1485016D01*
G03X639890Y1484884I200J0D01*
G02Y1481968I-1661J-1458D01*
G03X639840Y1481836I150J-132D01*
G01Y1479898D01*
G03X639890Y1479766I200J0D01*
G02Y1476850I-1661J-1458D01*
G03X639840Y1476718I150J-132D01*
G01Y1476096D01*
G37*
G36*
G01X1139101Y1485838D02*
X1141921D01*
G02X1142124Y1485635I0J-203D01*
G01Y1485014D01*
G03X1142174Y1484882I200J0D01*
G02Y1481970I-1664J-1456D01*
G03X1142124Y1481838I150J-132D01*
G01Y1479896D01*
G03X1142174Y1479764I200J0D01*
G02Y1476852I-1664J-1456D01*
G03X1142124Y1476720I150J-132D01*
G01Y1476097D01*
G02X1141921Y1475894I-203J0D01*
G01X1139101D01*
G02X1138898Y1476097I0J203D01*
G01Y1476720D01*
G03X1138848Y1476852I-200J0D01*
G02Y1479764I1664J1456D01*
G03X1138898Y1479896I-150J132D01*
G01Y1481838D01*
G03X1138848Y1481970I-200J0D01*
G02Y1484882I1664J1456D01*
G03X1138898Y1485014I-150J132D01*
G01Y1485635D01*
G02X1139101Y1485838I203J0D01*
G37*
G36*
G01X1159446Y1476096D02*
G02X1159244Y1475894I-202J0D01*
G01X1156424D01*
G02X1156222Y1476097I1J203D01*
G01Y1476718D01*
G03X1156172Y1476850I-200J0D01*
G02Y1479766I1661J1458D01*
G03X1156222Y1479898I-150J132D01*
G01Y1481836D01*
G03X1156172Y1481968I-200J0D01*
G02Y1484884I1661J1458D01*
G03X1156222Y1485016I-150J132D01*
G01Y1485636D01*
G02X1156424Y1485838I202J0D01*
G01X1159244D01*
G02X1159446Y1485635I-1J-203D01*
G01Y1485016D01*
G03X1159496Y1484884I200J0D01*
G02Y1481968I-1661J-1458D01*
G03X1159446Y1481836I150J-132D01*
G01Y1479898D01*
G03X1159496Y1479766I200J0D01*
G02Y1476850I-1661J-1458D01*
G03X1159446Y1476718I150J-132D01*
G01Y1476096D01*
G37*
G36*
G01X1661808D02*
G02X1661606Y1475894I-202J0D01*
G01X1658786D01*
G02X1658584Y1476097I1J203D01*
G01Y1476718D01*
G03X1658534Y1476850I-200J0D01*
G02Y1479766I1661J1458D01*
G03X1658584Y1479898I-150J132D01*
G01Y1481836D01*
G03X1658534Y1481968I-200J0D01*
G02Y1484884I1661J1458D01*
G03X1658584Y1485016I-150J132D01*
G01Y1485636D01*
G02X1658786Y1485838I202J0D01*
G01X1661606D01*
G02X1661808Y1485635I-1J-203D01*
G01Y1485016D01*
G03X1661858Y1484884I200J0D01*
G02Y1481968I-1661J-1458D01*
G03X1661808Y1481836I150J-132D01*
G01Y1479898D01*
G03X1661858Y1479766I200J0D01*
G02Y1476850I-1661J-1458D01*
G03X1661808Y1476718I150J-132D01*
G01Y1476096D01*
G37*
G36*
G01X1676109Y1485838D02*
X1678929D01*
G02X1679132Y1485635I0J-203D01*
G01Y1485014D01*
G03X1679182Y1484882I200J0D01*
G02Y1481970I-1664J-1456D01*
G03X1679132Y1481838I150J-132D01*
G01Y1479896D01*
G03X1679182Y1479764I200J0D01*
G02Y1476852I-1664J-1456D01*
G03X1679132Y1476720I150J-132D01*
G01Y1476097D01*
G02X1678929Y1475894I-203J0D01*
G01X1676109D01*
G02X1675906Y1476097I0J203D01*
G01Y1476720D01*
G03X1675856Y1476852I-200J0D01*
G02Y1479764I1664J1456D01*
G03X1675906Y1479896I-150J132D01*
G01Y1481838D01*
G03X1675856Y1481970I-200J0D01*
G02Y1484882I1664J1456D01*
G03X1675906Y1485014I-150J132D01*
G01Y1485635D01*
G02X1676109Y1485838I203J0D01*
G37*
G36*
G01X111494Y1487120D02*
G02X111292Y1486918I-202J0D01*
G01X108472D01*
G02X108270Y1487121I1J203D01*
G01Y1487741D01*
G03X108220Y1487873I-200J0D01*
G02Y1490789I1661J1458D01*
G03X108270Y1490921I-150J132D01*
G01Y1492859D01*
G03X108220Y1492991I-200J0D01*
G02Y1495907I1661J1458D01*
G03X108270Y1496039I-150J132D01*
G01Y1496660D01*
G02X108472Y1496862I202J0D01*
G01X111292D01*
G02X111494Y1496659I-1J-203D01*
G01Y1496039D01*
G03X111544Y1495907I200J0D01*
G02Y1492991I-1661J-1458D01*
G03X111494Y1492859I150J-132D01*
G01Y1490921D01*
G03X111544Y1490789I200J0D01*
G02Y1487873I-1661J-1458D01*
G03X111494Y1487741I150J-132D01*
G01Y1487120D01*
G37*
G36*
G01X319368D02*
G02X319166Y1486918I-202J0D01*
G01X316346D01*
G02X316144Y1487121I1J203D01*
G01Y1487741D01*
G03X316094Y1487873I-200J0D01*
G02Y1490789I1661J1458D01*
G03X316144Y1490921I-150J132D01*
G01Y1492859D01*
G03X316094Y1492991I-200J0D01*
G02Y1495907I1661J1458D01*
G03X316144Y1496039I-150J132D01*
G01Y1496660D01*
G02X316346Y1496862I202J0D01*
G01X319166D01*
G02X319368Y1496659I-1J-203D01*
G01Y1496039D01*
G03X319418Y1495907I200J0D01*
G02Y1492991I-1661J-1458D01*
G03X319368Y1492859I150J-132D01*
G01Y1490921D01*
G03X319418Y1490789I200J0D01*
G02Y1487873I-1661J-1458D01*
G03X319368Y1487741I150J-132D01*
G01Y1487120D01*
G37*
G36*
G01X336690D02*
G02X336488Y1486918I-202J0D01*
G01X333668D01*
G02X333466Y1487121I1J203D01*
G01Y1487741D01*
G03X333416Y1487873I-200J0D01*
G02Y1490789I1661J1458D01*
G03X333466Y1490921I-150J132D01*
G01Y1492859D01*
G03X333416Y1492991I-200J0D01*
G02Y1495907I1661J1458D01*
G03X333466Y1496039I-150J132D01*
G01Y1496660D01*
G02X333668Y1496862I202J0D01*
G01X336488D01*
G02X336690Y1496659I-1J-203D01*
G01Y1496039D01*
G03X336740Y1495907I200J0D01*
G02Y1492991I-1661J-1458D01*
G03X336690Y1492859I150J-132D01*
G01Y1490921D01*
G03X336740Y1490789I200J0D01*
G02Y1487873I-1661J-1458D01*
G03X336690Y1487741I150J-132D01*
G01Y1487120D01*
G37*
G36*
G01X628157Y1496862D02*
X630977D01*
G02X631180Y1496659I0J-203D01*
G01Y1496037D01*
G03X631230Y1495905I200J0D01*
G02Y1492993I-1664J-1456D01*
G03X631180Y1492861I150J-132D01*
G01Y1490919D01*
G03X631230Y1490787I200J0D01*
G02Y1487875I-1664J-1456D01*
G03X631180Y1487743I150J-132D01*
G01Y1487121D01*
G02X630977Y1486918I-203J0D01*
G01X628157D01*
G02X627954Y1487121I0J203D01*
G01Y1487743D01*
G03X627904Y1487875I-200J0D01*
G02Y1490787I1664J1456D01*
G03X627954Y1490919I-150J132D01*
G01Y1492861D01*
G03X627904Y1492993I-200J0D01*
G02Y1495905I1664J1456D01*
G03X627954Y1496037I-150J132D01*
G01Y1496659D01*
G02X628157Y1496862I203J0D01*
G37*
G36*
G01X1133462Y1487120D02*
G02X1133260Y1486918I-202J0D01*
G01X1130440D01*
G02X1130238Y1487121I1J203D01*
G01Y1487741D01*
G03X1130188Y1487873I-200J0D01*
G02Y1490789I1661J1458D01*
G03X1130238Y1490921I-150J132D01*
G01Y1492859D01*
G03X1130188Y1492991I-200J0D01*
G02Y1495907I1661J1458D01*
G03X1130238Y1496039I-150J132D01*
G01Y1496660D01*
G02X1130440Y1496862I202J0D01*
G01X1133260D01*
G02X1133462Y1496659I-1J-203D01*
G01Y1496039D01*
G03X1133512Y1495907I200J0D01*
G02Y1492991I-1661J-1458D01*
G03X1133462Y1492859I150J-132D01*
G01Y1490921D01*
G03X1133512Y1490789I200J0D01*
G02Y1487873I-1661J-1458D01*
G03X1133462Y1487741I150J-132D01*
G01Y1487120D01*
G37*
G36*
G01X1147763Y1496862D02*
X1150583D01*
G02X1150786Y1496659I0J-203D01*
G01Y1496037D01*
G03X1150836Y1495905I200J0D01*
G02Y1492993I-1664J-1456D01*
G03X1150786Y1492861I150J-132D01*
G01Y1490919D01*
G03X1150836Y1490787I200J0D01*
G02Y1487875I-1664J-1456D01*
G03X1150786Y1487743I150J-132D01*
G01Y1487121D01*
G02X1150583Y1486918I-203J0D01*
G01X1147763D01*
G02X1147560Y1487121I0J203D01*
G01Y1487743D01*
G03X1147510Y1487875I-200J0D01*
G02Y1490787I1664J1456D01*
G03X1147560Y1490919I-150J132D01*
G01Y1492861D01*
G03X1147510Y1492993I-200J0D01*
G02Y1495905I1664J1456D01*
G03X1147560Y1496037I-150J132D01*
G01Y1496659D01*
G02X1147763Y1496862I203J0D01*
G37*
G36*
G01X1650125D02*
X1652945D01*
G02X1653148Y1496659I0J-203D01*
G01Y1496037D01*
G03X1653198Y1495905I200J0D01*
G02Y1492993I-1664J-1456D01*
G03X1653148Y1492861I150J-132D01*
G01Y1490919D01*
G03X1653198Y1490787I200J0D01*
G02Y1487875I-1664J-1456D01*
G03X1653148Y1487743I150J-132D01*
G01Y1487121D01*
G02X1652945Y1486918I-203J0D01*
G01X1650125D01*
G02X1649922Y1487121I0J203D01*
G01Y1487743D01*
G03X1649872Y1487875I-200J0D01*
G02Y1490787I1664J1456D01*
G03X1649922Y1490919I-150J132D01*
G01Y1492861D01*
G03X1649872Y1492993I-200J0D01*
G02Y1495905I1664J1456D01*
G03X1649922Y1496037I-150J132D01*
G01Y1496659D01*
G02X1650125Y1496862I203J0D01*
G37*
G36*
G01X1670470Y1487120D02*
G02X1670268Y1486918I-202J0D01*
G01X1667448D01*
G02X1667246Y1487121I1J203D01*
G01Y1487741D01*
G03X1667196Y1487873I-200J0D01*
G02Y1490789I1661J1458D01*
G03X1667246Y1490921I-150J132D01*
G01Y1492859D01*
G03X1667196Y1492991I-200J0D01*
G02Y1495907I1661J1458D01*
G03X1667246Y1496039I-150J132D01*
G01Y1496660D01*
G02X1667448Y1496862I202J0D01*
G01X1670268D01*
G02X1670470Y1496659I-1J-203D01*
G01Y1496039D01*
G03X1670520Y1495907I200J0D01*
G02Y1492991I-1661J-1458D01*
G03X1670470Y1492859I150J-132D01*
G01Y1490921D01*
G03X1670520Y1490789I200J0D01*
G02Y1487873I-1661J-1458D01*
G03X1670470Y1487741I150J-132D01*
G01Y1487120D01*
G37*
G36*
G01X117133Y1501192D02*
X119953D01*
G02X120156Y1500989I0J-203D01*
G01Y1500368D01*
G03X120206Y1500236I200J0D01*
G02Y1497324I-1664J-1456D01*
G03X120156Y1497192I150J-132D01*
G01Y1495250D01*
G03X120206Y1495118I200J0D01*
G02Y1492206I-1664J-1456D01*
G03X120156Y1492074I150J-132D01*
G01Y1491451D01*
G02X119953Y1491248I-203J0D01*
G01X117133D01*
G02X116930Y1491451I0J203D01*
G01Y1492074D01*
G03X116880Y1492206I-200J0D01*
G02Y1495118I1664J1456D01*
G03X116930Y1495250I-150J132D01*
G01Y1497192D01*
G03X116880Y1497324I-200J0D01*
G02Y1500236I1664J1456D01*
G03X116930Y1500368I-150J132D01*
G01Y1500989D01*
G02X117133Y1501192I203J0D01*
G37*
G36*
G01X310706Y1491450D02*
G02X310504Y1491248I-202J0D01*
G01X307684D01*
G02X307482Y1491451I1J203D01*
G01Y1492072D01*
G03X307432Y1492204I-200J0D01*
G02Y1495120I1661J1458D01*
G03X307482Y1495252I-150J132D01*
G01Y1497190D01*
G03X307432Y1497322I-200J0D01*
G02Y1500238I1661J1458D01*
G03X307482Y1500370I-150J132D01*
G01Y1500990D01*
G02X307684Y1501192I202J0D01*
G01X310504D01*
G02X310706Y1500989I-1J-203D01*
G01Y1500370D01*
G03X310756Y1500238I200J0D01*
G02Y1497322I-1661J-1458D01*
G03X310706Y1497190I150J-132D01*
G01Y1495252D01*
G03X310756Y1495120I200J0D01*
G02Y1492204I-1661J-1458D01*
G03X310706Y1492072I150J-132D01*
G01Y1491450D01*
G37*
G36*
G01X325007Y1501192D02*
X327827D01*
G02X328030Y1500989I0J-203D01*
G01Y1500368D01*
G03X328080Y1500236I200J0D01*
G02Y1497324I-1664J-1456D01*
G03X328030Y1497192I150J-132D01*
G01Y1495250D01*
G03X328080Y1495118I200J0D01*
G02Y1492206I-1664J-1456D01*
G03X328030Y1492074I150J-132D01*
G01Y1491451D01*
G02X327827Y1491248I-203J0D01*
G01X325007D01*
G02X324804Y1491451I0J203D01*
G01Y1492074D01*
G03X324754Y1492206I-200J0D01*
G02Y1495118I1664J1456D01*
G03X324804Y1495250I-150J132D01*
G01Y1497192D01*
G03X324754Y1497324I-200J0D01*
G02Y1500236I1664J1456D01*
G03X324804Y1500368I-150J132D01*
G01Y1500989D01*
G02X325007Y1501192I203J0D01*
G37*
G36*
G01X345352Y1491450D02*
G02X345150Y1491248I-202J0D01*
G01X342330D01*
G02X342128Y1491451I1J203D01*
G01Y1492072D01*
G03X342078Y1492204I-200J0D01*
G02Y1495120I1661J1458D01*
G03X342128Y1495252I-150J132D01*
G01Y1497190D01*
G03X342078Y1497322I-200J0D01*
G02Y1500238I1661J1458D01*
G03X342128Y1500370I-150J132D01*
G01Y1500990D01*
G02X342330Y1501192I202J0D01*
G01X345150D01*
G02X345352Y1500989I-1J-203D01*
G01Y1500370D01*
G03X345402Y1500238I200J0D01*
G02Y1497322I-1661J-1458D01*
G03X345352Y1497190I150J-132D01*
G01Y1495252D01*
G03X345402Y1495120I200J0D01*
G02Y1492204I-1661J-1458D01*
G03X345352Y1492072I150J-132D01*
G01Y1491450D01*
G37*
G36*
G01X639840D02*
G02X639638Y1491248I-202J0D01*
G01X636818D01*
G02X636616Y1491451I1J203D01*
G01Y1492072D01*
G03X636566Y1492204I-200J0D01*
G02Y1495120I1661J1458D01*
G03X636616Y1495252I-150J132D01*
G01Y1497190D01*
G03X636566Y1497322I-200J0D01*
G02Y1500238I1661J1458D01*
G03X636616Y1500370I-150J132D01*
G01Y1500990D01*
G02X636818Y1501192I202J0D01*
G01X639638D01*
G02X639840Y1500989I-1J-203D01*
G01Y1500370D01*
G03X639890Y1500238I200J0D01*
G02Y1497322I-1661J-1458D01*
G03X639840Y1497190I150J-132D01*
G01Y1495252D01*
G03X639890Y1495120I200J0D01*
G02Y1492204I-1661J-1458D01*
G03X639840Y1492072I150J-132D01*
G01Y1491450D01*
G37*
G36*
G01X1139101Y1501192D02*
X1141921D01*
G02X1142124Y1500989I0J-203D01*
G01Y1500368D01*
G03X1142174Y1500236I200J0D01*
G02Y1497324I-1664J-1456D01*
G03X1142124Y1497192I150J-132D01*
G01Y1495250D01*
G03X1142174Y1495118I200J0D01*
G02Y1492206I-1664J-1456D01*
G03X1142124Y1492074I150J-132D01*
G01Y1491451D01*
G02X1141921Y1491248I-203J0D01*
G01X1139101D01*
G02X1138898Y1491451I0J203D01*
G01Y1492074D01*
G03X1138848Y1492206I-200J0D01*
G02Y1495118I1664J1456D01*
G03X1138898Y1495250I-150J132D01*
G01Y1497192D01*
G03X1138848Y1497324I-200J0D01*
G02Y1500236I1664J1456D01*
G03X1138898Y1500368I-150J132D01*
G01Y1500989D01*
G02X1139101Y1501192I203J0D01*
G37*
G36*
G01X1159446Y1491450D02*
G02X1159244Y1491248I-202J0D01*
G01X1156424D01*
G02X1156222Y1491451I1J203D01*
G01Y1492072D01*
G03X1156172Y1492204I-200J0D01*
G02Y1495120I1661J1458D01*
G03X1156222Y1495252I-150J132D01*
G01Y1497190D01*
G03X1156172Y1497322I-200J0D01*
G02Y1500238I1661J1458D01*
G03X1156222Y1500370I-150J132D01*
G01Y1500990D01*
G02X1156424Y1501192I202J0D01*
G01X1159244D01*
G02X1159446Y1500989I-1J-203D01*
G01Y1500370D01*
G03X1159496Y1500238I200J0D01*
G02Y1497322I-1661J-1458D01*
G03X1159446Y1497190I150J-132D01*
G01Y1495252D01*
G03X1159496Y1495120I200J0D01*
G02Y1492204I-1661J-1458D01*
G03X1159446Y1492072I150J-132D01*
G01Y1491450D01*
G37*
G36*
G01X1661808D02*
G02X1661606Y1491248I-202J0D01*
G01X1658786D01*
G02X1658584Y1491451I1J203D01*
G01Y1492072D01*
G03X1658534Y1492204I-200J0D01*
G02Y1495120I1661J1458D01*
G03X1658584Y1495252I-150J132D01*
G01Y1497190D01*
G03X1658534Y1497322I-200J0D01*
G02Y1500238I1661J1458D01*
G03X1658584Y1500370I-150J132D01*
G01Y1500990D01*
G02X1658786Y1501192I202J0D01*
G01X1661606D01*
G02X1661808Y1500989I-1J-203D01*
G01Y1500370D01*
G03X1661858Y1500238I200J0D01*
G02Y1497322I-1661J-1458D01*
G03X1661808Y1497190I150J-132D01*
G01Y1495252D01*
G03X1661858Y1495120I200J0D01*
G02Y1492204I-1661J-1458D01*
G03X1661808Y1492072I150J-132D01*
G01Y1491450D01*
G37*
G36*
G01X1676109Y1501192D02*
X1678929D01*
G02X1679132Y1500989I0J-203D01*
G01Y1500368D01*
G03X1679182Y1500236I200J0D01*
G02Y1497324I-1664J-1456D01*
G03X1679132Y1497192I150J-132D01*
G01Y1495250D01*
G03X1679182Y1495118I200J0D01*
G02Y1492206I-1664J-1456D01*
G03X1679132Y1492074I150J-132D01*
G01Y1491451D01*
G02X1678929Y1491248I-203J0D01*
G01X1676109D01*
G02X1675906Y1491451I0J203D01*
G01Y1492074D01*
G03X1675856Y1492206I-200J0D01*
G02Y1495118I1664J1456D01*
G03X1675906Y1495250I-150J132D01*
G01Y1497192D01*
G03X1675856Y1497324I-200J0D01*
G02Y1500236I1664J1456D01*
G03X1675906Y1500368I-150J132D01*
G01Y1500989D01*
G02X1676109Y1501192I203J0D01*
G37*
G36*
G01X108472Y1512216D02*
X111292D01*
G02X111494Y1512014I0J-202D01*
G01Y1511394D01*
G03X111544Y1511262I200J0D01*
G02Y1508346I-1661J-1458D01*
G03X111494Y1508214I150J-132D01*
G01Y1506275D01*
G03X111544Y1506143I200J0D01*
G02Y1503227I-1661J-1458D01*
G03X111494Y1503095I150J-132D01*
G01Y1502476D01*
G02X111292Y1502274I-202J0D01*
G01X108472D01*
G02X108270Y1502476I0J202D01*
G01Y1503095D01*
G03X108220Y1503227I-200J0D01*
G02Y1506143I1661J1458D01*
G03X108270Y1506275I-150J132D01*
G01Y1508214D01*
G03X108220Y1508346I-200J0D01*
G02Y1511262I1661J1458D01*
G03X108270Y1511394I-150J132D01*
G01Y1512014D01*
G02X108472Y1512216I202J0D01*
G37*
G36*
G01X316346D02*
X319166D01*
G02X319368Y1512014I0J-202D01*
G01Y1511394D01*
G03X319418Y1511262I200J0D01*
G02Y1508346I-1661J-1458D01*
G03X319368Y1508214I150J-132D01*
G01Y1506275D01*
G03X319418Y1506143I200J0D01*
G02Y1503227I-1661J-1458D01*
G03X319368Y1503095I150J-132D01*
G01Y1502476D01*
G02X319166Y1502274I-202J0D01*
G01X316346D01*
G02X316144Y1502476I0J202D01*
G01Y1503095D01*
G03X316094Y1503227I-200J0D01*
G02Y1506143I1661J1458D01*
G03X316144Y1506275I-150J132D01*
G01Y1508214D01*
G03X316094Y1508346I-200J0D01*
G02Y1511262I1661J1458D01*
G03X316144Y1511394I-150J132D01*
G01Y1512014D01*
G02X316346Y1512216I202J0D01*
G37*
G36*
G01X333668D02*
X336488D01*
G02X336690Y1512014I0J-202D01*
G01Y1511394D01*
G03X336740Y1511262I200J0D01*
G02Y1508346I-1661J-1458D01*
G03X336690Y1508214I150J-132D01*
G01Y1506275D01*
G03X336740Y1506143I200J0D01*
G02Y1503227I-1661J-1458D01*
G03X336690Y1503095I150J-132D01*
G01Y1502476D01*
G02X336488Y1502274I-202J0D01*
G01X333668D01*
G02X333466Y1502476I0J202D01*
G01Y1503095D01*
G03X333416Y1503227I-200J0D01*
G02Y1506143I1661J1458D01*
G03X333466Y1506275I-150J132D01*
G01Y1508214D01*
G03X333416Y1508346I-200J0D01*
G02Y1511262I1661J1458D01*
G03X333466Y1511394I-150J132D01*
G01Y1512014D01*
G02X333668Y1512216I202J0D01*
G37*
G36*
G01X1130440D02*
X1133260D01*
G02X1133462Y1512014I0J-202D01*
G01Y1511394D01*
G03X1133512Y1511262I200J0D01*
G02Y1508346I-1661J-1458D01*
G03X1133462Y1508214I150J-132D01*
G01Y1506275D01*
G03X1133512Y1506143I200J0D01*
G02Y1503227I-1661J-1458D01*
G03X1133462Y1503095I150J-132D01*
G01Y1502476D01*
G02X1133260Y1502274I-202J0D01*
G01X1130440D01*
G02X1130238Y1502476I0J202D01*
G01Y1503095D01*
G03X1130188Y1503227I-200J0D01*
G02Y1506143I1661J1458D01*
G03X1130238Y1506275I-150J132D01*
G01Y1508214D01*
G03X1130188Y1508346I-200J0D01*
G02Y1511262I1661J1458D01*
G03X1130238Y1511394I-150J132D01*
G01Y1512014D01*
G02X1130440Y1512216I202J0D01*
G37*
G36*
G01X1667448D02*
X1670268D01*
G02X1670470Y1512014I0J-202D01*
G01Y1511394D01*
G03X1670520Y1511262I200J0D01*
G02Y1508346I-1661J-1458D01*
G03X1670470Y1508214I150J-132D01*
G01Y1506275D01*
G03X1670520Y1506143I200J0D01*
G02Y1503227I-1661J-1458D01*
G03X1670470Y1503095I150J-132D01*
G01Y1502476D01*
G02X1670268Y1502274I-202J0D01*
G01X1667448D01*
G02X1667246Y1502476I0J202D01*
G01Y1503095D01*
G03X1667196Y1503227I-200J0D01*
G02Y1506143I1661J1458D01*
G03X1667246Y1506275I-150J132D01*
G01Y1508214D01*
G03X1667196Y1508346I-200J0D01*
G02Y1511262I1661J1458D01*
G03X1667246Y1511394I-150J132D01*
G01Y1512014D01*
G02X1667448Y1512216I202J0D01*
G37*
G36*
G01X628156Y1502274D02*
G02X627954Y1502476I0J202D01*
G01Y1503097D01*
G03X627904Y1503229I-200J0D01*
G02Y1506141I1664J1456D01*
G03X627954Y1506273I-150J132D01*
G01Y1508216D01*
G03X627904Y1508348I-200J0D01*
G02Y1511260I1664J1456D01*
G03X627954Y1511392I-150J132D01*
G01Y1512014D01*
G02X628157Y1512216I203J-1D01*
G01X630978D01*
G02X631180Y1512014I0J-202D01*
G01Y1511392D01*
G03X631230Y1511260I200J0D01*
G02Y1508348I-1664J-1456D01*
G03X631180Y1508216I150J-132D01*
G01Y1506273D01*
G03X631230Y1506141I200J0D01*
G02Y1503229I-1664J-1456D01*
G03X631180Y1503097I150J-132D01*
G01Y1502476D01*
G02X630977Y1502274I-203J1D01*
G01X628156D01*
G37*
G36*
G01X1147762D02*
G02X1147560Y1502476I0J202D01*
G01Y1503097D01*
G03X1147510Y1503229I-200J0D01*
G02Y1506141I1664J1456D01*
G03X1147560Y1506273I-150J132D01*
G01Y1508216D01*
G03X1147510Y1508348I-200J0D01*
G02Y1511260I1664J1456D01*
G03X1147560Y1511392I-150J132D01*
G01Y1512014D01*
G02X1147763Y1512216I203J-1D01*
G01X1150584D01*
G02X1150786Y1512014I0J-202D01*
G01Y1511392D01*
G03X1150836Y1511260I200J0D01*
G02Y1508348I-1664J-1456D01*
G03X1150786Y1508216I150J-132D01*
G01Y1506273D01*
G03X1150836Y1506141I200J0D01*
G02Y1503229I-1664J-1456D01*
G03X1150786Y1503097I150J-132D01*
G01Y1502476D01*
G02X1150583Y1502274I-203J1D01*
G01X1147762D01*
G37*
G36*
G01X1650124D02*
G02X1649922Y1502476I0J202D01*
G01Y1503097D01*
G03X1649872Y1503229I-200J0D01*
G02Y1506141I1664J1456D01*
G03X1649922Y1506273I-150J132D01*
G01Y1508216D01*
G03X1649872Y1508348I-200J0D01*
G02Y1511260I1664J1456D01*
G03X1649922Y1511392I-150J132D01*
G01Y1512014D01*
G02X1650125Y1512216I203J-1D01*
G01X1652946D01*
G02X1653148Y1512014I0J-202D01*
G01Y1511392D01*
G03X1653198Y1511260I200J0D01*
G02Y1508348I-1664J-1456D01*
G03X1653148Y1508216I150J-132D01*
G01Y1506273D01*
G03X1653198Y1506141I200J0D01*
G02Y1503229I-1664J-1456D01*
G03X1653148Y1503097I150J-132D01*
G01Y1502476D01*
G02X1652945Y1502274I-203J1D01*
G01X1650124D01*
G37*
G36*
G01X307684Y1516546D02*
X310504D01*
G02X310706Y1516344I0J-202D01*
G01Y1515724D01*
G03X310756Y1515592I200J0D01*
G02Y1512676I-1661J-1458D01*
G03X310706Y1512544I150J-132D01*
G01Y1510606D01*
G03X310756Y1510474I200J0D01*
G02Y1507558I-1661J-1458D01*
G03X310706Y1507426I150J-132D01*
G01Y1506806D01*
G02X310504Y1506604I-202J0D01*
G01X307684D01*
G02X307482Y1506806I0J202D01*
G01Y1507426D01*
G03X307432Y1507558I-200J0D01*
G02Y1510474I1661J1458D01*
G03X307482Y1510606I-150J132D01*
G01Y1512544D01*
G03X307432Y1512676I-200J0D01*
G02Y1515592I1661J1458D01*
G03X307482Y1515724I-150J132D01*
G01Y1516344D01*
G02X307684Y1516546I202J0D01*
G37*
G36*
G01X342330D02*
X345150D01*
G02X345352Y1516344I0J-202D01*
G01Y1515724D01*
G03X345402Y1515592I200J0D01*
G02Y1512676I-1661J-1458D01*
G03X345352Y1512544I150J-132D01*
G01Y1510606D01*
G03X345402Y1510474I200J0D01*
G02Y1507558I-1661J-1458D01*
G03X345352Y1507426I150J-132D01*
G01Y1506806D01*
G02X345150Y1506604I-202J0D01*
G01X342330D01*
G02X342128Y1506806I0J202D01*
G01Y1507426D01*
G03X342078Y1507558I-200J0D01*
G02Y1510474I1661J1458D01*
G03X342128Y1510606I-150J132D01*
G01Y1512544D01*
G03X342078Y1512676I-200J0D01*
G02Y1515592I1661J1458D01*
G03X342128Y1515724I-150J132D01*
G01Y1516344D01*
G02X342330Y1516546I202J0D01*
G37*
G36*
G01X636818D02*
X639638D01*
G02X639840Y1516344I0J-202D01*
G01Y1515724D01*
G03X639890Y1515592I200J0D01*
G02Y1512676I-1661J-1458D01*
G03X639840Y1512544I150J-132D01*
G01Y1510606D01*
G03X639890Y1510474I200J0D01*
G02Y1507558I-1661J-1458D01*
G03X639840Y1507426I150J-132D01*
G01Y1506806D01*
G02X639638Y1506604I-202J0D01*
G01X636818D01*
G02X636616Y1506806I0J202D01*
G01Y1507426D01*
G03X636566Y1507558I-200J0D01*
G02Y1510474I1661J1458D01*
G03X636616Y1510606I-150J132D01*
G01Y1512544D01*
G03X636566Y1512676I-200J0D01*
G02Y1515592I1661J1458D01*
G03X636616Y1515724I-150J132D01*
G01Y1516344D01*
G02X636818Y1516546I202J0D01*
G37*
G36*
G01X1156424D02*
X1159244D01*
G02X1159446Y1516344I0J-202D01*
G01Y1515724D01*
G03X1159496Y1515592I200J0D01*
G02Y1512676I-1661J-1458D01*
G03X1159446Y1512544I150J-132D01*
G01Y1510606D01*
G03X1159496Y1510474I200J0D01*
G02Y1507558I-1661J-1458D01*
G03X1159446Y1507426I150J-132D01*
G01Y1506806D01*
G02X1159244Y1506604I-202J0D01*
G01X1156424D01*
G02X1156222Y1506806I0J202D01*
G01Y1507426D01*
G03X1156172Y1507558I-200J0D01*
G02Y1510474I1661J1458D01*
G03X1156222Y1510606I-150J132D01*
G01Y1512544D01*
G03X1156172Y1512676I-200J0D01*
G02Y1515592I1661J1458D01*
G03X1156222Y1515724I-150J132D01*
G01Y1516344D01*
G02X1156424Y1516546I202J0D01*
G37*
G36*
G01X1658786D02*
X1661606D01*
G02X1661808Y1516344I0J-202D01*
G01Y1515724D01*
G03X1661858Y1515592I200J0D01*
G02Y1512676I-1661J-1458D01*
G03X1661808Y1512544I150J-132D01*
G01Y1510606D01*
G03X1661858Y1510474I200J0D01*
G02Y1507558I-1661J-1458D01*
G03X1661808Y1507426I150J-132D01*
G01Y1506806D01*
G02X1661606Y1506604I-202J0D01*
G01X1658786D01*
G02X1658584Y1506806I0J202D01*
G01Y1507426D01*
G03X1658534Y1507558I-200J0D01*
G02Y1510474I1661J1458D01*
G03X1658584Y1510606I-150J132D01*
G01Y1512544D01*
G03X1658534Y1512676I-200J0D01*
G02Y1515592I1661J1458D01*
G03X1658584Y1515724I-150J132D01*
G01Y1516344D01*
G02X1658786Y1516546I202J0D01*
G37*
G36*
G01X117132Y1506604D02*
G02X116930Y1506806I0J202D01*
G01Y1507428D01*
G03X116880Y1507560I-200J0D01*
G02Y1510472I1664J1456D01*
G03X116930Y1510604I-150J132D01*
G01Y1512546D01*
G03X116880Y1512678I-200J0D01*
G02Y1515590I1664J1456D01*
G03X116930Y1515722I-150J132D01*
G01Y1516344D01*
G02X117133Y1516546I203J-1D01*
G01X119954D01*
G02X120156Y1516344I0J-202D01*
G01Y1515722D01*
G03X120206Y1515590I200J0D01*
G02Y1512678I-1664J-1456D01*
G03X120156Y1512546I150J-132D01*
G01Y1510604D01*
G03X120206Y1510472I200J0D01*
G02Y1507560I-1664J-1456D01*
G03X120156Y1507428I150J-132D01*
G01Y1506806D01*
G02X119953Y1506604I-203J1D01*
G01X117132D01*
G37*
G36*
G01X325006D02*
G02X324804Y1506806I0J202D01*
G01Y1507428D01*
G03X324754Y1507560I-200J0D01*
G02Y1510472I1664J1456D01*
G03X324804Y1510604I-150J132D01*
G01Y1512546D01*
G03X324754Y1512678I-200J0D01*
G02Y1515590I1664J1456D01*
G03X324804Y1515722I-150J132D01*
G01Y1516344D01*
G02X325007Y1516546I203J-1D01*
G01X327828D01*
G02X328030Y1516344I0J-202D01*
G01Y1515722D01*
G03X328080Y1515590I200J0D01*
G02Y1512678I-1664J-1456D01*
G03X328030Y1512546I150J-132D01*
G01Y1510604D01*
G03X328080Y1510472I200J0D01*
G02Y1507560I-1664J-1456D01*
G03X328030Y1507428I150J-132D01*
G01Y1506806D01*
G02X327827Y1506604I-203J1D01*
G01X325006D01*
G37*
G36*
G01X1139100D02*
G02X1138898Y1506806I0J202D01*
G01Y1507428D01*
G03X1138848Y1507560I-200J0D01*
G02Y1510472I1664J1456D01*
G03X1138898Y1510604I-150J132D01*
G01Y1512546D01*
G03X1138848Y1512678I-200J0D01*
G02Y1515590I1664J1456D01*
G03X1138898Y1515722I-150J132D01*
G01Y1516344D01*
G02X1139101Y1516546I203J-1D01*
G01X1141922D01*
G02X1142124Y1516344I0J-202D01*
G01Y1515722D01*
G03X1142174Y1515590I200J0D01*
G02Y1512678I-1664J-1456D01*
G03X1142124Y1512546I150J-132D01*
G01Y1510604D01*
G03X1142174Y1510472I200J0D01*
G02Y1507560I-1664J-1456D01*
G03X1142124Y1507428I150J-132D01*
G01Y1506806D01*
G02X1141921Y1506604I-203J1D01*
G01X1139100D01*
G37*
G36*
G01X1676108D02*
G02X1675906Y1506806I0J202D01*
G01Y1507428D01*
G03X1675856Y1507560I-200J0D01*
G02Y1510472I1664J1456D01*
G03X1675906Y1510604I-150J132D01*
G01Y1512546D01*
G03X1675856Y1512678I-200J0D01*
G02Y1515590I1664J1456D01*
G03X1675906Y1515722I-150J132D01*
G01Y1516344D01*
G02X1676109Y1516546I203J-1D01*
G01X1678930D01*
G02X1679132Y1516344I0J-202D01*
G01Y1515722D01*
G03X1679182Y1515590I200J0D01*
G02Y1512678I-1664J-1456D01*
G03X1679132Y1512546I150J-132D01*
G01Y1510604D01*
G03X1679182Y1510472I200J0D01*
G02Y1507560I-1664J-1456D01*
G03X1679132Y1507428I150J-132D01*
G01Y1506806D01*
G02X1678929Y1506604I-203J1D01*
G01X1676108D01*
G37*
G36*
G01X454929Y1568516D02*
X457749D01*
G02X457952Y1568313I0J-203D01*
G01Y1567691D01*
G03X458002Y1567559I200J0D01*
G02Y1564647I-1664J-1456D01*
G03X457952Y1564515I150J-132D01*
G01Y1562573D01*
G03X458002Y1562441I200J0D01*
G02Y1559529I-1664J-1456D01*
G03X457952Y1559397I150J-132D01*
G01Y1558775D01*
G02X457749Y1558572I-203J0D01*
G01X454929D01*
G02X454726Y1558775I0J203D01*
G01Y1559397D01*
G03X454676Y1559529I-200J0D01*
G02Y1562441I1664J1456D01*
G03X454726Y1562573I-150J132D01*
G01Y1564515D01*
G03X454676Y1564647I-200J0D01*
G02Y1567559I1664J1456D01*
G03X454726Y1567691I-150J132D01*
G01Y1568313D01*
G02X454929Y1568516I203J0D01*
G37*
G36*
G01X475274Y1558774D02*
G02X475072Y1558572I-202J0D01*
G01X472252D01*
G02X472050Y1558775I1J203D01*
G01Y1559395D01*
G03X472000Y1559527I-200J0D01*
G02Y1562443I1661J1458D01*
G03X472050Y1562575I-150J132D01*
G01Y1564513D01*
G03X472000Y1564645I-200J0D01*
G02Y1567561I1661J1458D01*
G03X472050Y1567693I-150J132D01*
G01Y1568314D01*
G02X472252Y1568516I202J0D01*
G01X475072D01*
G02X475274Y1568313I-1J-203D01*
G01Y1567693D01*
G03X475324Y1567561I200J0D01*
G02Y1564645I-1661J-1458D01*
G03X475274Y1564513I150J-132D01*
G01Y1562575D01*
G03X475324Y1562443I200J0D01*
G02Y1559527I-1661J-1458D01*
G03X475274Y1559395I150J-132D01*
G01Y1558774D01*
G37*
G36*
G01X489575Y1568516D02*
X492395D01*
G02X492598Y1568313I0J-203D01*
G01Y1567691D01*
G03X492648Y1567559I200J0D01*
G02Y1564647I-1664J-1456D01*
G03X492598Y1564515I150J-132D01*
G01Y1562573D01*
G03X492648Y1562441I200J0D01*
G02Y1559529I-1664J-1456D01*
G03X492598Y1559397I150J-132D01*
G01Y1558775D01*
G02X492395Y1558572I-203J0D01*
G01X489575D01*
G02X489372Y1558775I0J203D01*
G01Y1559397D01*
G03X489322Y1559529I-200J0D01*
G02Y1562441I1664J1456D01*
G03X489372Y1562573I-150J132D01*
G01Y1564515D01*
G03X489322Y1564647I-200J0D01*
G02Y1567559I1664J1456D01*
G03X489372Y1567691I-150J132D01*
G01Y1568313D01*
G02X489575Y1568516I203J0D01*
G37*
G36*
G01X506897D02*
X509717D01*
G02X509920Y1568313I0J-203D01*
G01Y1567691D01*
G03X509970Y1567559I200J0D01*
G02Y1564647I-1664J-1456D01*
G03X509920Y1564515I150J-132D01*
G01Y1562573D01*
G03X509970Y1562441I200J0D01*
G02Y1559529I-1664J-1456D01*
G03X509920Y1559397I150J-132D01*
G01Y1558775D01*
G02X509717Y1558572I-203J0D01*
G01X506897D01*
G02X506694Y1558775I0J203D01*
G01Y1559397D01*
G03X506644Y1559529I-200J0D01*
G02Y1562441I1664J1456D01*
G03X506694Y1562573I-150J132D01*
G01Y1564515D01*
G03X506644Y1564647I-200J0D01*
G02Y1567559I1664J1456D01*
G03X506694Y1567691I-150J132D01*
G01Y1568313D01*
G02X506897Y1568516I203J0D01*
G37*
G36*
G01X1497242Y1558774D02*
G02X1497040Y1558572I-202J0D01*
G01X1494220D01*
G02X1494018Y1558775I1J203D01*
G01Y1559395D01*
G03X1493968Y1559527I-200J0D01*
G02Y1562443I1661J1458D01*
G03X1494018Y1562575I-150J132D01*
G01Y1564513D01*
G03X1493968Y1564645I-200J0D01*
G02Y1567561I1661J1458D01*
G03X1494018Y1567693I-150J132D01*
G01Y1568314D01*
G02X1494220Y1568516I202J0D01*
G01X1497040D01*
G02X1497242Y1568313I-1J-203D01*
G01Y1567693D01*
G03X1497292Y1567561I200J0D01*
G02Y1564645I-1661J-1458D01*
G03X1497242Y1564513I150J-132D01*
G01Y1562575D01*
G03X1497292Y1562443I200J0D01*
G02Y1559527I-1661J-1458D01*
G03X1497242Y1559395I150J-132D01*
G01Y1558774D01*
G37*
G36*
G01X1511543Y1568516D02*
X1514363D01*
G02X1514566Y1568313I0J-203D01*
G01Y1567691D01*
G03X1514616Y1567559I200J0D01*
G02Y1564647I-1664J-1456D01*
G03X1514566Y1564515I150J-132D01*
G01Y1562573D01*
G03X1514616Y1562441I200J0D01*
G02Y1559529I-1664J-1456D01*
G03X1514566Y1559397I150J-132D01*
G01Y1558775D01*
G02X1514363Y1558572I-203J0D01*
G01X1511543D01*
G02X1511340Y1558775I0J203D01*
G01Y1559397D01*
G03X1511290Y1559529I-200J0D01*
G02Y1562441I1664J1456D01*
G03X1511340Y1562573I-150J132D01*
G01Y1564515D01*
G03X1511290Y1564647I-200J0D01*
G02Y1567559I1664J1456D01*
G03X1511340Y1567691I-150J132D01*
G01Y1568313D01*
G02X1511543Y1568516I203J0D01*
G37*
G36*
G01X1528865D02*
X1531685D01*
G02X1531888Y1568313I0J-203D01*
G01Y1567691D01*
G03X1531938Y1567559I200J0D01*
G02Y1564647I-1664J-1456D01*
G03X1531888Y1564515I150J-132D01*
G01Y1562573D01*
G03X1531938Y1562441I200J0D01*
G02Y1559529I-1664J-1456D01*
G03X1531888Y1559397I150J-132D01*
G01Y1558775D01*
G02X1531685Y1558572I-203J0D01*
G01X1528865D01*
G02X1528662Y1558775I0J203D01*
G01Y1559397D01*
G03X1528612Y1559529I-200J0D01*
G02Y1562441I1664J1456D01*
G03X1528662Y1562573I-150J132D01*
G01Y1564515D01*
G03X1528612Y1564647I-200J0D01*
G02Y1567559I1664J1456D01*
G03X1528662Y1567691I-150J132D01*
G01Y1568313D01*
G02X1528865Y1568516I203J0D01*
G37*
G36*
G01X463590Y1572846D02*
X466410D01*
G02X466612Y1572644I0J-202D01*
G01Y1572024D01*
G03X466662Y1571892I200J0D01*
G02Y1568976I-1661J-1458D01*
G03X466612Y1568844I150J-132D01*
G01Y1566905D01*
G03X466662Y1566773I200J0D01*
G02Y1563857I-1661J-1458D01*
G03X466612Y1563725I150J-132D01*
G01Y1563106D01*
G02X466410Y1562904I-202J0D01*
G01X463590D01*
G02X463388Y1563106I0J202D01*
G01Y1563725D01*
G03X463338Y1563857I-200J0D01*
G02Y1566773I1661J1458D01*
G03X463388Y1566905I-150J132D01*
G01Y1568844D01*
G03X463338Y1568976I-200J0D01*
G02Y1571892I1661J1458D01*
G03X463388Y1572024I-150J132D01*
G01Y1572644D01*
G02X463590Y1572846I202J0D01*
G37*
G36*
G01X498236D02*
X501056D01*
G02X501258Y1572644I0J-202D01*
G01Y1572024D01*
G03X501308Y1571892I200J0D01*
G02Y1568976I-1661J-1458D01*
G03X501258Y1568844I150J-132D01*
G01Y1566905D01*
G03X501308Y1566773I200J0D01*
G02Y1563857I-1661J-1458D01*
G03X501258Y1563725I150J-132D01*
G01Y1563106D01*
G02X501056Y1562904I-202J0D01*
G01X498236D01*
G02X498034Y1563106I0J202D01*
G01Y1563725D01*
G03X497984Y1563857I-200J0D01*
G02Y1566773I1661J1458D01*
G03X498034Y1566905I-150J132D01*
G01Y1568844D01*
G03X497984Y1568976I-200J0D01*
G02Y1571892I1661J1458D01*
G03X498034Y1572024I-150J132D01*
G01Y1572644D01*
G02X498236Y1572846I202J0D01*
G37*
G36*
G01X1485558D02*
X1488378D01*
G02X1488580Y1572644I0J-202D01*
G01Y1572024D01*
G03X1488630Y1571892I200J0D01*
G02Y1568976I-1661J-1458D01*
G03X1488580Y1568844I150J-132D01*
G01Y1566905D01*
G03X1488630Y1566773I200J0D01*
G02Y1563857I-1661J-1458D01*
G03X1488580Y1563725I150J-132D01*
G01Y1563106D01*
G02X1488378Y1562904I-202J0D01*
G01X1485558D01*
G02X1485356Y1563106I0J202D01*
G01Y1563725D01*
G03X1485306Y1563857I-200J0D01*
G02Y1566773I1661J1458D01*
G03X1485356Y1566905I-150J132D01*
G01Y1568844D01*
G03X1485306Y1568976I-200J0D01*
G02Y1571892I1661J1458D01*
G03X1485356Y1572024I-150J132D01*
G01Y1572644D01*
G02X1485558Y1572846I202J0D01*
G37*
G36*
G01X1520204D02*
X1523024D01*
G02X1523226Y1572644I0J-202D01*
G01Y1572024D01*
G03X1523276Y1571892I200J0D01*
G02Y1568976I-1661J-1458D01*
G03X1523226Y1568844I150J-132D01*
G01Y1566905D01*
G03X1523276Y1566773I200J0D01*
G02Y1563857I-1661J-1458D01*
G03X1523226Y1563725I150J-132D01*
G01Y1563106D01*
G02X1523024Y1562904I-202J0D01*
G01X1520204D01*
G02X1520002Y1563106I0J202D01*
G01Y1563725D01*
G03X1519952Y1563857I-200J0D01*
G02Y1566773I1661J1458D01*
G03X1520002Y1566905I-150J132D01*
G01Y1568844D01*
G03X1519952Y1568976I-200J0D01*
G02Y1571892I1661J1458D01*
G03X1520002Y1572024I-150J132D01*
G01Y1572644D01*
G02X1520204Y1572846I202J0D01*
G37*
G36*
G01X480912Y1562904D02*
G02X480710Y1563106I0J202D01*
G01Y1563727D01*
G03X480660Y1563859I-200J0D01*
G02Y1566771I1664J1456D01*
G03X480710Y1566903I-150J132D01*
G01Y1568846D01*
G03X480660Y1568978I-200J0D01*
G02Y1571890I1664J1456D01*
G03X480710Y1572022I-150J132D01*
G01Y1572644D01*
G02X480913Y1572846I203J-1D01*
G01X483734D01*
G02X483936Y1572644I0J-202D01*
G01Y1572022D01*
G03X483986Y1571890I200J0D01*
G02Y1568978I-1664J-1456D01*
G03X483936Y1568846I150J-132D01*
G01Y1566903D01*
G03X483986Y1566771I200J0D01*
G02Y1563859I-1664J-1456D01*
G03X483936Y1563727I150J-132D01*
G01Y1563106D01*
G02X483733Y1562904I-203J1D01*
G01X480912D01*
G37*
G36*
G01X1502880D02*
G02X1502678Y1563106I0J202D01*
G01Y1563727D01*
G03X1502628Y1563859I-200J0D01*
G02Y1566771I1664J1456D01*
G03X1502678Y1566903I-150J132D01*
G01Y1568846D01*
G03X1502628Y1568978I-200J0D01*
G02Y1571890I1664J1456D01*
G03X1502678Y1572022I-150J132D01*
G01Y1572644D01*
G02X1502881Y1572846I203J-1D01*
G01X1505702D01*
G02X1505904Y1572644I0J-202D01*
G01Y1572022D01*
G03X1505954Y1571890I200J0D01*
G02Y1568978I-1664J-1456D01*
G03X1505904Y1568846I150J-132D01*
G01Y1566903D01*
G03X1505954Y1566771I200J0D01*
G02Y1563859I-1664J-1456D01*
G03X1505904Y1563727I150J-132D01*
G01Y1563106D01*
G02X1505701Y1562904I-203J1D01*
G01X1502880D01*
G37*
G36*
G01X1537526D02*
G02X1537324Y1563106I0J202D01*
G01Y1563727D01*
G03X1537274Y1563859I-200J0D01*
G02Y1566771I1664J1456D01*
G03X1537324Y1566903I-150J132D01*
G01Y1568846D01*
G03X1537274Y1568978I-200J0D01*
G02Y1571890I1664J1456D01*
G03X1537324Y1572022I-150J132D01*
G01Y1572644D01*
G02X1537527Y1572846I203J-1D01*
G01X1540348D01*
G02X1540550Y1572644I0J-202D01*
G01Y1572022D01*
G03X1540600Y1571890I200J0D01*
G02Y1568978I-1664J-1456D01*
G03X1540550Y1568846I150J-132D01*
G01Y1566903D01*
G03X1540600Y1566771I200J0D01*
G02Y1563859I-1664J-1456D01*
G03X1540550Y1563727I150J-132D01*
G01Y1563106D01*
G02X1540347Y1562904I-203J1D01*
G01X1537526D01*
G37*
G36*
G01X454929Y1583870D02*
X457749D01*
G02X457952Y1583667I0J-203D01*
G01Y1583045D01*
G03X458002Y1582913I200J0D01*
G02Y1580001I-1664J-1456D01*
G03X457952Y1579869I150J-132D01*
G01Y1577927D01*
G03X458002Y1577795I200J0D01*
G02Y1574883I-1664J-1456D01*
G03X457952Y1574751I150J-132D01*
G01Y1574129D01*
G02X457749Y1573926I-203J0D01*
G01X454929D01*
G02X454726Y1574129I0J203D01*
G01Y1574751D01*
G03X454676Y1574883I-200J0D01*
G02Y1577795I1664J1456D01*
G03X454726Y1577927I-150J132D01*
G01Y1579869D01*
G03X454676Y1580001I-200J0D01*
G02Y1582913I1664J1456D01*
G03X454726Y1583045I-150J132D01*
G01Y1583667D01*
G02X454929Y1583870I203J0D01*
G37*
G36*
G01X475274Y1574128D02*
G02X475072Y1573926I-202J0D01*
G01X472252D01*
G02X472050Y1574129I1J203D01*
G01Y1574749D01*
G03X472000Y1574881I-200J0D01*
G02Y1577797I1661J1458D01*
G03X472050Y1577929I-150J132D01*
G01Y1579867D01*
G03X472000Y1579999I-200J0D01*
G02Y1582915I1661J1458D01*
G03X472050Y1583047I-150J132D01*
G01Y1583668D01*
G02X472252Y1583870I202J0D01*
G01X475072D01*
G02X475274Y1583667I-1J-203D01*
G01Y1583047D01*
G03X475324Y1582915I200J0D01*
G02Y1579999I-1661J-1458D01*
G03X475274Y1579867I150J-132D01*
G01Y1577929D01*
G03X475324Y1577797I200J0D01*
G02Y1574881I-1661J-1458D01*
G03X475274Y1574749I150J-132D01*
G01Y1574128D01*
G37*
G36*
G01X489575Y1583870D02*
X492395D01*
G02X492598Y1583667I0J-203D01*
G01Y1583045D01*
G03X492648Y1582913I200J0D01*
G02Y1580001I-1664J-1456D01*
G03X492598Y1579869I150J-132D01*
G01Y1577927D01*
G03X492648Y1577795I200J0D01*
G02Y1574883I-1664J-1456D01*
G03X492598Y1574751I150J-132D01*
G01Y1574129D01*
G02X492395Y1573926I-203J0D01*
G01X489575D01*
G02X489372Y1574129I0J203D01*
G01Y1574751D01*
G03X489322Y1574883I-200J0D01*
G02Y1577795I1664J1456D01*
G03X489372Y1577927I-150J132D01*
G01Y1579869D01*
G03X489322Y1580001I-200J0D01*
G02Y1582913I1664J1456D01*
G03X489372Y1583045I-150J132D01*
G01Y1583667D01*
G02X489575Y1583870I203J0D01*
G37*
G36*
G01X506897D02*
X509717D01*
G02X509920Y1583667I0J-203D01*
G01Y1583045D01*
G03X509970Y1582913I200J0D01*
G02Y1580001I-1664J-1456D01*
G03X509920Y1579869I150J-132D01*
G01Y1577927D01*
G03X509970Y1577795I200J0D01*
G02Y1574883I-1664J-1456D01*
G03X509920Y1574751I150J-132D01*
G01Y1574129D01*
G02X509717Y1573926I-203J0D01*
G01X506897D01*
G02X506694Y1574129I0J203D01*
G01Y1574751D01*
G03X506644Y1574883I-200J0D01*
G02Y1577795I1664J1456D01*
G03X506694Y1577927I-150J132D01*
G01Y1579869D01*
G03X506644Y1580001I-200J0D01*
G02Y1582913I1664J1456D01*
G03X506694Y1583045I-150J132D01*
G01Y1583667D01*
G02X506897Y1583870I203J0D01*
G37*
G36*
G01X1497242Y1574128D02*
G02X1497040Y1573926I-202J0D01*
G01X1494220D01*
G02X1494018Y1574129I1J203D01*
G01Y1574749D01*
G03X1493968Y1574881I-200J0D01*
G02Y1577797I1661J1458D01*
G03X1494018Y1577929I-150J132D01*
G01Y1579867D01*
G03X1493968Y1579999I-200J0D01*
G02Y1582915I1661J1458D01*
G03X1494018Y1583047I-150J132D01*
G01Y1583668D01*
G02X1494220Y1583870I202J0D01*
G01X1497040D01*
G02X1497242Y1583667I-1J-203D01*
G01Y1583047D01*
G03X1497292Y1582915I200J0D01*
G02Y1579999I-1661J-1458D01*
G03X1497242Y1579867I150J-132D01*
G01Y1577929D01*
G03X1497292Y1577797I200J0D01*
G02Y1574881I-1661J-1458D01*
G03X1497242Y1574749I150J-132D01*
G01Y1574128D01*
G37*
G36*
G01X1511543Y1583870D02*
X1514363D01*
G02X1514566Y1583667I0J-203D01*
G01Y1583045D01*
G03X1514616Y1582913I200J0D01*
G02Y1580001I-1664J-1456D01*
G03X1514566Y1579869I150J-132D01*
G01Y1577927D01*
G03X1514616Y1577795I200J0D01*
G02Y1574883I-1664J-1456D01*
G03X1514566Y1574751I150J-132D01*
G01Y1574129D01*
G02X1514363Y1573926I-203J0D01*
G01X1511543D01*
G02X1511340Y1574129I0J203D01*
G01Y1574751D01*
G03X1511290Y1574883I-200J0D01*
G02Y1577795I1664J1456D01*
G03X1511340Y1577927I-150J132D01*
G01Y1579869D01*
G03X1511290Y1580001I-200J0D01*
G02Y1582913I1664J1456D01*
G03X1511340Y1583045I-150J132D01*
G01Y1583667D01*
G02X1511543Y1583870I203J0D01*
G37*
G36*
G01X1528865D02*
X1531685D01*
G02X1531888Y1583667I0J-203D01*
G01Y1583045D01*
G03X1531938Y1582913I200J0D01*
G02Y1580001I-1664J-1456D01*
G03X1531888Y1579869I150J-132D01*
G01Y1577927D01*
G03X1531938Y1577795I200J0D01*
G02Y1574883I-1664J-1456D01*
G03X1531888Y1574751I150J-132D01*
G01Y1574129D01*
G02X1531685Y1573926I-203J0D01*
G01X1528865D01*
G02X1528662Y1574129I0J203D01*
G01Y1574751D01*
G03X1528612Y1574883I-200J0D01*
G02Y1577795I1664J1456D01*
G03X1528662Y1577927I-150J132D01*
G01Y1579869D01*
G03X1528612Y1580001I-200J0D01*
G02Y1582913I1664J1456D01*
G03X1528662Y1583045I-150J132D01*
G01Y1583667D01*
G02X1528865Y1583870I203J0D01*
G37*
G36*
G01X463590Y1588200D02*
X466410D01*
G02X466612Y1587998I0J-202D01*
G01Y1587378D01*
G03X466662Y1587246I200J0D01*
G02Y1584330I-1661J-1458D01*
G03X466612Y1584198I150J-132D01*
G01Y1582260D01*
G03X466662Y1582128I200J0D01*
G02Y1579212I-1661J-1458D01*
G03X466612Y1579080I150J-132D01*
G01Y1578460D01*
G02X466410Y1578258I-202J0D01*
G01X463590D01*
G02X463388Y1578460I0J202D01*
G01Y1579080D01*
G03X463338Y1579212I-200J0D01*
G02Y1582128I1661J1458D01*
G03X463388Y1582260I-150J132D01*
G01Y1584198D01*
G03X463338Y1584330I-200J0D01*
G02Y1587246I1661J1458D01*
G03X463388Y1587378I-150J132D01*
G01Y1587998D01*
G02X463590Y1588200I202J0D01*
G37*
G36*
G01X498236D02*
X501056D01*
G02X501258Y1587998I0J-202D01*
G01Y1587378D01*
G03X501308Y1587246I200J0D01*
G02Y1584330I-1661J-1458D01*
G03X501258Y1584198I150J-132D01*
G01Y1582260D01*
G03X501308Y1582128I200J0D01*
G02Y1579212I-1661J-1458D01*
G03X501258Y1579080I150J-132D01*
G01Y1578460D01*
G02X501056Y1578258I-202J0D01*
G01X498236D01*
G02X498034Y1578460I0J202D01*
G01Y1579080D01*
G03X497984Y1579212I-200J0D01*
G02Y1582128I1661J1458D01*
G03X498034Y1582260I-150J132D01*
G01Y1584198D01*
G03X497984Y1584330I-200J0D01*
G02Y1587246I1661J1458D01*
G03X498034Y1587378I-150J132D01*
G01Y1587998D01*
G02X498236Y1588200I202J0D01*
G37*
G36*
G01X1485558D02*
X1488378D01*
G02X1488580Y1587998I0J-202D01*
G01Y1587378D01*
G03X1488630Y1587246I200J0D01*
G02Y1584330I-1661J-1458D01*
G03X1488580Y1584198I150J-132D01*
G01Y1582260D01*
G03X1488630Y1582128I200J0D01*
G02Y1579212I-1661J-1458D01*
G03X1488580Y1579080I150J-132D01*
G01Y1578460D01*
G02X1488378Y1578258I-202J0D01*
G01X1485558D01*
G02X1485356Y1578460I0J202D01*
G01Y1579080D01*
G03X1485306Y1579212I-200J0D01*
G02Y1582128I1661J1458D01*
G03X1485356Y1582260I-150J132D01*
G01Y1584198D01*
G03X1485306Y1584330I-200J0D01*
G02Y1587246I1661J1458D01*
G03X1485356Y1587378I-150J132D01*
G01Y1587998D01*
G02X1485558Y1588200I202J0D01*
G37*
G36*
G01X1520204D02*
X1523024D01*
G02X1523226Y1587998I0J-202D01*
G01Y1587378D01*
G03X1523276Y1587246I200J0D01*
G02Y1584330I-1661J-1458D01*
G03X1523226Y1584198I150J-132D01*
G01Y1582260D01*
G03X1523276Y1582128I200J0D01*
G02Y1579212I-1661J-1458D01*
G03X1523226Y1579080I150J-132D01*
G01Y1578460D01*
G02X1523024Y1578258I-202J0D01*
G01X1520204D01*
G02X1520002Y1578460I0J202D01*
G01Y1579080D01*
G03X1519952Y1579212I-200J0D01*
G02Y1582128I1661J1458D01*
G03X1520002Y1582260I-150J132D01*
G01Y1584198D01*
G03X1519952Y1584330I-200J0D01*
G02Y1587246I1661J1458D01*
G03X1520002Y1587378I-150J132D01*
G01Y1587998D01*
G02X1520204Y1588200I202J0D01*
G37*
G36*
G01X480912Y1578258D02*
G02X480710Y1578460I0J202D01*
G01Y1579082D01*
G03X480660Y1579214I-200J0D01*
G02Y1582126I1664J1456D01*
G03X480710Y1582258I-150J132D01*
G01Y1584200D01*
G03X480660Y1584332I-200J0D01*
G02Y1587244I1664J1456D01*
G03X480710Y1587376I-150J132D01*
G01Y1587998D01*
G02X480913Y1588200I203J-1D01*
G01X483734D01*
G02X483936Y1587998I0J-202D01*
G01Y1587376D01*
G03X483986Y1587244I200J0D01*
G02Y1584332I-1664J-1456D01*
G03X483936Y1584200I150J-132D01*
G01Y1582258D01*
G03X483986Y1582126I200J0D01*
G02Y1579214I-1664J-1456D01*
G03X483936Y1579082I150J-132D01*
G01Y1578460D01*
G02X483733Y1578258I-203J1D01*
G01X480912D01*
G37*
G36*
G01X1502880D02*
G02X1502678Y1578460I0J202D01*
G01Y1579082D01*
G03X1502628Y1579214I-200J0D01*
G02Y1582126I1664J1456D01*
G03X1502678Y1582258I-150J132D01*
G01Y1584200D01*
G03X1502628Y1584332I-200J0D01*
G02Y1587244I1664J1456D01*
G03X1502678Y1587376I-150J132D01*
G01Y1587998D01*
G02X1502881Y1588200I203J-1D01*
G01X1505702D01*
G02X1505904Y1587998I0J-202D01*
G01Y1587376D01*
G03X1505954Y1587244I200J0D01*
G02Y1584332I-1664J-1456D01*
G03X1505904Y1584200I150J-132D01*
G01Y1582258D01*
G03X1505954Y1582126I200J0D01*
G02Y1579214I-1664J-1456D01*
G03X1505904Y1579082I150J-132D01*
G01Y1578460D01*
G02X1505701Y1578258I-203J1D01*
G01X1502880D01*
G37*
G36*
G01X1537526D02*
G02X1537324Y1578460I0J202D01*
G01Y1579082D01*
G03X1537274Y1579214I-200J0D01*
G02Y1582126I1664J1456D01*
G03X1537324Y1582258I-150J132D01*
G01Y1584200D01*
G03X1537274Y1584332I-200J0D01*
G02Y1587244I1664J1456D01*
G03X1537324Y1587376I-150J132D01*
G01Y1587998D01*
G02X1537527Y1588200I203J-1D01*
G01X1540348D01*
G02X1540550Y1587998I0J-202D01*
G01Y1587376D01*
G03X1540600Y1587244I200J0D01*
G02Y1584332I-1664J-1456D01*
G03X1540550Y1584200I150J-132D01*
G01Y1582258D01*
G03X1540600Y1582126I200J0D01*
G02Y1579214I-1664J-1456D01*
G03X1540550Y1579082I150J-132D01*
G01Y1578460D01*
G02X1540347Y1578258I-203J1D01*
G01X1537526D01*
G37*
G36*
G01X454929Y1599224D02*
X457749D01*
G02X457952Y1599021I0J-203D01*
G01Y1598399D01*
G03X458002Y1598267I200J0D01*
G02Y1595355I-1664J-1456D01*
G03X457952Y1595223I150J-132D01*
G01Y1593281D01*
G03X458002Y1593149I200J0D01*
G02Y1590237I-1664J-1456D01*
G03X457952Y1590105I150J-132D01*
G01Y1589483D01*
G02X457749Y1589280I-203J0D01*
G01X454929D01*
G02X454726Y1589483I0J203D01*
G01Y1590105D01*
G03X454676Y1590237I-200J0D01*
G02Y1593149I1664J1456D01*
G03X454726Y1593281I-150J132D01*
G01Y1595223D01*
G03X454676Y1595355I-200J0D01*
G02Y1598267I1664J1456D01*
G03X454726Y1598399I-150J132D01*
G01Y1599021D01*
G02X454929Y1599224I203J0D01*
G37*
G36*
G01X475274Y1589482D02*
G02X475072Y1589280I-202J0D01*
G01X472252D01*
G02X472050Y1589483I1J203D01*
G01Y1590103D01*
G03X472000Y1590235I-200J0D01*
G02Y1593151I1661J1458D01*
G03X472050Y1593283I-150J132D01*
G01Y1595221D01*
G03X472000Y1595353I-200J0D01*
G02Y1598269I1661J1458D01*
G03X472050Y1598401I-150J132D01*
G01Y1599022D01*
G02X472252Y1599224I202J0D01*
G01X475072D01*
G02X475274Y1599021I-1J-203D01*
G01Y1598401D01*
G03X475324Y1598269I200J0D01*
G02Y1595353I-1661J-1458D01*
G03X475274Y1595221I150J-132D01*
G01Y1593283D01*
G03X475324Y1593151I200J0D01*
G02Y1590235I-1661J-1458D01*
G03X475274Y1590103I150J-132D01*
G01Y1589482D01*
G37*
G36*
G01X489575Y1599224D02*
X492395D01*
G02X492598Y1599021I0J-203D01*
G01Y1598399D01*
G03X492648Y1598267I200J0D01*
G02Y1595355I-1664J-1456D01*
G03X492598Y1595223I150J-132D01*
G01Y1593281D01*
G03X492648Y1593149I200J0D01*
G02Y1590237I-1664J-1456D01*
G03X492598Y1590105I150J-132D01*
G01Y1589483D01*
G02X492395Y1589280I-203J0D01*
G01X489575D01*
G02X489372Y1589483I0J203D01*
G01Y1590105D01*
G03X489322Y1590237I-200J0D01*
G02Y1593149I1664J1456D01*
G03X489372Y1593281I-150J132D01*
G01Y1595223D01*
G03X489322Y1595355I-200J0D01*
G02Y1598267I1664J1456D01*
G03X489372Y1598399I-150J132D01*
G01Y1599021D01*
G02X489575Y1599224I203J0D01*
G37*
G36*
G01X506897D02*
X509717D01*
G02X509920Y1599021I0J-203D01*
G01Y1598399D01*
G03X509970Y1598267I200J0D01*
G02Y1595355I-1664J-1456D01*
G03X509920Y1595223I150J-132D01*
G01Y1593281D01*
G03X509970Y1593149I200J0D01*
G02Y1590237I-1664J-1456D01*
G03X509920Y1590105I150J-132D01*
G01Y1589483D01*
G02X509717Y1589280I-203J0D01*
G01X506897D01*
G02X506694Y1589483I0J203D01*
G01Y1590105D01*
G03X506644Y1590237I-200J0D01*
G02Y1593149I1664J1456D01*
G03X506694Y1593281I-150J132D01*
G01Y1595223D01*
G03X506644Y1595355I-200J0D01*
G02Y1598267I1664J1456D01*
G03X506694Y1598399I-150J132D01*
G01Y1599021D01*
G02X506897Y1599224I203J0D01*
G37*
G36*
G01X1497242Y1589482D02*
G02X1497040Y1589280I-202J0D01*
G01X1494220D01*
G02X1494018Y1589483I1J203D01*
G01Y1590103D01*
G03X1493968Y1590235I-200J0D01*
G02Y1593151I1661J1458D01*
G03X1494018Y1593283I-150J132D01*
G01Y1595221D01*
G03X1493968Y1595353I-200J0D01*
G02Y1598269I1661J1458D01*
G03X1494018Y1598401I-150J132D01*
G01Y1599022D01*
G02X1494220Y1599224I202J0D01*
G01X1497040D01*
G02X1497242Y1599021I-1J-203D01*
G01Y1598401D01*
G03X1497292Y1598269I200J0D01*
G02Y1595353I-1661J-1458D01*
G03X1497242Y1595221I150J-132D01*
G01Y1593283D01*
G03X1497292Y1593151I200J0D01*
G02Y1590235I-1661J-1458D01*
G03X1497242Y1590103I150J-132D01*
G01Y1589482D01*
G37*
G36*
G01X1511543Y1599224D02*
X1514363D01*
G02X1514566Y1599021I0J-203D01*
G01Y1598399D01*
G03X1514616Y1598267I200J0D01*
G02Y1595355I-1664J-1456D01*
G03X1514566Y1595223I150J-132D01*
G01Y1593281D01*
G03X1514616Y1593149I200J0D01*
G02Y1590237I-1664J-1456D01*
G03X1514566Y1590105I150J-132D01*
G01Y1589483D01*
G02X1514363Y1589280I-203J0D01*
G01X1511543D01*
G02X1511340Y1589483I0J203D01*
G01Y1590105D01*
G03X1511290Y1590237I-200J0D01*
G02Y1593149I1664J1456D01*
G03X1511340Y1593281I-150J132D01*
G01Y1595223D01*
G03X1511290Y1595355I-200J0D01*
G02Y1598267I1664J1456D01*
G03X1511340Y1598399I-150J132D01*
G01Y1599021D01*
G02X1511543Y1599224I203J0D01*
G37*
G36*
G01X1528865D02*
X1531685D01*
G02X1531888Y1599021I0J-203D01*
G01Y1598399D01*
G03X1531938Y1598267I200J0D01*
G02Y1595355I-1664J-1456D01*
G03X1531888Y1595223I150J-132D01*
G01Y1593281D01*
G03X1531938Y1593149I200J0D01*
G02Y1590237I-1664J-1456D01*
G03X1531888Y1590105I150J-132D01*
G01Y1589483D01*
G02X1531685Y1589280I-203J0D01*
G01X1528865D01*
G02X1528662Y1589483I0J203D01*
G01Y1590105D01*
G03X1528612Y1590237I-200J0D01*
G02Y1593149I1664J1456D01*
G03X1528662Y1593281I-150J132D01*
G01Y1595223D01*
G03X1528612Y1595355I-200J0D01*
G02Y1598267I1664J1456D01*
G03X1528662Y1598399I-150J132D01*
G01Y1599021D01*
G02X1528865Y1599224I203J0D01*
G37*
G36*
G01X463590Y1603554D02*
X466410D01*
G02X466612Y1603352I0J-202D01*
G01Y1602732D01*
G03X466662Y1602600I200J0D01*
G02Y1599684I-1661J-1458D01*
G03X466612Y1599552I150J-132D01*
G01Y1597614D01*
G03X466662Y1597482I200J0D01*
G02Y1594566I-1661J-1458D01*
G03X466612Y1594434I150J-132D01*
G01Y1593814D01*
G02X466410Y1593612I-202J0D01*
G01X463590D01*
G02X463388Y1593814I0J202D01*
G01Y1594434D01*
G03X463338Y1594566I-200J0D01*
G02Y1597482I1661J1458D01*
G03X463388Y1597614I-150J132D01*
G01Y1599552D01*
G03X463338Y1599684I-200J0D01*
G02Y1602600I1661J1458D01*
G03X463388Y1602732I-150J132D01*
G01Y1603352D01*
G02X463590Y1603554I202J0D01*
G37*
G36*
G01X498236D02*
X501056D01*
G02X501258Y1603352I0J-202D01*
G01Y1602732D01*
G03X501308Y1602600I200J0D01*
G02Y1599684I-1661J-1458D01*
G03X501258Y1599552I150J-132D01*
G01Y1597614D01*
G03X501308Y1597482I200J0D01*
G02Y1594566I-1661J-1458D01*
G03X501258Y1594434I150J-132D01*
G01Y1593814D01*
G02X501056Y1593612I-202J0D01*
G01X498236D01*
G02X498034Y1593814I0J202D01*
G01Y1594434D01*
G03X497984Y1594566I-200J0D01*
G02Y1597482I1661J1458D01*
G03X498034Y1597614I-150J132D01*
G01Y1599552D01*
G03X497984Y1599684I-200J0D01*
G02Y1602600I1661J1458D01*
G03X498034Y1602732I-150J132D01*
G01Y1603352D01*
G02X498236Y1603554I202J0D01*
G37*
G36*
G01X1485558D02*
X1488378D01*
G02X1488580Y1603352I0J-202D01*
G01Y1602732D01*
G03X1488630Y1602600I200J0D01*
G02Y1599684I-1661J-1458D01*
G03X1488580Y1599552I150J-132D01*
G01Y1597614D01*
G03X1488630Y1597482I200J0D01*
G02Y1594566I-1661J-1458D01*
G03X1488580Y1594434I150J-132D01*
G01Y1593814D01*
G02X1488378Y1593612I-202J0D01*
G01X1485558D01*
G02X1485356Y1593814I0J202D01*
G01Y1594434D01*
G03X1485306Y1594566I-200J0D01*
G02Y1597482I1661J1458D01*
G03X1485356Y1597614I-150J132D01*
G01Y1599552D01*
G03X1485306Y1599684I-200J0D01*
G02Y1602600I1661J1458D01*
G03X1485356Y1602732I-150J132D01*
G01Y1603352D01*
G02X1485558Y1603554I202J0D01*
G37*
G36*
G01X1520204D02*
X1523024D01*
G02X1523226Y1603352I0J-202D01*
G01Y1602732D01*
G03X1523276Y1602600I200J0D01*
G02Y1599684I-1661J-1458D01*
G03X1523226Y1599552I150J-132D01*
G01Y1597614D01*
G03X1523276Y1597482I200J0D01*
G02Y1594566I-1661J-1458D01*
G03X1523226Y1594434I150J-132D01*
G01Y1593814D01*
G02X1523024Y1593612I-202J0D01*
G01X1520204D01*
G02X1520002Y1593814I0J202D01*
G01Y1594434D01*
G03X1519952Y1594566I-200J0D01*
G02Y1597482I1661J1458D01*
G03X1520002Y1597614I-150J132D01*
G01Y1599552D01*
G03X1519952Y1599684I-200J0D01*
G02Y1602600I1661J1458D01*
G03X1520002Y1602732I-150J132D01*
G01Y1603352D01*
G02X1520204Y1603554I202J0D01*
G37*
G36*
G01X480912Y1593612D02*
G02X480710Y1593814I0J202D01*
G01Y1594436D01*
G03X480660Y1594568I-200J0D01*
G02Y1597480I1664J1456D01*
G03X480710Y1597612I-150J132D01*
G01Y1599554D01*
G03X480660Y1599686I-200J0D01*
G02Y1602598I1664J1456D01*
G03X480710Y1602730I-150J132D01*
G01Y1603352D01*
G02X480913Y1603554I203J-1D01*
G01X483734D01*
G02X483936Y1603352I0J-202D01*
G01Y1602730D01*
G03X483986Y1602598I200J0D01*
G02Y1599686I-1664J-1456D01*
G03X483936Y1599554I150J-132D01*
G01Y1597612D01*
G03X483986Y1597480I200J0D01*
G02Y1594568I-1664J-1456D01*
G03X483936Y1594436I150J-132D01*
G01Y1593814D01*
G02X483733Y1593612I-203J1D01*
G01X480912D01*
G37*
G36*
G01X1502880D02*
G02X1502678Y1593814I0J202D01*
G01Y1594436D01*
G03X1502628Y1594568I-200J0D01*
G02Y1597480I1664J1456D01*
G03X1502678Y1597612I-150J132D01*
G01Y1599554D01*
G03X1502628Y1599686I-200J0D01*
G02Y1602598I1664J1456D01*
G03X1502678Y1602730I-150J132D01*
G01Y1603352D01*
G02X1502881Y1603554I203J-1D01*
G01X1505702D01*
G02X1505904Y1603352I0J-202D01*
G01Y1602730D01*
G03X1505954Y1602598I200J0D01*
G02Y1599686I-1664J-1456D01*
G03X1505904Y1599554I150J-132D01*
G01Y1597612D01*
G03X1505954Y1597480I200J0D01*
G02Y1594568I-1664J-1456D01*
G03X1505904Y1594436I150J-132D01*
G01Y1593814D01*
G02X1505701Y1593612I-203J1D01*
G01X1502880D01*
G37*
G36*
G01X1537526D02*
G02X1537324Y1593814I0J202D01*
G01Y1594436D01*
G03X1537274Y1594568I-200J0D01*
G02Y1597480I1664J1456D01*
G03X1537324Y1597612I-150J132D01*
G01Y1599554D01*
G03X1537274Y1599686I-200J0D01*
G02Y1602598I1664J1456D01*
G03X1537324Y1602730I-150J132D01*
G01Y1603352D01*
G02X1537527Y1603554I203J-1D01*
G01X1540348D01*
G02X1540550Y1603352I0J-202D01*
G01Y1602730D01*
G03X1540600Y1602598I200J0D01*
G02Y1599686I-1664J-1456D01*
G03X1540550Y1599554I150J-132D01*
G01Y1597612D01*
G03X1540600Y1597480I200J0D01*
G02Y1594568I-1664J-1456D01*
G03X1540550Y1594436I150J-132D01*
G01Y1593814D01*
G02X1540347Y1593612I-203J1D01*
G01X1537526D01*
G37*
G36*
G01X472252Y1614578D02*
X475072D01*
G02X475274Y1614376I0J-202D01*
G01Y1613756D01*
G03X475324Y1613624I200J0D01*
G02Y1610708I-1661J-1458D01*
G03X475274Y1610576I150J-132D01*
G01Y1608638D01*
G03X475324Y1608506I200J0D01*
G02Y1605590I-1661J-1458D01*
G03X475274Y1605458I150J-132D01*
G01Y1604838D01*
G02X475072Y1604636I-202J0D01*
G01X472252D01*
G02X472050Y1604838I0J202D01*
G01Y1605458D01*
G03X472000Y1605590I-200J0D01*
G02Y1608506I1661J1458D01*
G03X472050Y1608638I-150J132D01*
G01Y1610576D01*
G03X472000Y1610708I-200J0D01*
G02Y1613624I1661J1458D01*
G03X472050Y1613756I-150J132D01*
G01Y1614376D01*
G02X472252Y1614578I202J0D01*
G37*
G36*
G01X1494220D02*
X1497040D01*
G02X1497242Y1614376I0J-202D01*
G01Y1613756D01*
G03X1497292Y1613624I200J0D01*
G02Y1610708I-1661J-1458D01*
G03X1497242Y1610576I150J-132D01*
G01Y1608638D01*
G03X1497292Y1608506I200J0D01*
G02Y1605590I-1661J-1458D01*
G03X1497242Y1605458I150J-132D01*
G01Y1604838D01*
G02X1497040Y1604636I-202J0D01*
G01X1494220D01*
G02X1494018Y1604838I0J202D01*
G01Y1605458D01*
G03X1493968Y1605590I-200J0D01*
G02Y1608506I1661J1458D01*
G03X1494018Y1608638I-150J132D01*
G01Y1610576D01*
G03X1493968Y1610708I-200J0D01*
G02Y1613624I1661J1458D01*
G03X1494018Y1613756I-150J132D01*
G01Y1614376D01*
G02X1494220Y1614578I202J0D01*
G37*
G36*
G01X454928Y1604636D02*
G02X454726Y1604838I0J202D01*
G01Y1605460D01*
G03X454676Y1605592I-200J0D01*
G02Y1608504I1664J1456D01*
G03X454726Y1608636I-150J132D01*
G01Y1610578D01*
G03X454676Y1610710I-200J0D01*
G02Y1613622I1664J1456D01*
G03X454726Y1613754I-150J132D01*
G01Y1614376D01*
G02X454929Y1614578I203J-1D01*
G01X457750D01*
G02X457952Y1614376I0J-202D01*
G01Y1613754D01*
G03X458002Y1613622I200J0D01*
G02Y1610710I-1664J-1456D01*
G03X457952Y1610578I150J-132D01*
G01Y1608636D01*
G03X458002Y1608504I200J0D01*
G02Y1605592I-1664J-1456D01*
G03X457952Y1605460I150J-132D01*
G01Y1604838D01*
G02X457749Y1604636I-203J1D01*
G01X454928D01*
G37*
G36*
G01X489574D02*
G02X489372Y1604838I0J202D01*
G01Y1605460D01*
G03X489322Y1605592I-200J0D01*
G02Y1608504I1664J1456D01*
G03X489372Y1608636I-150J132D01*
G01Y1610578D01*
G03X489322Y1610710I-200J0D01*
G02Y1613622I1664J1456D01*
G03X489372Y1613754I-150J132D01*
G01Y1614376D01*
G02X489575Y1614578I203J-1D01*
G01X492396D01*
G02X492598Y1614376I0J-202D01*
G01Y1613754D01*
G03X492648Y1613622I200J0D01*
G02Y1610710I-1664J-1456D01*
G03X492598Y1610578I150J-132D01*
G01Y1608636D01*
G03X492648Y1608504I200J0D01*
G02Y1605592I-1664J-1456D01*
G03X492598Y1605460I150J-132D01*
G01Y1604838D01*
G02X492395Y1604636I-203J1D01*
G01X489574D01*
G37*
G36*
G01X506896D02*
G02X506694Y1604838I0J202D01*
G01Y1605460D01*
G03X506644Y1605592I-200J0D01*
G02Y1608504I1664J1456D01*
G03X506694Y1608636I-150J132D01*
G01Y1610578D01*
G03X506644Y1610710I-200J0D01*
G02Y1613622I1664J1456D01*
G03X506694Y1613754I-150J132D01*
G01Y1614376D01*
G02X506897Y1614578I203J-1D01*
G01X509718D01*
G02X509920Y1614376I0J-202D01*
G01Y1613754D01*
G03X509970Y1613622I200J0D01*
G02Y1610710I-1664J-1456D01*
G03X509920Y1610578I150J-132D01*
G01Y1608636D01*
G03X509970Y1608504I200J0D01*
G02Y1605592I-1664J-1456D01*
G03X509920Y1605460I150J-132D01*
G01Y1604838D01*
G02X509717Y1604636I-203J1D01*
G01X506896D01*
G37*
G36*
G01X1511542D02*
G02X1511340Y1604838I0J202D01*
G01Y1605460D01*
G03X1511290Y1605592I-200J0D01*
G02Y1608504I1664J1456D01*
G03X1511340Y1608636I-150J132D01*
G01Y1610578D01*
G03X1511290Y1610710I-200J0D01*
G02Y1613622I1664J1456D01*
G03X1511340Y1613754I-150J132D01*
G01Y1614376D01*
G02X1511543Y1614578I203J-1D01*
G01X1514364D01*
G02X1514566Y1614376I0J-202D01*
G01Y1613754D01*
G03X1514616Y1613622I200J0D01*
G02Y1610710I-1664J-1456D01*
G03X1514566Y1610578I150J-132D01*
G01Y1608636D01*
G03X1514616Y1608504I200J0D01*
G02Y1605592I-1664J-1456D01*
G03X1514566Y1605460I150J-132D01*
G01Y1604838D01*
G02X1514363Y1604636I-203J1D01*
G01X1511542D01*
G37*
G36*
G01X1528864D02*
G02X1528662Y1604838I0J202D01*
G01Y1605460D01*
G03X1528612Y1605592I-200J0D01*
G02Y1608504I1664J1456D01*
G03X1528662Y1608636I-150J132D01*
G01Y1610578D01*
G03X1528612Y1610710I-200J0D01*
G02Y1613622I1664J1456D01*
G03X1528662Y1613754I-150J132D01*
G01Y1614376D01*
G02X1528865Y1614578I203J-1D01*
G01X1531686D01*
G02X1531888Y1614376I0J-202D01*
G01Y1613754D01*
G03X1531938Y1613622I200J0D01*
G02Y1610710I-1664J-1456D01*
G03X1531888Y1610578I150J-132D01*
G01Y1608636D01*
G03X1531938Y1608504I200J0D01*
G02Y1605592I-1664J-1456D01*
G03X1531888Y1605460I150J-132D01*
G01Y1604838D01*
G02X1531685Y1604636I-203J1D01*
G01X1528864D01*
G37*
G36*
G01X463590Y1618908D02*
X466410D01*
G02X466612Y1618706I0J-202D01*
G01Y1618086D01*
G03X466662Y1617954I200J0D01*
G02Y1615038I-1661J-1458D01*
G03X466612Y1614906I150J-132D01*
G01Y1612968D01*
G03X466662Y1612836I200J0D01*
G02Y1609920I-1661J-1458D01*
G03X466612Y1609788I150J-132D01*
G01Y1609168D01*
G02X466410Y1608966I-202J0D01*
G01X463590D01*
G02X463388Y1609168I0J202D01*
G01Y1609788D01*
G03X463338Y1609920I-200J0D01*
G02Y1612836I1661J1458D01*
G03X463388Y1612968I-150J132D01*
G01Y1614906D01*
G03X463338Y1615038I-200J0D01*
G02Y1617954I1661J1458D01*
G03X463388Y1618086I-150J132D01*
G01Y1618706D01*
G02X463590Y1618908I202J0D01*
G37*
G36*
G01X498236D02*
X501056D01*
G02X501258Y1618706I0J-202D01*
G01Y1618086D01*
G03X501308Y1617954I200J0D01*
G02Y1615038I-1661J-1458D01*
G03X501258Y1614906I150J-132D01*
G01Y1612968D01*
G03X501308Y1612836I200J0D01*
G02Y1609920I-1661J-1458D01*
G03X501258Y1609788I150J-132D01*
G01Y1609168D01*
G02X501056Y1608966I-202J0D01*
G01X498236D01*
G02X498034Y1609168I0J202D01*
G01Y1609788D01*
G03X497984Y1609920I-200J0D01*
G02Y1612836I1661J1458D01*
G03X498034Y1612968I-150J132D01*
G01Y1614906D01*
G03X497984Y1615038I-200J0D01*
G02Y1617954I1661J1458D01*
G03X498034Y1618086I-150J132D01*
G01Y1618706D01*
G02X498236Y1618908I202J0D01*
G37*
G36*
G01X1485558D02*
X1488378D01*
G02X1488580Y1618706I0J-202D01*
G01Y1618086D01*
G03X1488630Y1617954I200J0D01*
G02Y1615038I-1661J-1458D01*
G03X1488580Y1614906I150J-132D01*
G01Y1612968D01*
G03X1488630Y1612836I200J0D01*
G02Y1609920I-1661J-1458D01*
G03X1488580Y1609788I150J-132D01*
G01Y1609168D01*
G02X1488378Y1608966I-202J0D01*
G01X1485558D01*
G02X1485356Y1609168I0J202D01*
G01Y1609788D01*
G03X1485306Y1609920I-200J0D01*
G02Y1612836I1661J1458D01*
G03X1485356Y1612968I-150J132D01*
G01Y1614906D01*
G03X1485306Y1615038I-200J0D01*
G02Y1617954I1661J1458D01*
G03X1485356Y1618086I-150J132D01*
G01Y1618706D01*
G02X1485558Y1618908I202J0D01*
G37*
G36*
G01X1520204D02*
X1523024D01*
G02X1523226Y1618706I0J-202D01*
G01Y1618086D01*
G03X1523276Y1617954I200J0D01*
G02Y1615038I-1661J-1458D01*
G03X1523226Y1614906I150J-132D01*
G01Y1612968D01*
G03X1523276Y1612836I200J0D01*
G02Y1609920I-1661J-1458D01*
G03X1523226Y1609788I150J-132D01*
G01Y1609168D01*
G02X1523024Y1608966I-202J0D01*
G01X1520204D01*
G02X1520002Y1609168I0J202D01*
G01Y1609788D01*
G03X1519952Y1609920I-200J0D01*
G02Y1612836I1661J1458D01*
G03X1520002Y1612968I-150J132D01*
G01Y1614906D01*
G03X1519952Y1615038I-200J0D01*
G02Y1617954I1661J1458D01*
G03X1520002Y1618086I-150J132D01*
G01Y1618706D01*
G02X1520204Y1618908I202J0D01*
G37*
G36*
G01X480912Y1608966D02*
G02X480710Y1609168I0J202D01*
G01Y1609790D01*
G03X480660Y1609922I-200J0D01*
G02Y1612834I1664J1456D01*
G03X480710Y1612966I-150J132D01*
G01Y1614908D01*
G03X480660Y1615040I-200J0D01*
G02Y1617952I1664J1456D01*
G03X480710Y1618084I-150J132D01*
G01Y1618706D01*
G02X480913Y1618908I203J-1D01*
G01X483734D01*
G02X483936Y1618706I0J-202D01*
G01Y1618084D01*
G03X483986Y1617952I200J0D01*
G02Y1615040I-1664J-1456D01*
G03X483936Y1614908I150J-132D01*
G01Y1612966D01*
G03X483986Y1612834I200J0D01*
G02Y1609922I-1664J-1456D01*
G03X483936Y1609790I150J-132D01*
G01Y1609168D01*
G02X483733Y1608966I-203J1D01*
G01X480912D01*
G37*
G36*
G01X1502880D02*
G02X1502678Y1609168I0J202D01*
G01Y1609790D01*
G03X1502628Y1609922I-200J0D01*
G02Y1612834I1664J1456D01*
G03X1502678Y1612966I-150J132D01*
G01Y1614908D01*
G03X1502628Y1615040I-200J0D01*
G02Y1617952I1664J1456D01*
G03X1502678Y1618084I-150J132D01*
G01Y1618706D01*
G02X1502881Y1618908I203J-1D01*
G01X1505702D01*
G02X1505904Y1618706I0J-202D01*
G01Y1618084D01*
G03X1505954Y1617952I200J0D01*
G02Y1615040I-1664J-1456D01*
G03X1505904Y1614908I150J-132D01*
G01Y1612966D01*
G03X1505954Y1612834I200J0D01*
G02Y1609922I-1664J-1456D01*
G03X1505904Y1609790I150J-132D01*
G01Y1609168D01*
G02X1505701Y1608966I-203J1D01*
G01X1502880D01*
G37*
G36*
G01X1537526D02*
G02X1537324Y1609168I0J202D01*
G01Y1609790D01*
G03X1537274Y1609922I-200J0D01*
G02Y1612834I1664J1456D01*
G03X1537324Y1612966I-150J132D01*
G01Y1614908D01*
G03X1537274Y1615040I-200J0D01*
G02Y1617952I1664J1456D01*
G03X1537324Y1618084I-150J132D01*
G01Y1618706D01*
G02X1537527Y1618908I203J-1D01*
G01X1540348D01*
G02X1540550Y1618706I0J-202D01*
G01Y1618084D01*
G03X1540600Y1617952I200J0D01*
G02Y1615040I-1664J-1456D01*
G03X1540550Y1614908I150J-132D01*
G01Y1612966D01*
G03X1540600Y1612834I200J0D01*
G02Y1609922I-1664J-1456D01*
G03X1540550Y1609790I150J-132D01*
G01Y1609168D01*
G02X1540347Y1608966I-203J1D01*
G01X1537526D01*
G37*
G36*
G01X125795Y1466154D02*
X128615D01*
G02X128818Y1465951I0J-203D01*
G01Y1465329D01*
G03X128868Y1465197I200J0D01*
G02Y1462285I-1664J-1456D01*
G03X128818Y1462153I150J-132D01*
G01Y1460210D01*
G03X128868Y1460078I200J0D01*
G02Y1457166I-1664J-1456D01*
G03X128818Y1457034I150J-132D01*
G01Y1456413D01*
G02X128615Y1456210I-203J0D01*
G01X125795D01*
G02X125592Y1456413I0J203D01*
G01Y1457034D01*
G03X125542Y1457166I-200J0D01*
G02Y1460078I1664J1456D01*
G03X125592Y1460210I-150J132D01*
G01Y1462153D01*
G03X125542Y1462285I-200J0D01*
G02Y1465197I1664J1456D01*
G03X125592Y1465329I-150J132D01*
G01Y1465951D01*
G02X125795Y1466154I203J0D01*
G37*
G36*
G01X143118D02*
X145938D01*
G02X146140Y1465951I-1J-203D01*
G01Y1465331D01*
G03X146190Y1465199I200J0D01*
G02Y1462283I-1661J-1458D01*
G03X146140Y1462151I150J-132D01*
G01Y1460212D01*
G03X146190Y1460080I200J0D01*
G02Y1457164I-1661J-1458D01*
G03X146140Y1457032I150J-132D01*
G01Y1456413D01*
G02X145938Y1456210I-202J-1D01*
G01X143118D01*
G02X142916Y1456413I1J203D01*
G01Y1457032D01*
G03X142866Y1457164I-200J0D01*
G02Y1460080I1661J1458D01*
G03X142916Y1460212I-150J132D01*
G01Y1462151D01*
G03X142866Y1462283I-200J0D01*
G02Y1465199I1661J1458D01*
G03X142916Y1465331I-150J132D01*
G01Y1465951D01*
G02X143118Y1466154I202J1D01*
G37*
G36*
G01X160440D02*
X163260D01*
G02X163462Y1465951I-1J-203D01*
G01Y1465331D01*
G03X163512Y1465199I200J0D01*
G02Y1462283I-1661J-1458D01*
G03X163462Y1462151I150J-132D01*
G01Y1460212D01*
G03X163512Y1460080I200J0D01*
G02Y1457164I-1661J-1458D01*
G03X163462Y1457032I150J-132D01*
G01Y1456413D01*
G02X163260Y1456210I-202J-1D01*
G01X160440D01*
G02X160238Y1456413I1J203D01*
G01Y1457032D01*
G03X160188Y1457164I-200J0D01*
G02Y1460080I1661J1458D01*
G03X160238Y1460212I-150J132D01*
G01Y1462151D01*
G03X160188Y1462283I-200J0D01*
G02Y1465199I1661J1458D01*
G03X160238Y1465331I-150J132D01*
G01Y1465951D01*
G02X160440Y1466154I202J1D01*
G37*
G36*
G01X177763D02*
X180583D01*
G02X180786Y1465951I0J-203D01*
G01Y1465329D01*
G03X180836Y1465197I200J0D01*
G02Y1462285I-1664J-1456D01*
G03X180786Y1462153I150J-132D01*
G01Y1460210D01*
G03X180836Y1460078I200J0D01*
G02Y1457166I-1664J-1456D01*
G03X180786Y1457034I150J-132D01*
G01Y1456413D01*
G02X180583Y1456210I-203J0D01*
G01X177763D01*
G02X177560Y1456413I0J203D01*
G01Y1457034D01*
G03X177510Y1457166I-200J0D01*
G02Y1460078I1664J1456D01*
G03X177560Y1460210I-150J132D01*
G01Y1462153D01*
G03X177510Y1462285I-200J0D01*
G02Y1465197I1664J1456D01*
G03X177560Y1465329I-150J132D01*
G01Y1465951D01*
G02X177763Y1466154I203J0D01*
G37*
G36*
G01X281700D02*
X284520D01*
G02X284722Y1465951I-1J-203D01*
G01Y1465331D01*
G03X284772Y1465199I200J0D01*
G02Y1462283I-1661J-1458D01*
G03X284722Y1462151I150J-132D01*
G01Y1460212D01*
G03X284772Y1460080I200J0D01*
G02Y1457164I-1661J-1458D01*
G03X284722Y1457032I150J-132D01*
G01Y1456413D01*
G02X284520Y1456210I-202J-1D01*
G01X281700D01*
G02X281498Y1456413I1J203D01*
G01Y1457032D01*
G03X281448Y1457164I-200J0D01*
G02Y1460080I1661J1458D01*
G03X281498Y1460212I-150J132D01*
G01Y1462151D01*
G03X281448Y1462283I-200J0D01*
G02Y1465199I1661J1458D01*
G03X281498Y1465331I-150J132D01*
G01Y1465951D01*
G02X281700Y1466154I202J1D01*
G37*
G36*
G01X299023D02*
X301843D01*
G02X302046Y1465951I0J-203D01*
G01Y1465329D01*
G03X302096Y1465197I200J0D01*
G02Y1462285I-1664J-1456D01*
G03X302046Y1462153I150J-132D01*
G01Y1460210D01*
G03X302096Y1460078I200J0D01*
G02Y1457166I-1664J-1456D01*
G03X302046Y1457034I150J-132D01*
G01Y1456413D01*
G02X301843Y1456210I-203J0D01*
G01X299023D01*
G02X298820Y1456413I0J203D01*
G01Y1457034D01*
G03X298770Y1457166I-200J0D01*
G02Y1460078I1664J1456D01*
G03X298820Y1460210I-150J132D01*
G01Y1462153D01*
G03X298770Y1462285I-200J0D01*
G02Y1465197I1664J1456D01*
G03X298820Y1465329I-150J132D01*
G01Y1465951D01*
G02X299023Y1466154I203J0D01*
G37*
G36*
G01X454929D02*
X457749D01*
G02X457952Y1465951I0J-203D01*
G01Y1465329D01*
G03X458002Y1465197I200J0D01*
G02Y1462285I-1664J-1456D01*
G03X457952Y1462153I150J-132D01*
G01Y1460210D01*
G03X458002Y1460078I200J0D01*
G02Y1457166I-1664J-1456D01*
G03X457952Y1457034I150J-132D01*
G01Y1456413D01*
G02X457749Y1456210I-203J0D01*
G01X454929D01*
G02X454726Y1456413I0J203D01*
G01Y1457034D01*
G03X454676Y1457166I-200J0D01*
G02Y1460078I1664J1456D01*
G03X454726Y1460210I-150J132D01*
G01Y1462153D01*
G03X454676Y1462285I-200J0D01*
G02Y1465197I1664J1456D01*
G03X454726Y1465329I-150J132D01*
G01Y1465951D01*
G02X454929Y1466154I203J0D01*
G37*
G36*
G01X472252D02*
X475072D01*
G02X475274Y1465951I-1J-203D01*
G01Y1465331D01*
G03X475324Y1465199I200J0D01*
G02Y1462283I-1661J-1458D01*
G03X475274Y1462151I150J-132D01*
G01Y1460212D01*
G03X475324Y1460080I200J0D01*
G02Y1457164I-1661J-1458D01*
G03X475274Y1457032I150J-132D01*
G01Y1456413D01*
G02X475072Y1456210I-202J-1D01*
G01X472252D01*
G02X472050Y1456413I1J203D01*
G01Y1457032D01*
G03X472000Y1457164I-200J0D01*
G02Y1460080I1661J1458D01*
G03X472050Y1460212I-150J132D01*
G01Y1462151D01*
G03X472000Y1462283I-200J0D01*
G02Y1465199I1661J1458D01*
G03X472050Y1465331I-150J132D01*
G01Y1465951D01*
G02X472252Y1466154I202J1D01*
G37*
G36*
G01X489575D02*
X492395D01*
G02X492598Y1465951I0J-203D01*
G01Y1465329D01*
G03X492648Y1465197I200J0D01*
G02Y1462285I-1664J-1456D01*
G03X492598Y1462153I150J-132D01*
G01Y1460210D01*
G03X492648Y1460078I200J0D01*
G02Y1457166I-1664J-1456D01*
G03X492598Y1457034I150J-132D01*
G01Y1456413D01*
G02X492395Y1456210I-203J0D01*
G01X489575D01*
G02X489372Y1456413I0J203D01*
G01Y1457034D01*
G03X489322Y1457166I-200J0D01*
G02Y1460078I1664J1456D01*
G03X489372Y1460210I-150J132D01*
G01Y1462153D01*
G03X489322Y1462285I-200J0D01*
G02Y1465197I1664J1456D01*
G03X489372Y1465329I-150J132D01*
G01Y1465951D01*
G02X489575Y1466154I203J0D01*
G37*
G36*
G01X506897D02*
X509717D01*
G02X509920Y1465951I0J-203D01*
G01Y1465329D01*
G03X509970Y1465197I200J0D01*
G02Y1462285I-1664J-1456D01*
G03X509920Y1462153I150J-132D01*
G01Y1460210D01*
G03X509970Y1460078I200J0D01*
G02Y1457166I-1664J-1456D01*
G03X509920Y1457034I150J-132D01*
G01Y1456413D01*
G02X509717Y1456210I-203J0D01*
G01X506897D01*
G02X506694Y1456413I0J203D01*
G01Y1457034D01*
G03X506644Y1457166I-200J0D01*
G02Y1460078I1664J1456D01*
G03X506694Y1460210I-150J132D01*
G01Y1462153D01*
G03X506644Y1462285I-200J0D01*
G02Y1465197I1664J1456D01*
G03X506694Y1465329I-150J132D01*
G01Y1465951D01*
G02X506897Y1466154I203J0D01*
G37*
G36*
G01X645480D02*
X648300D01*
G02X648502Y1465951I-1J-203D01*
G01Y1465331D01*
G03X648552Y1465199I200J0D01*
G02Y1462283I-1661J-1458D01*
G03X648502Y1462151I150J-132D01*
G01Y1460212D01*
G03X648552Y1460080I200J0D01*
G02Y1457164I-1661J-1458D01*
G03X648502Y1457032I150J-132D01*
G01Y1456413D01*
G02X648300Y1456210I-202J-1D01*
G01X645480D01*
G02X645278Y1456413I1J203D01*
G01Y1457032D01*
G03X645228Y1457164I-200J0D01*
G02Y1460080I1661J1458D01*
G03X645278Y1460212I-150J132D01*
G01Y1462151D01*
G03X645228Y1462283I-200J0D01*
G02Y1465199I1661J1458D01*
G03X645278Y1465331I-150J132D01*
G01Y1465951D01*
G02X645480Y1466154I202J1D01*
G37*
G36*
G01X662803D02*
X665623D01*
G02X665826Y1465951I0J-203D01*
G01Y1465329D01*
G03X665876Y1465197I200J0D01*
G02Y1462285I-1664J-1456D01*
G03X665826Y1462153I150J-132D01*
G01Y1460210D01*
G03X665876Y1460078I200J0D01*
G02Y1457166I-1664J-1456D01*
G03X665826Y1457034I150J-132D01*
G01Y1456413D01*
G02X665623Y1456210I-203J0D01*
G01X662803D01*
G02X662600Y1456413I0J203D01*
G01Y1457034D01*
G03X662550Y1457166I-200J0D01*
G02Y1460078I1664J1456D01*
G03X662600Y1460210I-150J132D01*
G01Y1462153D01*
G03X662550Y1462285I-200J0D01*
G02Y1465197I1664J1456D01*
G03X662600Y1465329I-150J132D01*
G01Y1465951D01*
G02X662803Y1466154I203J0D01*
G37*
G36*
G01X680125D02*
X682945D01*
G02X683148Y1465951I0J-203D01*
G01Y1465329D01*
G03X683198Y1465197I200J0D01*
G02Y1462285I-1664J-1456D01*
G03X683148Y1462153I150J-132D01*
G01Y1460210D01*
G03X683198Y1460078I200J0D01*
G02Y1457166I-1664J-1456D01*
G03X683148Y1457034I150J-132D01*
G01Y1456413D01*
G02X682945Y1456210I-203J0D01*
G01X680125D01*
G02X679922Y1456413I0J203D01*
G01Y1457034D01*
G03X679872Y1457166I-200J0D01*
G02Y1460078I1664J1456D01*
G03X679922Y1460210I-150J132D01*
G01Y1462153D01*
G03X679872Y1462285I-200J0D01*
G02Y1465197I1664J1456D01*
G03X679922Y1465329I-150J132D01*
G01Y1465951D01*
G02X680125Y1466154I203J0D01*
G37*
G36*
G01X1165086D02*
X1167906D01*
G02X1168108Y1465951I-1J-203D01*
G01Y1465331D01*
G03X1168158Y1465199I200J0D01*
G02Y1462283I-1661J-1458D01*
G03X1168108Y1462151I150J-132D01*
G01Y1460212D01*
G03X1168158Y1460080I200J0D01*
G02Y1457164I-1661J-1458D01*
G03X1168108Y1457032I150J-132D01*
G01Y1456413D01*
G02X1167906Y1456210I-202J-1D01*
G01X1165086D01*
G02X1164884Y1456413I1J203D01*
G01Y1457032D01*
G03X1164834Y1457164I-200J0D01*
G02Y1460080I1661J1458D01*
G03X1164884Y1460212I-150J132D01*
G01Y1462151D01*
G03X1164834Y1462283I-200J0D01*
G02Y1465199I1661J1458D01*
G03X1164884Y1465331I-150J132D01*
G01Y1465951D01*
G02X1165086Y1466154I202J1D01*
G37*
G36*
G01X1182408D02*
X1185228D01*
G02X1185430Y1465951I-1J-203D01*
G01Y1465331D01*
G03X1185480Y1465199I200J0D01*
G02Y1462283I-1661J-1458D01*
G03X1185430Y1462151I150J-132D01*
G01Y1460212D01*
G03X1185480Y1460080I200J0D01*
G02Y1457164I-1661J-1458D01*
G03X1185430Y1457032I150J-132D01*
G01Y1456413D01*
G02X1185228Y1456210I-202J-1D01*
G01X1182408D01*
G02X1182206Y1456413I1J203D01*
G01Y1457032D01*
G03X1182156Y1457164I-200J0D01*
G02Y1460080I1661J1458D01*
G03X1182206Y1460212I-150J132D01*
G01Y1462151D01*
G03X1182156Y1462283I-200J0D01*
G02Y1465199I1661J1458D01*
G03X1182206Y1465331I-150J132D01*
G01Y1465951D01*
G02X1182408Y1466154I202J1D01*
G37*
G36*
G01X1303669D02*
X1306489D01*
G02X1306692Y1465951I0J-203D01*
G01Y1465329D01*
G03X1306742Y1465197I200J0D01*
G02Y1462285I-1664J-1456D01*
G03X1306692Y1462153I150J-132D01*
G01Y1460210D01*
G03X1306742Y1460078I200J0D01*
G02Y1457166I-1664J-1456D01*
G03X1306692Y1457034I150J-132D01*
G01Y1456413D01*
G02X1306489Y1456210I-203J0D01*
G01X1303669D01*
G02X1303466Y1456413I0J203D01*
G01Y1457034D01*
G03X1303416Y1457166I-200J0D01*
G02Y1460078I1664J1456D01*
G03X1303466Y1460210I-150J132D01*
G01Y1462153D01*
G03X1303416Y1462285I-200J0D01*
G02Y1465197I1664J1456D01*
G03X1303466Y1465329I-150J132D01*
G01Y1465951D01*
G02X1303669Y1466154I203J0D01*
G37*
G36*
G01X1320992D02*
X1323812D01*
G02X1324014Y1465951I-1J-203D01*
G01Y1465331D01*
G03X1324064Y1465199I200J0D01*
G02Y1462283I-1661J-1458D01*
G03X1324014Y1462151I150J-132D01*
G01Y1460212D01*
G03X1324064Y1460080I200J0D01*
G02Y1457164I-1661J-1458D01*
G03X1324014Y1457032I150J-132D01*
G01Y1456413D01*
G02X1323812Y1456210I-202J-1D01*
G01X1320992D01*
G02X1320790Y1456413I1J203D01*
G01Y1457032D01*
G03X1320740Y1457164I-200J0D01*
G02Y1460080I1661J1458D01*
G03X1320790Y1460212I-150J132D01*
G01Y1462151D01*
G03X1320740Y1462283I-200J0D01*
G02Y1465199I1661J1458D01*
G03X1320790Y1465331I-150J132D01*
G01Y1465951D01*
G02X1320992Y1466154I202J1D01*
G37*
G36*
G01X1338315D02*
X1341135D01*
G02X1341338Y1465951I0J-203D01*
G01Y1465329D01*
G03X1341388Y1465197I200J0D01*
G02Y1462285I-1664J-1456D01*
G03X1341338Y1462153I150J-132D01*
G01Y1460210D01*
G03X1341388Y1460078I200J0D01*
G02Y1457166I-1664J-1456D01*
G03X1341338Y1457034I150J-132D01*
G01Y1456413D01*
G02X1341135Y1456210I-203J0D01*
G01X1338315D01*
G02X1338112Y1456413I0J203D01*
G01Y1457034D01*
G03X1338062Y1457166I-200J0D01*
G02Y1460078I1664J1456D01*
G03X1338112Y1460210I-150J132D01*
G01Y1462153D01*
G03X1338062Y1462285I-200J0D01*
G02Y1465197I1664J1456D01*
G03X1338112Y1465329I-150J132D01*
G01Y1465951D01*
G02X1338315Y1466154I203J0D01*
G37*
G36*
G01X1355637D02*
X1358457D01*
G02X1358660Y1465951I0J-203D01*
G01Y1465329D01*
G03X1358710Y1465197I200J0D01*
G02Y1462285I-1664J-1456D01*
G03X1358660Y1462153I150J-132D01*
G01Y1460210D01*
G03X1358710Y1460078I200J0D01*
G02Y1457166I-1664J-1456D01*
G03X1358660Y1457034I150J-132D01*
G01Y1456413D01*
G02X1358457Y1456210I-203J0D01*
G01X1355637D01*
G02X1355434Y1456413I0J203D01*
G01Y1457034D01*
G03X1355384Y1457166I-200J0D01*
G02Y1460078I1664J1456D01*
G03X1355434Y1460210I-150J132D01*
G01Y1462153D01*
G03X1355384Y1462285I-200J0D01*
G02Y1465197I1664J1456D01*
G03X1355434Y1465329I-150J132D01*
G01Y1465951D01*
G02X1355637Y1466154I203J0D01*
G37*
G36*
G01X1476897D02*
X1479717D01*
G02X1479920Y1465951I0J-203D01*
G01Y1465329D01*
G03X1479970Y1465197I200J0D01*
G02Y1462285I-1664J-1456D01*
G03X1479920Y1462153I150J-132D01*
G01Y1460210D01*
G03X1479970Y1460078I200J0D01*
G02Y1457166I-1664J-1456D01*
G03X1479920Y1457034I150J-132D01*
G01Y1456413D01*
G02X1479717Y1456210I-203J0D01*
G01X1476897D01*
G02X1476694Y1456413I0J203D01*
G01Y1457034D01*
G03X1476644Y1457166I-200J0D01*
G02Y1460078I1664J1456D01*
G03X1476694Y1460210I-150J132D01*
G01Y1462153D01*
G03X1476644Y1462285I-200J0D01*
G02Y1465197I1664J1456D01*
G03X1476694Y1465329I-150J132D01*
G01Y1465951D01*
G02X1476897Y1466154I203J0D01*
G37*
G36*
G01X1494220D02*
X1497040D01*
G02X1497242Y1465951I-1J-203D01*
G01Y1465331D01*
G03X1497292Y1465199I200J0D01*
G02Y1462283I-1661J-1458D01*
G03X1497242Y1462151I150J-132D01*
G01Y1460212D01*
G03X1497292Y1460080I200J0D01*
G02Y1457164I-1661J-1458D01*
G03X1497242Y1457032I150J-132D01*
G01Y1456413D01*
G02X1497040Y1456210I-202J-1D01*
G01X1494220D01*
G02X1494018Y1456413I1J203D01*
G01Y1457032D01*
G03X1493968Y1457164I-200J0D01*
G02Y1460080I1661J1458D01*
G03X1494018Y1460212I-150J132D01*
G01Y1462151D01*
G03X1493968Y1462283I-200J0D01*
G02Y1465199I1661J1458D01*
G03X1494018Y1465331I-150J132D01*
G01Y1465951D01*
G02X1494220Y1466154I202J1D01*
G37*
G36*
G01X1511543D02*
X1514363D01*
G02X1514566Y1465951I0J-203D01*
G01Y1465329D01*
G03X1514616Y1465197I200J0D01*
G02Y1462285I-1664J-1456D01*
G03X1514566Y1462153I150J-132D01*
G01Y1460210D01*
G03X1514616Y1460078I200J0D01*
G02Y1457166I-1664J-1456D01*
G03X1514566Y1457034I150J-132D01*
G01Y1456413D01*
G02X1514363Y1456210I-203J0D01*
G01X1511543D01*
G02X1511340Y1456413I0J203D01*
G01Y1457034D01*
G03X1511290Y1457166I-200J0D01*
G02Y1460078I1664J1456D01*
G03X1511340Y1460210I-150J132D01*
G01Y1462153D01*
G03X1511290Y1462285I-200J0D01*
G02Y1465197I1664J1456D01*
G03X1511340Y1465329I-150J132D01*
G01Y1465951D01*
G02X1511543Y1466154I203J0D01*
G37*
G36*
G01X1528865D02*
X1531685D01*
G02X1531888Y1465951I0J-203D01*
G01Y1465329D01*
G03X1531938Y1465197I200J0D01*
G02Y1462285I-1664J-1456D01*
G03X1531888Y1462153I150J-132D01*
G01Y1460210D01*
G03X1531938Y1460078I200J0D01*
G02Y1457166I-1664J-1456D01*
G03X1531888Y1457034I150J-132D01*
G01Y1456413D01*
G02X1531685Y1456210I-203J0D01*
G01X1528865D01*
G02X1528662Y1456413I0J203D01*
G01Y1457034D01*
G03X1528612Y1457166I-200J0D01*
G02Y1460078I1664J1456D01*
G03X1528662Y1460210I-150J132D01*
G01Y1462153D01*
G03X1528612Y1462285I-200J0D01*
G02Y1465197I1664J1456D01*
G03X1528662Y1465329I-150J132D01*
G01Y1465951D01*
G02X1528865Y1466154I203J0D01*
G37*
G36*
G01X1684771D02*
X1687591D01*
G02X1687794Y1465951I0J-203D01*
G01Y1465329D01*
G03X1687844Y1465197I200J0D01*
G02Y1462285I-1664J-1456D01*
G03X1687794Y1462153I150J-132D01*
G01Y1460210D01*
G03X1687844Y1460078I200J0D01*
G02Y1457166I-1664J-1456D01*
G03X1687794Y1457034I150J-132D01*
G01Y1456413D01*
G02X1687591Y1456210I-203J0D01*
G01X1684771D01*
G02X1684568Y1456413I0J203D01*
G01Y1457034D01*
G03X1684518Y1457166I-200J0D01*
G02Y1460078I1664J1456D01*
G03X1684568Y1460210I-150J132D01*
G01Y1462153D01*
G03X1684518Y1462285I-200J0D01*
G02Y1465197I1664J1456D01*
G03X1684568Y1465329I-150J132D01*
G01Y1465951D01*
G02X1684771Y1466154I203J0D01*
G37*
G36*
G01X1702093D02*
X1704913D01*
G02X1705116Y1465951I0J-203D01*
G01Y1465329D01*
G03X1705166Y1465197I200J0D01*
G02Y1462285I-1664J-1456D01*
G03X1705116Y1462153I150J-132D01*
G01Y1460210D01*
G03X1705166Y1460078I200J0D01*
G02Y1457166I-1664J-1456D01*
G03X1705116Y1457034I150J-132D01*
G01Y1456413D01*
G02X1704913Y1456210I-203J0D01*
G01X1702093D01*
G02X1701890Y1456413I0J203D01*
G01Y1457034D01*
G03X1701840Y1457166I-200J0D01*
G02Y1460078I1664J1456D01*
G03X1701890Y1460210I-150J132D01*
G01Y1462153D01*
G03X1701840Y1462285I-200J0D01*
G02Y1465197I1664J1456D01*
G03X1701890Y1465329I-150J132D01*
G01Y1465951D01*
G02X1702093Y1466154I203J0D01*
G37*
G36*
G01X134456Y1470484D02*
X137276D01*
G02X137478Y1470281I-1J-203D01*
G01Y1469661D01*
G03X137528Y1469529I200J0D01*
G02Y1466613I-1661J-1458D01*
G03X137478Y1466481I150J-132D01*
G01Y1464543D01*
G03X137528Y1464411I200J0D01*
G02Y1461495I-1661J-1458D01*
G03X137478Y1461363I150J-132D01*
G01Y1460743D01*
G02X137276Y1460540I-202J-1D01*
G01X134456D01*
G02X134254Y1460743I1J203D01*
G01Y1461363D01*
G03X134204Y1461495I-200J0D01*
G02Y1464411I1661J1458D01*
G03X134254Y1464543I-150J132D01*
G01Y1466481D01*
G03X134204Y1466613I-200J0D01*
G02Y1469529I1661J1458D01*
G03X134254Y1469661I-150J132D01*
G01Y1470281D01*
G02X134456Y1470484I202J1D01*
G37*
G36*
G01X151779D02*
X154599D01*
G02X154802Y1470281I0J-203D01*
G01Y1469659D01*
G03X154852Y1469527I200J0D01*
G02Y1466615I-1664J-1456D01*
G03X154802Y1466483I150J-132D01*
G01Y1464541D01*
G03X154852Y1464409I200J0D01*
G02Y1461497I-1664J-1456D01*
G03X154802Y1461365I150J-132D01*
G01Y1460743D01*
G02X154599Y1460540I-203J0D01*
G01X151779D01*
G02X151576Y1460743I0J203D01*
G01Y1461365D01*
G03X151526Y1461497I-200J0D01*
G02Y1464409I1664J1456D01*
G03X151576Y1464541I-150J132D01*
G01Y1466483D01*
G03X151526Y1466615I-200J0D01*
G02Y1469527I1664J1456D01*
G03X151576Y1469659I-150J132D01*
G01Y1470281D01*
G02X151779Y1470484I203J0D01*
G37*
G36*
G01X169102D02*
X171922D01*
G02X172124Y1470281I-1J-203D01*
G01Y1469661D01*
G03X172174Y1469529I200J0D01*
G02Y1466613I-1661J-1458D01*
G03X172124Y1466481I150J-132D01*
G01Y1464543D01*
G03X172174Y1464411I200J0D01*
G02Y1461495I-1661J-1458D01*
G03X172124Y1461363I150J-132D01*
G01Y1460743D01*
G02X171922Y1460540I-202J-1D01*
G01X169102D01*
G02X168900Y1460743I1J203D01*
G01Y1461363D01*
G03X168850Y1461495I-200J0D01*
G02Y1464411I1661J1458D01*
G03X168900Y1464543I-150J132D01*
G01Y1466481D01*
G03X168850Y1466613I-200J0D01*
G02Y1469529I1661J1458D01*
G03X168900Y1469661I-150J132D01*
G01Y1470281D01*
G02X169102Y1470484I202J1D01*
G37*
G36*
G01X186425D02*
X189245D01*
G02X189448Y1470281I0J-203D01*
G01Y1469659D01*
G03X189498Y1469527I200J0D01*
G02Y1466615I-1664J-1456D01*
G03X189448Y1466483I150J-132D01*
G01Y1464541D01*
G03X189498Y1464409I200J0D01*
G02Y1461497I-1664J-1456D01*
G03X189448Y1461365I150J-132D01*
G01Y1460743D01*
G02X189245Y1460540I-203J0D01*
G01X186425D01*
G02X186222Y1460743I0J203D01*
G01Y1461365D01*
G03X186172Y1461497I-200J0D01*
G02Y1464409I1664J1456D01*
G03X186222Y1464541I-150J132D01*
G01Y1466483D01*
G03X186172Y1466615I-200J0D01*
G02Y1469527I1664J1456D01*
G03X186222Y1469659I-150J132D01*
G01Y1470281D01*
G02X186425Y1470484I203J0D01*
G37*
G36*
G01X290361D02*
X293181D01*
G02X293384Y1470281I0J-203D01*
G01Y1469659D01*
G03X293434Y1469527I200J0D01*
G02Y1466615I-1664J-1456D01*
G03X293384Y1466483I150J-132D01*
G01Y1464541D01*
G03X293434Y1464409I200J0D01*
G02Y1461497I-1664J-1456D01*
G03X293384Y1461365I150J-132D01*
G01Y1460743D01*
G02X293181Y1460540I-203J0D01*
G01X290361D01*
G02X290158Y1460743I0J203D01*
G01Y1461365D01*
G03X290108Y1461497I-200J0D01*
G02Y1464409I1664J1456D01*
G03X290158Y1464541I-150J132D01*
G01Y1466483D01*
G03X290108Y1466615I-200J0D01*
G02Y1469527I1664J1456D01*
G03X290158Y1469659I-150J132D01*
G01Y1470281D01*
G02X290361Y1470484I203J0D01*
G37*
G36*
G01X463590D02*
X466410D01*
G02X466612Y1470281I-1J-203D01*
G01Y1469661D01*
G03X466662Y1469529I200J0D01*
G02Y1466613I-1661J-1458D01*
G03X466612Y1466481I150J-132D01*
G01Y1464543D01*
G03X466662Y1464411I200J0D01*
G02Y1461495I-1661J-1458D01*
G03X466612Y1461363I150J-132D01*
G01Y1460743D01*
G02X466410Y1460540I-202J-1D01*
G01X463590D01*
G02X463388Y1460743I1J203D01*
G01Y1461363D01*
G03X463338Y1461495I-200J0D01*
G02Y1464411I1661J1458D01*
G03X463388Y1464543I-150J132D01*
G01Y1466481D01*
G03X463338Y1466613I-200J0D01*
G02Y1469529I1661J1458D01*
G03X463388Y1469661I-150J132D01*
G01Y1470281D01*
G02X463590Y1470484I202J1D01*
G37*
G36*
G01X480913D02*
X483733D01*
G02X483936Y1470281I0J-203D01*
G01Y1469659D01*
G03X483986Y1469527I200J0D01*
G02Y1466615I-1664J-1456D01*
G03X483936Y1466483I150J-132D01*
G01Y1464541D01*
G03X483986Y1464409I200J0D01*
G02Y1461497I-1664J-1456D01*
G03X483936Y1461365I150J-132D01*
G01Y1460743D01*
G02X483733Y1460540I-203J0D01*
G01X480913D01*
G02X480710Y1460743I0J203D01*
G01Y1461365D01*
G03X480660Y1461497I-200J0D01*
G02Y1464409I1664J1456D01*
G03X480710Y1464541I-150J132D01*
G01Y1466483D01*
G03X480660Y1466615I-200J0D01*
G02Y1469527I1664J1456D01*
G03X480710Y1469659I-150J132D01*
G01Y1470281D01*
G02X480913Y1470484I203J0D01*
G37*
G36*
G01X498236D02*
X501056D01*
G02X501258Y1470281I-1J-203D01*
G01Y1469661D01*
G03X501308Y1469529I200J0D01*
G02Y1466613I-1661J-1458D01*
G03X501258Y1466481I150J-132D01*
G01Y1464543D01*
G03X501308Y1464411I200J0D01*
G02Y1461495I-1661J-1458D01*
G03X501258Y1461363I150J-132D01*
G01Y1460743D01*
G02X501056Y1460540I-202J-1D01*
G01X498236D01*
G02X498034Y1460743I1J203D01*
G01Y1461363D01*
G03X497984Y1461495I-200J0D01*
G02Y1464411I1661J1458D01*
G03X498034Y1464543I-150J132D01*
G01Y1466481D01*
G03X497984Y1466613I-200J0D01*
G02Y1469529I1661J1458D01*
G03X498034Y1469661I-150J132D01*
G01Y1470281D01*
G02X498236Y1470484I202J1D01*
G37*
G36*
G01X515559D02*
X518379D01*
G02X518582Y1470281I0J-203D01*
G01Y1469659D01*
G03X518632Y1469527I200J0D01*
G02Y1466615I-1664J-1456D01*
G03X518582Y1466483I150J-132D01*
G01Y1464541D01*
G03X518632Y1464409I200J0D01*
G02Y1461497I-1664J-1456D01*
G03X518582Y1461365I150J-132D01*
G01Y1460743D01*
G02X518379Y1460540I-203J0D01*
G01X515559D01*
G02X515356Y1460743I0J203D01*
G01Y1461365D01*
G03X515306Y1461497I-200J0D01*
G02Y1464409I1664J1456D01*
G03X515356Y1464541I-150J132D01*
G01Y1466483D01*
G03X515306Y1466615I-200J0D01*
G02Y1469527I1664J1456D01*
G03X515356Y1469659I-150J132D01*
G01Y1470281D01*
G02X515559Y1470484I203J0D01*
G37*
G36*
G01X654141D02*
X656961D01*
G02X657164Y1470281I0J-203D01*
G01Y1469659D01*
G03X657214Y1469527I200J0D01*
G02Y1466615I-1664J-1456D01*
G03X657164Y1466483I150J-132D01*
G01Y1464541D01*
G03X657214Y1464409I200J0D01*
G02Y1461497I-1664J-1456D01*
G03X657164Y1461365I150J-132D01*
G01Y1460743D01*
G02X656961Y1460540I-203J0D01*
G01X654141D01*
G02X653938Y1460743I0J203D01*
G01Y1461365D01*
G03X653888Y1461497I-200J0D01*
G02Y1464409I1664J1456D01*
G03X653938Y1464541I-150J132D01*
G01Y1466483D01*
G03X653888Y1466615I-200J0D01*
G02Y1469527I1664J1456D01*
G03X653938Y1469659I-150J132D01*
G01Y1470281D01*
G02X654141Y1470484I203J0D01*
G37*
G36*
G01X671464D02*
X674284D01*
G02X674486Y1470281I-1J-203D01*
G01Y1469661D01*
G03X674536Y1469529I200J0D01*
G02Y1466613I-1661J-1458D01*
G03X674486Y1466481I150J-132D01*
G01Y1464543D01*
G03X674536Y1464411I200J0D01*
G02Y1461495I-1661J-1458D01*
G03X674486Y1461363I150J-132D01*
G01Y1460743D01*
G02X674284Y1460540I-202J-1D01*
G01X671464D01*
G02X671262Y1460743I1J203D01*
G01Y1461363D01*
G03X671212Y1461495I-200J0D01*
G02Y1464411I1661J1458D01*
G03X671262Y1464543I-150J132D01*
G01Y1466481D01*
G03X671212Y1466613I-200J0D01*
G02Y1469529I1661J1458D01*
G03X671262Y1469661I-150J132D01*
G01Y1470281D01*
G02X671464Y1470484I202J1D01*
G37*
G36*
G01X688787D02*
X691607D01*
G02X691810Y1470281I0J-203D01*
G01Y1469659D01*
G03X691860Y1469527I200J0D01*
G02Y1466615I-1664J-1456D01*
G03X691810Y1466483I150J-132D01*
G01Y1464541D01*
G03X691860Y1464409I200J0D01*
G02Y1461497I-1664J-1456D01*
G03X691810Y1461365I150J-132D01*
G01Y1460743D01*
G02X691607Y1460540I-203J0D01*
G01X688787D01*
G02X688584Y1460743I0J203D01*
G01Y1461365D01*
G03X688534Y1461497I-200J0D01*
G02Y1464409I1664J1456D01*
G03X688584Y1464541I-150J132D01*
G01Y1466483D01*
G03X688534Y1466615I-200J0D01*
G02Y1469527I1664J1456D01*
G03X688584Y1469659I-150J132D01*
G01Y1470281D01*
G02X688787Y1470484I203J0D01*
G37*
G36*
G01X1173747D02*
X1176567D01*
G02X1176770Y1470281I0J-203D01*
G01Y1469659D01*
G03X1176820Y1469527I200J0D01*
G02Y1466615I-1664J-1456D01*
G03X1176770Y1466483I150J-132D01*
G01Y1464541D01*
G03X1176820Y1464409I200J0D01*
G02Y1461497I-1664J-1456D01*
G03X1176770Y1461365I150J-132D01*
G01Y1460743D01*
G02X1176567Y1460540I-203J0D01*
G01X1173747D01*
G02X1173544Y1460743I0J203D01*
G01Y1461365D01*
G03X1173494Y1461497I-200J0D01*
G02Y1464409I1664J1456D01*
G03X1173544Y1464541I-150J132D01*
G01Y1466483D01*
G03X1173494Y1466615I-200J0D01*
G02Y1469527I1664J1456D01*
G03X1173544Y1469659I-150J132D01*
G01Y1470281D01*
G02X1173747Y1470484I203J0D01*
G37*
G36*
G01X1191070D02*
X1193890D01*
G02X1194092Y1470281I-1J-203D01*
G01Y1469661D01*
G03X1194142Y1469529I200J0D01*
G02Y1466613I-1661J-1458D01*
G03X1194092Y1466481I150J-132D01*
G01Y1464543D01*
G03X1194142Y1464411I200J0D01*
G02Y1461495I-1661J-1458D01*
G03X1194092Y1461363I150J-132D01*
G01Y1460743D01*
G02X1193890Y1460540I-202J-1D01*
G01X1191070D01*
G02X1190868Y1460743I1J203D01*
G01Y1461363D01*
G03X1190818Y1461495I-200J0D01*
G02Y1464411I1661J1458D01*
G03X1190868Y1464543I-150J132D01*
G01Y1466481D01*
G03X1190818Y1466613I-200J0D01*
G02Y1469529I1661J1458D01*
G03X1190868Y1469661I-150J132D01*
G01Y1470281D01*
G02X1191070Y1470484I202J1D01*
G37*
G36*
G01X1312330D02*
X1315150D01*
G02X1315352Y1470281I-1J-203D01*
G01Y1469661D01*
G03X1315402Y1469529I200J0D01*
G02Y1466613I-1661J-1458D01*
G03X1315352Y1466481I150J-132D01*
G01Y1464543D01*
G03X1315402Y1464411I200J0D01*
G02Y1461495I-1661J-1458D01*
G03X1315352Y1461363I150J-132D01*
G01Y1460743D01*
G02X1315150Y1460540I-202J-1D01*
G01X1312330D01*
G02X1312128Y1460743I1J203D01*
G01Y1461363D01*
G03X1312078Y1461495I-200J0D01*
G02Y1464411I1661J1458D01*
G03X1312128Y1464543I-150J132D01*
G01Y1466481D01*
G03X1312078Y1466613I-200J0D01*
G02Y1469529I1661J1458D01*
G03X1312128Y1469661I-150J132D01*
G01Y1470281D01*
G02X1312330Y1470484I202J1D01*
G37*
G36*
G01X1329653D02*
X1332473D01*
G02X1332676Y1470281I0J-203D01*
G01Y1469659D01*
G03X1332726Y1469527I200J0D01*
G02Y1466615I-1664J-1456D01*
G03X1332676Y1466483I150J-132D01*
G01Y1464541D01*
G03X1332726Y1464409I200J0D01*
G02Y1461497I-1664J-1456D01*
G03X1332676Y1461365I150J-132D01*
G01Y1460743D01*
G02X1332473Y1460540I-203J0D01*
G01X1329653D01*
G02X1329450Y1460743I0J203D01*
G01Y1461365D01*
G03X1329400Y1461497I-200J0D01*
G02Y1464409I1664J1456D01*
G03X1329450Y1464541I-150J132D01*
G01Y1466483D01*
G03X1329400Y1466615I-200J0D01*
G02Y1469527I1664J1456D01*
G03X1329450Y1469659I-150J132D01*
G01Y1470281D01*
G02X1329653Y1470484I203J0D01*
G37*
G36*
G01X1346976D02*
X1349796D01*
G02X1349998Y1470281I-1J-203D01*
G01Y1469661D01*
G03X1350048Y1469529I200J0D01*
G02Y1466613I-1661J-1458D01*
G03X1349998Y1466481I150J-132D01*
G01Y1464543D01*
G03X1350048Y1464411I200J0D01*
G02Y1461495I-1661J-1458D01*
G03X1349998Y1461363I150J-132D01*
G01Y1460743D01*
G02X1349796Y1460540I-202J-1D01*
G01X1346976D01*
G02X1346774Y1460743I1J203D01*
G01Y1461363D01*
G03X1346724Y1461495I-200J0D01*
G02Y1464411I1661J1458D01*
G03X1346774Y1464543I-150J132D01*
G01Y1466481D01*
G03X1346724Y1466613I-200J0D01*
G02Y1469529I1661J1458D01*
G03X1346774Y1469661I-150J132D01*
G01Y1470281D01*
G02X1346976Y1470484I202J1D01*
G37*
G36*
G01X1364299D02*
X1367119D01*
G02X1367322Y1470281I0J-203D01*
G01Y1469659D01*
G03X1367372Y1469527I200J0D01*
G02Y1466615I-1664J-1456D01*
G03X1367322Y1466483I150J-132D01*
G01Y1464541D01*
G03X1367372Y1464409I200J0D01*
G02Y1461497I-1664J-1456D01*
G03X1367322Y1461365I150J-132D01*
G01Y1460743D01*
G02X1367119Y1460540I-203J0D01*
G01X1364299D01*
G02X1364096Y1460743I0J203D01*
G01Y1461365D01*
G03X1364046Y1461497I-200J0D01*
G02Y1464409I1664J1456D01*
G03X1364096Y1464541I-150J132D01*
G01Y1466483D01*
G03X1364046Y1466615I-200J0D01*
G02Y1469527I1664J1456D01*
G03X1364096Y1469659I-150J132D01*
G01Y1470281D01*
G02X1364299Y1470484I203J0D01*
G37*
G36*
G01X1485558D02*
X1488378D01*
G02X1488580Y1470281I-1J-203D01*
G01Y1469661D01*
G03X1488630Y1469529I200J0D01*
G02Y1466613I-1661J-1458D01*
G03X1488580Y1466481I150J-132D01*
G01Y1464543D01*
G03X1488630Y1464411I200J0D01*
G02Y1461495I-1661J-1458D01*
G03X1488580Y1461363I150J-132D01*
G01Y1460743D01*
G02X1488378Y1460540I-202J-1D01*
G01X1485558D01*
G02X1485356Y1460743I1J203D01*
G01Y1461363D01*
G03X1485306Y1461495I-200J0D01*
G02Y1464411I1661J1458D01*
G03X1485356Y1464543I-150J132D01*
G01Y1466481D01*
G03X1485306Y1466613I-200J0D01*
G02Y1469529I1661J1458D01*
G03X1485356Y1469661I-150J132D01*
G01Y1470281D01*
G02X1485558Y1470484I202J1D01*
G37*
G36*
G01X1502881D02*
X1505701D01*
G02X1505904Y1470281I0J-203D01*
G01Y1469659D01*
G03X1505954Y1469527I200J0D01*
G02Y1466615I-1664J-1456D01*
G03X1505904Y1466483I150J-132D01*
G01Y1464541D01*
G03X1505954Y1464409I200J0D01*
G02Y1461497I-1664J-1456D01*
G03X1505904Y1461365I150J-132D01*
G01Y1460743D01*
G02X1505701Y1460540I-203J0D01*
G01X1502881D01*
G02X1502678Y1460743I0J203D01*
G01Y1461365D01*
G03X1502628Y1461497I-200J0D01*
G02Y1464409I1664J1456D01*
G03X1502678Y1464541I-150J132D01*
G01Y1466483D01*
G03X1502628Y1466615I-200J0D01*
G02Y1469527I1664J1456D01*
G03X1502678Y1469659I-150J132D01*
G01Y1470281D01*
G02X1502881Y1470484I203J0D01*
G37*
G36*
G01X1520204D02*
X1523024D01*
G02X1523226Y1470281I-1J-203D01*
G01Y1469661D01*
G03X1523276Y1469529I200J0D01*
G02Y1466613I-1661J-1458D01*
G03X1523226Y1466481I150J-132D01*
G01Y1464543D01*
G03X1523276Y1464411I200J0D01*
G02Y1461495I-1661J-1458D01*
G03X1523226Y1461363I150J-132D01*
G01Y1460743D01*
G02X1523024Y1460540I-202J-1D01*
G01X1520204D01*
G02X1520002Y1460743I1J203D01*
G01Y1461363D01*
G03X1519952Y1461495I-200J0D01*
G02Y1464411I1661J1458D01*
G03X1520002Y1464543I-150J132D01*
G01Y1466481D01*
G03X1519952Y1466613I-200J0D01*
G02Y1469529I1661J1458D01*
G03X1520002Y1469661I-150J132D01*
G01Y1470281D01*
G02X1520204Y1470484I202J1D01*
G37*
G36*
G01X1537527D02*
X1540347D01*
G02X1540550Y1470281I0J-203D01*
G01Y1469659D01*
G03X1540600Y1469527I200J0D01*
G02Y1466615I-1664J-1456D01*
G03X1540550Y1466483I150J-132D01*
G01Y1464541D01*
G03X1540600Y1464409I200J0D01*
G02Y1461497I-1664J-1456D01*
G03X1540550Y1461365I150J-132D01*
G01Y1460743D01*
G02X1540347Y1460540I-203J0D01*
G01X1537527D01*
G02X1537324Y1460743I0J203D01*
G01Y1461365D01*
G03X1537274Y1461497I-200J0D01*
G02Y1464409I1664J1456D01*
G03X1537324Y1464541I-150J132D01*
G01Y1466483D01*
G03X1537274Y1466615I-200J0D01*
G02Y1469527I1664J1456D01*
G03X1537324Y1469659I-150J132D01*
G01Y1470281D01*
G02X1537527Y1470484I203J0D01*
G37*
G36*
G01X1693432D02*
X1696252D01*
G02X1696454Y1470281I-1J-203D01*
G01Y1469661D01*
G03X1696504Y1469529I200J0D01*
G02Y1466613I-1661J-1458D01*
G03X1696454Y1466481I150J-132D01*
G01Y1464543D01*
G03X1696504Y1464411I200J0D01*
G02Y1461495I-1661J-1458D01*
G03X1696454Y1461363I150J-132D01*
G01Y1460743D01*
G02X1696252Y1460540I-202J-1D01*
G01X1693432D01*
G02X1693230Y1460743I1J203D01*
G01Y1461363D01*
G03X1693180Y1461495I-200J0D01*
G02Y1464411I1661J1458D01*
G03X1693230Y1464543I-150J132D01*
G01Y1466481D01*
G03X1693180Y1466613I-200J0D01*
G02Y1469529I1661J1458D01*
G03X1693230Y1469661I-150J132D01*
G01Y1470281D01*
G02X1693432Y1470484I202J1D01*
G37*
G36*
G01X1710755D02*
X1713575D01*
G02X1713778Y1470281I0J-203D01*
G01Y1469659D01*
G03X1713828Y1469527I200J0D01*
G02Y1466615I-1664J-1456D01*
G03X1713778Y1466483I150J-132D01*
G01Y1464541D01*
G03X1713828Y1464409I200J0D01*
G02Y1461497I-1664J-1456D01*
G03X1713778Y1461365I150J-132D01*
G01Y1460743D01*
G02X1713575Y1460540I-203J0D01*
G01X1710755D01*
G02X1710552Y1460743I0J203D01*
G01Y1461365D01*
G03X1710502Y1461497I-200J0D01*
G02Y1464409I1664J1456D01*
G03X1710552Y1464541I-150J132D01*
G01Y1466483D01*
G03X1710502Y1466615I-200J0D01*
G02Y1469527I1664J1456D01*
G03X1710552Y1469659I-150J132D01*
G01Y1470281D01*
G02X1710755Y1470484I203J0D01*
G37*
G36*
G01X125795Y1481508D02*
X128615D01*
G02X128818Y1481305I0J-203D01*
G01Y1480683D01*
G03X128868Y1480551I200J0D01*
G02Y1477639I-1664J-1456D01*
G03X128818Y1477507I150J-132D01*
G01Y1475565D01*
G03X128868Y1475433I200J0D01*
G02Y1472521I-1664J-1456D01*
G03X128818Y1472389I150J-132D01*
G01Y1471767D01*
G02X128615Y1471564I-203J0D01*
G01X125795D01*
G02X125592Y1471767I0J203D01*
G01Y1472389D01*
G03X125542Y1472521I-200J0D01*
G02Y1475433I1664J1456D01*
G03X125592Y1475565I-150J132D01*
G01Y1477507D01*
G03X125542Y1477639I-200J0D01*
G02Y1480551I1664J1456D01*
G03X125592Y1480683I-150J132D01*
G01Y1481305D01*
G02X125795Y1481508I203J0D01*
G37*
G36*
G01X143118D02*
X145938D01*
G02X146140Y1481305I-1J-203D01*
G01Y1480685D01*
G03X146190Y1480553I200J0D01*
G02Y1477637I-1661J-1458D01*
G03X146140Y1477505I150J-132D01*
G01Y1475567D01*
G03X146190Y1475435I200J0D01*
G02Y1472519I-1661J-1458D01*
G03X146140Y1472387I150J-132D01*
G01Y1471767D01*
G02X145938Y1471564I-202J-1D01*
G01X143118D01*
G02X142916Y1471767I1J203D01*
G01Y1472387D01*
G03X142866Y1472519I-200J0D01*
G02Y1475435I1661J1458D01*
G03X142916Y1475567I-150J132D01*
G01Y1477505D01*
G03X142866Y1477637I-200J0D01*
G02Y1480553I1661J1458D01*
G03X142916Y1480685I-150J132D01*
G01Y1481305D01*
G02X143118Y1481508I202J1D01*
G37*
G36*
G01X160440D02*
X163260D01*
G02X163462Y1481305I-1J-203D01*
G01Y1480685D01*
G03X163512Y1480553I200J0D01*
G02Y1477637I-1661J-1458D01*
G03X163462Y1477505I150J-132D01*
G01Y1475567D01*
G03X163512Y1475435I200J0D01*
G02Y1472519I-1661J-1458D01*
G03X163462Y1472387I150J-132D01*
G01Y1471767D01*
G02X163260Y1471564I-202J-1D01*
G01X160440D01*
G02X160238Y1471767I1J203D01*
G01Y1472387D01*
G03X160188Y1472519I-200J0D01*
G02Y1475435I1661J1458D01*
G03X160238Y1475567I-150J132D01*
G01Y1477505D01*
G03X160188Y1477637I-200J0D01*
G02Y1480553I1661J1458D01*
G03X160238Y1480685I-150J132D01*
G01Y1481305D01*
G02X160440Y1481508I202J1D01*
G37*
G36*
G01X177763D02*
X180583D01*
G02X180786Y1481305I0J-203D01*
G01Y1480683D01*
G03X180836Y1480551I200J0D01*
G02Y1477639I-1664J-1456D01*
G03X180786Y1477507I150J-132D01*
G01Y1475565D01*
G03X180836Y1475433I200J0D01*
G02Y1472521I-1664J-1456D01*
G03X180786Y1472389I150J-132D01*
G01Y1471767D01*
G02X180583Y1471564I-203J0D01*
G01X177763D01*
G02X177560Y1471767I0J203D01*
G01Y1472389D01*
G03X177510Y1472521I-200J0D01*
G02Y1475433I1664J1456D01*
G03X177560Y1475565I-150J132D01*
G01Y1477507D01*
G03X177510Y1477639I-200J0D01*
G02Y1480551I1664J1456D01*
G03X177560Y1480683I-150J132D01*
G01Y1481305D01*
G02X177763Y1481508I203J0D01*
G37*
G36*
G01X281700D02*
X284520D01*
G02X284722Y1481305I-1J-203D01*
G01Y1480685D01*
G03X284772Y1480553I200J0D01*
G02Y1477637I-1661J-1458D01*
G03X284722Y1477505I150J-132D01*
G01Y1475567D01*
G03X284772Y1475435I200J0D01*
G02Y1472519I-1661J-1458D01*
G03X284722Y1472387I150J-132D01*
G01Y1471767D01*
G02X284520Y1471564I-202J-1D01*
G01X281700D01*
G02X281498Y1471767I1J203D01*
G01Y1472387D01*
G03X281448Y1472519I-200J0D01*
G02Y1475435I1661J1458D01*
G03X281498Y1475567I-150J132D01*
G01Y1477505D01*
G03X281448Y1477637I-200J0D01*
G02Y1480553I1661J1458D01*
G03X281498Y1480685I-150J132D01*
G01Y1481305D01*
G02X281700Y1481508I202J1D01*
G37*
G36*
G01X299023D02*
X301843D01*
G02X302046Y1481305I0J-203D01*
G01Y1480683D01*
G03X302096Y1480551I200J0D01*
G02Y1477639I-1664J-1456D01*
G03X302046Y1477507I150J-132D01*
G01Y1475565D01*
G03X302096Y1475433I200J0D01*
G02Y1472521I-1664J-1456D01*
G03X302046Y1472389I150J-132D01*
G01Y1471767D01*
G02X301843Y1471564I-203J0D01*
G01X299023D01*
G02X298820Y1471767I0J203D01*
G01Y1472389D01*
G03X298770Y1472521I-200J0D01*
G02Y1475433I1664J1456D01*
G03X298820Y1475565I-150J132D01*
G01Y1477507D01*
G03X298770Y1477639I-200J0D01*
G02Y1480551I1664J1456D01*
G03X298820Y1480683I-150J132D01*
G01Y1481305D01*
G02X299023Y1481508I203J0D01*
G37*
G36*
G01X454929D02*
X457749D01*
G02X457952Y1481305I0J-203D01*
G01Y1480683D01*
G03X458002Y1480551I200J0D01*
G02Y1477639I-1664J-1456D01*
G03X457952Y1477507I150J-132D01*
G01Y1475565D01*
G03X458002Y1475433I200J0D01*
G02Y1472521I-1664J-1456D01*
G03X457952Y1472389I150J-132D01*
G01Y1471767D01*
G02X457749Y1471564I-203J0D01*
G01X454929D01*
G02X454726Y1471767I0J203D01*
G01Y1472389D01*
G03X454676Y1472521I-200J0D01*
G02Y1475433I1664J1456D01*
G03X454726Y1475565I-150J132D01*
G01Y1477507D01*
G03X454676Y1477639I-200J0D01*
G02Y1480551I1664J1456D01*
G03X454726Y1480683I-150J132D01*
G01Y1481305D01*
G02X454929Y1481508I203J0D01*
G37*
G36*
G01X472252D02*
X475072D01*
G02X475274Y1481305I-1J-203D01*
G01Y1480685D01*
G03X475324Y1480553I200J0D01*
G02Y1477637I-1661J-1458D01*
G03X475274Y1477505I150J-132D01*
G01Y1475567D01*
G03X475324Y1475435I200J0D01*
G02Y1472519I-1661J-1458D01*
G03X475274Y1472387I150J-132D01*
G01Y1471767D01*
G02X475072Y1471564I-202J-1D01*
G01X472252D01*
G02X472050Y1471767I1J203D01*
G01Y1472387D01*
G03X472000Y1472519I-200J0D01*
G02Y1475435I1661J1458D01*
G03X472050Y1475567I-150J132D01*
G01Y1477505D01*
G03X472000Y1477637I-200J0D01*
G02Y1480553I1661J1458D01*
G03X472050Y1480685I-150J132D01*
G01Y1481305D01*
G02X472252Y1481508I202J1D01*
G37*
G36*
G01X489575D02*
X492395D01*
G02X492598Y1481305I0J-203D01*
G01Y1480683D01*
G03X492648Y1480551I200J0D01*
G02Y1477639I-1664J-1456D01*
G03X492598Y1477507I150J-132D01*
G01Y1475565D01*
G03X492648Y1475433I200J0D01*
G02Y1472521I-1664J-1456D01*
G03X492598Y1472389I150J-132D01*
G01Y1471767D01*
G02X492395Y1471564I-203J0D01*
G01X489575D01*
G02X489372Y1471767I0J203D01*
G01Y1472389D01*
G03X489322Y1472521I-200J0D01*
G02Y1475433I1664J1456D01*
G03X489372Y1475565I-150J132D01*
G01Y1477507D01*
G03X489322Y1477639I-200J0D01*
G02Y1480551I1664J1456D01*
G03X489372Y1480683I-150J132D01*
G01Y1481305D01*
G02X489575Y1481508I203J0D01*
G37*
G36*
G01X506897D02*
X509717D01*
G02X509920Y1481305I0J-203D01*
G01Y1480683D01*
G03X509970Y1480551I200J0D01*
G02Y1477639I-1664J-1456D01*
G03X509920Y1477507I150J-132D01*
G01Y1475565D01*
G03X509970Y1475433I200J0D01*
G02Y1472521I-1664J-1456D01*
G03X509920Y1472389I150J-132D01*
G01Y1471767D01*
G02X509717Y1471564I-203J0D01*
G01X506897D01*
G02X506694Y1471767I0J203D01*
G01Y1472389D01*
G03X506644Y1472521I-200J0D01*
G02Y1475433I1664J1456D01*
G03X506694Y1475565I-150J132D01*
G01Y1477507D01*
G03X506644Y1477639I-200J0D01*
G02Y1480551I1664J1456D01*
G03X506694Y1480683I-150J132D01*
G01Y1481305D01*
G02X506897Y1481508I203J0D01*
G37*
G36*
G01X645480D02*
X648300D01*
G02X648502Y1481305I-1J-203D01*
G01Y1480685D01*
G03X648552Y1480553I200J0D01*
G02Y1477637I-1661J-1458D01*
G03X648502Y1477505I150J-132D01*
G01Y1475567D01*
G03X648552Y1475435I200J0D01*
G02Y1472519I-1661J-1458D01*
G03X648502Y1472387I150J-132D01*
G01Y1471767D01*
G02X648300Y1471564I-202J-1D01*
G01X645480D01*
G02X645278Y1471767I1J203D01*
G01Y1472387D01*
G03X645228Y1472519I-200J0D01*
G02Y1475435I1661J1458D01*
G03X645278Y1475567I-150J132D01*
G01Y1477505D01*
G03X645228Y1477637I-200J0D01*
G02Y1480553I1661J1458D01*
G03X645278Y1480685I-150J132D01*
G01Y1481305D01*
G02X645480Y1481508I202J1D01*
G37*
G36*
G01X662803D02*
X665623D01*
G02X665826Y1481305I0J-203D01*
G01Y1480683D01*
G03X665876Y1480551I200J0D01*
G02Y1477639I-1664J-1456D01*
G03X665826Y1477507I150J-132D01*
G01Y1475565D01*
G03X665876Y1475433I200J0D01*
G02Y1472521I-1664J-1456D01*
G03X665826Y1472389I150J-132D01*
G01Y1471767D01*
G02X665623Y1471564I-203J0D01*
G01X662803D01*
G02X662600Y1471767I0J203D01*
G01Y1472389D01*
G03X662550Y1472521I-200J0D01*
G02Y1475433I1664J1456D01*
G03X662600Y1475565I-150J132D01*
G01Y1477507D01*
G03X662550Y1477639I-200J0D01*
G02Y1480551I1664J1456D01*
G03X662600Y1480683I-150J132D01*
G01Y1481305D01*
G02X662803Y1481508I203J0D01*
G37*
G36*
G01X680125D02*
X682945D01*
G02X683148Y1481305I0J-203D01*
G01Y1480683D01*
G03X683198Y1480551I200J0D01*
G02Y1477639I-1664J-1456D01*
G03X683148Y1477507I150J-132D01*
G01Y1475565D01*
G03X683198Y1475433I200J0D01*
G02Y1472521I-1664J-1456D01*
G03X683148Y1472389I150J-132D01*
G01Y1471767D01*
G02X682945Y1471564I-203J0D01*
G01X680125D01*
G02X679922Y1471767I0J203D01*
G01Y1472389D01*
G03X679872Y1472521I-200J0D01*
G02Y1475433I1664J1456D01*
G03X679922Y1475565I-150J132D01*
G01Y1477507D01*
G03X679872Y1477639I-200J0D01*
G02Y1480551I1664J1456D01*
G03X679922Y1480683I-150J132D01*
G01Y1481305D01*
G02X680125Y1481508I203J0D01*
G37*
G36*
G01X1165086D02*
X1167906D01*
G02X1168108Y1481305I-1J-203D01*
G01Y1480685D01*
G03X1168158Y1480553I200J0D01*
G02Y1477637I-1661J-1458D01*
G03X1168108Y1477505I150J-132D01*
G01Y1475567D01*
G03X1168158Y1475435I200J0D01*
G02Y1472519I-1661J-1458D01*
G03X1168108Y1472387I150J-132D01*
G01Y1471767D01*
G02X1167906Y1471564I-202J-1D01*
G01X1165086D01*
G02X1164884Y1471767I1J203D01*
G01Y1472387D01*
G03X1164834Y1472519I-200J0D01*
G02Y1475435I1661J1458D01*
G03X1164884Y1475567I-150J132D01*
G01Y1477505D01*
G03X1164834Y1477637I-200J0D01*
G02Y1480553I1661J1458D01*
G03X1164884Y1480685I-150J132D01*
G01Y1481305D01*
G02X1165086Y1481508I202J1D01*
G37*
G36*
G01X1182408D02*
X1185228D01*
G02X1185430Y1481305I-1J-203D01*
G01Y1480685D01*
G03X1185480Y1480553I200J0D01*
G02Y1477637I-1661J-1458D01*
G03X1185430Y1477505I150J-132D01*
G01Y1475567D01*
G03X1185480Y1475435I200J0D01*
G02Y1472519I-1661J-1458D01*
G03X1185430Y1472387I150J-132D01*
G01Y1471767D01*
G02X1185228Y1471564I-202J-1D01*
G01X1182408D01*
G02X1182206Y1471767I1J203D01*
G01Y1472387D01*
G03X1182156Y1472519I-200J0D01*
G02Y1475435I1661J1458D01*
G03X1182206Y1475567I-150J132D01*
G01Y1477505D01*
G03X1182156Y1477637I-200J0D01*
G02Y1480553I1661J1458D01*
G03X1182206Y1480685I-150J132D01*
G01Y1481305D01*
G02X1182408Y1481508I202J1D01*
G37*
G36*
G01X1303669D02*
X1306489D01*
G02X1306692Y1481305I0J-203D01*
G01Y1480683D01*
G03X1306742Y1480551I200J0D01*
G02Y1477639I-1664J-1456D01*
G03X1306692Y1477507I150J-132D01*
G01Y1475565D01*
G03X1306742Y1475433I200J0D01*
G02Y1472521I-1664J-1456D01*
G03X1306692Y1472389I150J-132D01*
G01Y1471767D01*
G02X1306489Y1471564I-203J0D01*
G01X1303669D01*
G02X1303466Y1471767I0J203D01*
G01Y1472389D01*
G03X1303416Y1472521I-200J0D01*
G02Y1475433I1664J1456D01*
G03X1303466Y1475565I-150J132D01*
G01Y1477507D01*
G03X1303416Y1477639I-200J0D01*
G02Y1480551I1664J1456D01*
G03X1303466Y1480683I-150J132D01*
G01Y1481305D01*
G02X1303669Y1481508I203J0D01*
G37*
G36*
G01X1320992D02*
X1323812D01*
G02X1324014Y1481305I-1J-203D01*
G01Y1480685D01*
G03X1324064Y1480553I200J0D01*
G02Y1477637I-1661J-1458D01*
G03X1324014Y1477505I150J-132D01*
G01Y1475567D01*
G03X1324064Y1475435I200J0D01*
G02Y1472519I-1661J-1458D01*
G03X1324014Y1472387I150J-132D01*
G01Y1471767D01*
G02X1323812Y1471564I-202J-1D01*
G01X1320992D01*
G02X1320790Y1471767I1J203D01*
G01Y1472387D01*
G03X1320740Y1472519I-200J0D01*
G02Y1475435I1661J1458D01*
G03X1320790Y1475567I-150J132D01*
G01Y1477505D01*
G03X1320740Y1477637I-200J0D01*
G02Y1480553I1661J1458D01*
G03X1320790Y1480685I-150J132D01*
G01Y1481305D01*
G02X1320992Y1481508I202J1D01*
G37*
G36*
G01X1338315D02*
X1341135D01*
G02X1341338Y1481305I0J-203D01*
G01Y1480683D01*
G03X1341388Y1480551I200J0D01*
G02Y1477639I-1664J-1456D01*
G03X1341338Y1477507I150J-132D01*
G01Y1475565D01*
G03X1341388Y1475433I200J0D01*
G02Y1472521I-1664J-1456D01*
G03X1341338Y1472389I150J-132D01*
G01Y1471767D01*
G02X1341135Y1471564I-203J0D01*
G01X1338315D01*
G02X1338112Y1471767I0J203D01*
G01Y1472389D01*
G03X1338062Y1472521I-200J0D01*
G02Y1475433I1664J1456D01*
G03X1338112Y1475565I-150J132D01*
G01Y1477507D01*
G03X1338062Y1477639I-200J0D01*
G02Y1480551I1664J1456D01*
G03X1338112Y1480683I-150J132D01*
G01Y1481305D01*
G02X1338315Y1481508I203J0D01*
G37*
G36*
G01X1355637D02*
X1358457D01*
G02X1358660Y1481305I0J-203D01*
G01Y1480683D01*
G03X1358710Y1480551I200J0D01*
G02Y1477639I-1664J-1456D01*
G03X1358660Y1477507I150J-132D01*
G01Y1475565D01*
G03X1358710Y1475433I200J0D01*
G02Y1472521I-1664J-1456D01*
G03X1358660Y1472389I150J-132D01*
G01Y1471767D01*
G02X1358457Y1471564I-203J0D01*
G01X1355637D01*
G02X1355434Y1471767I0J203D01*
G01Y1472389D01*
G03X1355384Y1472521I-200J0D01*
G02Y1475433I1664J1456D01*
G03X1355434Y1475565I-150J132D01*
G01Y1477507D01*
G03X1355384Y1477639I-200J0D01*
G02Y1480551I1664J1456D01*
G03X1355434Y1480683I-150J132D01*
G01Y1481305D01*
G02X1355637Y1481508I203J0D01*
G37*
G36*
G01X1476897D02*
X1479717D01*
G02X1479920Y1481305I0J-203D01*
G01Y1480683D01*
G03X1479970Y1480551I200J0D01*
G02Y1477639I-1664J-1456D01*
G03X1479920Y1477507I150J-132D01*
G01Y1475565D01*
G03X1479970Y1475433I200J0D01*
G02Y1472521I-1664J-1456D01*
G03X1479920Y1472389I150J-132D01*
G01Y1471767D01*
G02X1479717Y1471564I-203J0D01*
G01X1476897D01*
G02X1476694Y1471767I0J203D01*
G01Y1472389D01*
G03X1476644Y1472521I-200J0D01*
G02Y1475433I1664J1456D01*
G03X1476694Y1475565I-150J132D01*
G01Y1477507D01*
G03X1476644Y1477639I-200J0D01*
G02Y1480551I1664J1456D01*
G03X1476694Y1480683I-150J132D01*
G01Y1481305D01*
G02X1476897Y1481508I203J0D01*
G37*
G36*
G01X1494220D02*
X1497040D01*
G02X1497242Y1481305I-1J-203D01*
G01Y1480685D01*
G03X1497292Y1480553I200J0D01*
G02Y1477637I-1661J-1458D01*
G03X1497242Y1477505I150J-132D01*
G01Y1475567D01*
G03X1497292Y1475435I200J0D01*
G02Y1472519I-1661J-1458D01*
G03X1497242Y1472387I150J-132D01*
G01Y1471767D01*
G02X1497040Y1471564I-202J-1D01*
G01X1494220D01*
G02X1494018Y1471767I1J203D01*
G01Y1472387D01*
G03X1493968Y1472519I-200J0D01*
G02Y1475435I1661J1458D01*
G03X1494018Y1475567I-150J132D01*
G01Y1477505D01*
G03X1493968Y1477637I-200J0D01*
G02Y1480553I1661J1458D01*
G03X1494018Y1480685I-150J132D01*
G01Y1481305D01*
G02X1494220Y1481508I202J1D01*
G37*
G36*
G01X1511543D02*
X1514363D01*
G02X1514566Y1481305I0J-203D01*
G01Y1480683D01*
G03X1514616Y1480551I200J0D01*
G02Y1477639I-1664J-1456D01*
G03X1514566Y1477507I150J-132D01*
G01Y1475565D01*
G03X1514616Y1475433I200J0D01*
G02Y1472521I-1664J-1456D01*
G03X1514566Y1472389I150J-132D01*
G01Y1471767D01*
G02X1514363Y1471564I-203J0D01*
G01X1511543D01*
G02X1511340Y1471767I0J203D01*
G01Y1472389D01*
G03X1511290Y1472521I-200J0D01*
G02Y1475433I1664J1456D01*
G03X1511340Y1475565I-150J132D01*
G01Y1477507D01*
G03X1511290Y1477639I-200J0D01*
G02Y1480551I1664J1456D01*
G03X1511340Y1480683I-150J132D01*
G01Y1481305D01*
G02X1511543Y1481508I203J0D01*
G37*
G36*
G01X1528865D02*
X1531685D01*
G02X1531888Y1481305I0J-203D01*
G01Y1480683D01*
G03X1531938Y1480551I200J0D01*
G02Y1477639I-1664J-1456D01*
G03X1531888Y1477507I150J-132D01*
G01Y1475565D01*
G03X1531938Y1475433I200J0D01*
G02Y1472521I-1664J-1456D01*
G03X1531888Y1472389I150J-132D01*
G01Y1471767D01*
G02X1531685Y1471564I-203J0D01*
G01X1528865D01*
G02X1528662Y1471767I0J203D01*
G01Y1472389D01*
G03X1528612Y1472521I-200J0D01*
G02Y1475433I1664J1456D01*
G03X1528662Y1475565I-150J132D01*
G01Y1477507D01*
G03X1528612Y1477639I-200J0D01*
G02Y1480551I1664J1456D01*
G03X1528662Y1480683I-150J132D01*
G01Y1481305D01*
G02X1528865Y1481508I203J0D01*
G37*
G36*
G01X1684771D02*
X1687591D01*
G02X1687794Y1481305I0J-203D01*
G01Y1480683D01*
G03X1687844Y1480551I200J0D01*
G02Y1477639I-1664J-1456D01*
G03X1687794Y1477507I150J-132D01*
G01Y1475565D01*
G03X1687844Y1475433I200J0D01*
G02Y1472521I-1664J-1456D01*
G03X1687794Y1472389I150J-132D01*
G01Y1471767D01*
G02X1687591Y1471564I-203J0D01*
G01X1684771D01*
G02X1684568Y1471767I0J203D01*
G01Y1472389D01*
G03X1684518Y1472521I-200J0D01*
G02Y1475433I1664J1456D01*
G03X1684568Y1475565I-150J132D01*
G01Y1477507D01*
G03X1684518Y1477639I-200J0D01*
G02Y1480551I1664J1456D01*
G03X1684568Y1480683I-150J132D01*
G01Y1481305D01*
G02X1684771Y1481508I203J0D01*
G37*
G36*
G01X1702093D02*
X1704913D01*
G02X1705116Y1481305I0J-203D01*
G01Y1480683D01*
G03X1705166Y1480551I200J0D01*
G02Y1477639I-1664J-1456D01*
G03X1705116Y1477507I150J-132D01*
G01Y1475565D01*
G03X1705166Y1475433I200J0D01*
G02Y1472521I-1664J-1456D01*
G03X1705116Y1472389I150J-132D01*
G01Y1471767D01*
G02X1704913Y1471564I-203J0D01*
G01X1702093D01*
G02X1701890Y1471767I0J203D01*
G01Y1472389D01*
G03X1701840Y1472521I-200J0D01*
G02Y1475433I1664J1456D01*
G03X1701890Y1475565I-150J132D01*
G01Y1477507D01*
G03X1701840Y1477639I-200J0D01*
G02Y1480551I1664J1456D01*
G03X1701890Y1480683I-150J132D01*
G01Y1481305D01*
G02X1702093Y1481508I203J0D01*
G37*
G36*
G01X134456Y1485838D02*
X137276D01*
G02X137478Y1485635I-1J-203D01*
G01Y1485016D01*
G03X137528Y1484884I200J0D01*
G02Y1481968I-1661J-1458D01*
G03X137478Y1481836I150J-132D01*
G01Y1479898D01*
G03X137528Y1479766I200J0D01*
G02Y1476850I-1661J-1458D01*
G03X137478Y1476718I150J-132D01*
G01Y1476097D01*
G02X137276Y1475894I-202J-1D01*
G01X134456D01*
G02X134254Y1476097I1J203D01*
G01Y1476718D01*
G03X134204Y1476850I-200J0D01*
G02Y1479766I1661J1458D01*
G03X134254Y1479898I-150J132D01*
G01Y1481836D01*
G03X134204Y1481968I-200J0D01*
G02Y1484884I1661J1458D01*
G03X134254Y1485016I-150J132D01*
G01Y1485635D01*
G02X134456Y1485838I202J1D01*
G37*
G36*
G01X151779D02*
X154599D01*
G02X154802Y1485635I0J-203D01*
G01Y1485014D01*
G03X154852Y1484882I200J0D01*
G02Y1481970I-1664J-1456D01*
G03X154802Y1481838I150J-132D01*
G01Y1479896D01*
G03X154852Y1479764I200J0D01*
G02Y1476852I-1664J-1456D01*
G03X154802Y1476720I150J-132D01*
G01Y1476097D01*
G02X154599Y1475894I-203J0D01*
G01X151779D01*
G02X151576Y1476097I0J203D01*
G01Y1476720D01*
G03X151526Y1476852I-200J0D01*
G02Y1479764I1664J1456D01*
G03X151576Y1479896I-150J132D01*
G01Y1481838D01*
G03X151526Y1481970I-200J0D01*
G02Y1484882I1664J1456D01*
G03X151576Y1485014I-150J132D01*
G01Y1485635D01*
G02X151779Y1485838I203J0D01*
G37*
G36*
G01X169102D02*
X171922D01*
G02X172124Y1485635I-1J-203D01*
G01Y1485016D01*
G03X172174Y1484884I200J0D01*
G02Y1481968I-1661J-1458D01*
G03X172124Y1481836I150J-132D01*
G01Y1479898D01*
G03X172174Y1479766I200J0D01*
G02Y1476850I-1661J-1458D01*
G03X172124Y1476718I150J-132D01*
G01Y1476097D01*
G02X171922Y1475894I-202J-1D01*
G01X169102D01*
G02X168900Y1476097I1J203D01*
G01Y1476718D01*
G03X168850Y1476850I-200J0D01*
G02Y1479766I1661J1458D01*
G03X168900Y1479898I-150J132D01*
G01Y1481836D01*
G03X168850Y1481968I-200J0D01*
G02Y1484884I1661J1458D01*
G03X168900Y1485016I-150J132D01*
G01Y1485635D01*
G02X169102Y1485838I202J1D01*
G37*
G36*
G01X290361D02*
X293181D01*
G02X293384Y1485635I0J-203D01*
G01Y1485014D01*
G03X293434Y1484882I200J0D01*
G02Y1481970I-1664J-1456D01*
G03X293384Y1481838I150J-132D01*
G01Y1479896D01*
G03X293434Y1479764I200J0D01*
G02Y1476852I-1664J-1456D01*
G03X293384Y1476720I150J-132D01*
G01Y1476097D01*
G02X293181Y1475894I-203J0D01*
G01X290361D01*
G02X290158Y1476097I0J203D01*
G01Y1476720D01*
G03X290108Y1476852I-200J0D01*
G02Y1479764I1664J1456D01*
G03X290158Y1479896I-150J132D01*
G01Y1481838D01*
G03X290108Y1481970I-200J0D01*
G02Y1484882I1664J1456D01*
G03X290158Y1485014I-150J132D01*
G01Y1485635D01*
G02X290361Y1485838I203J0D01*
G37*
G36*
G01X463590D02*
X466410D01*
G02X466612Y1485635I-1J-203D01*
G01Y1485016D01*
G03X466662Y1484884I200J0D01*
G02Y1481968I-1661J-1458D01*
G03X466612Y1481836I150J-132D01*
G01Y1479898D01*
G03X466662Y1479766I200J0D01*
G02Y1476850I-1661J-1458D01*
G03X466612Y1476718I150J-132D01*
G01Y1476097D01*
G02X466410Y1475894I-202J-1D01*
G01X463590D01*
G02X463388Y1476097I1J203D01*
G01Y1476718D01*
G03X463338Y1476850I-200J0D01*
G02Y1479766I1661J1458D01*
G03X463388Y1479898I-150J132D01*
G01Y1481836D01*
G03X463338Y1481968I-200J0D01*
G02Y1484884I1661J1458D01*
G03X463388Y1485016I-150J132D01*
G01Y1485635D01*
G02X463590Y1485838I202J1D01*
G37*
G36*
G01X480913D02*
X483733D01*
G02X483936Y1485635I0J-203D01*
G01Y1485014D01*
G03X483986Y1484882I200J0D01*
G02Y1481970I-1664J-1456D01*
G03X483936Y1481838I150J-132D01*
G01Y1479896D01*
G03X483986Y1479764I200J0D01*
G02Y1476852I-1664J-1456D01*
G03X483936Y1476720I150J-132D01*
G01Y1476097D01*
G02X483733Y1475894I-203J0D01*
G01X480913D01*
G02X480710Y1476097I0J203D01*
G01Y1476720D01*
G03X480660Y1476852I-200J0D01*
G02Y1479764I1664J1456D01*
G03X480710Y1479896I-150J132D01*
G01Y1481838D01*
G03X480660Y1481970I-200J0D01*
G02Y1484882I1664J1456D01*
G03X480710Y1485014I-150J132D01*
G01Y1485635D01*
G02X480913Y1485838I203J0D01*
G37*
G36*
G01X498236D02*
X501056D01*
G02X501258Y1485635I-1J-203D01*
G01Y1485016D01*
G03X501308Y1484884I200J0D01*
G02Y1481968I-1661J-1458D01*
G03X501258Y1481836I150J-132D01*
G01Y1479898D01*
G03X501308Y1479766I200J0D01*
G02Y1476850I-1661J-1458D01*
G03X501258Y1476718I150J-132D01*
G01Y1476097D01*
G02X501056Y1475894I-202J-1D01*
G01X498236D01*
G02X498034Y1476097I1J203D01*
G01Y1476718D01*
G03X497984Y1476850I-200J0D01*
G02Y1479766I1661J1458D01*
G03X498034Y1479898I-150J132D01*
G01Y1481836D01*
G03X497984Y1481968I-200J0D01*
G02Y1484884I1661J1458D01*
G03X498034Y1485016I-150J132D01*
G01Y1485635D01*
G02X498236Y1485838I202J1D01*
G37*
G36*
G01X515559D02*
X518379D01*
G02X518582Y1485635I0J-203D01*
G01Y1485014D01*
G03X518632Y1484882I200J0D01*
G02Y1481970I-1664J-1456D01*
G03X518582Y1481838I150J-132D01*
G01Y1479896D01*
G03X518632Y1479764I200J0D01*
G02Y1476852I-1664J-1456D01*
G03X518582Y1476720I150J-132D01*
G01Y1476097D01*
G02X518379Y1475894I-203J0D01*
G01X515559D01*
G02X515356Y1476097I0J203D01*
G01Y1476720D01*
G03X515306Y1476852I-200J0D01*
G02Y1479764I1664J1456D01*
G03X515356Y1479896I-150J132D01*
G01Y1481838D01*
G03X515306Y1481970I-200J0D01*
G02Y1484882I1664J1456D01*
G03X515356Y1485014I-150J132D01*
G01Y1485635D01*
G02X515559Y1485838I203J0D01*
G37*
G36*
G01X654141D02*
X656961D01*
G02X657164Y1485635I0J-203D01*
G01Y1485014D01*
G03X657214Y1484882I200J0D01*
G02Y1481970I-1664J-1456D01*
G03X657164Y1481838I150J-132D01*
G01Y1479896D01*
G03X657214Y1479764I200J0D01*
G02Y1476852I-1664J-1456D01*
G03X657164Y1476720I150J-132D01*
G01Y1476097D01*
G02X656961Y1475894I-203J0D01*
G01X654141D01*
G02X653938Y1476097I0J203D01*
G01Y1476720D01*
G03X653888Y1476852I-200J0D01*
G02Y1479764I1664J1456D01*
G03X653938Y1479896I-150J132D01*
G01Y1481838D01*
G03X653888Y1481970I-200J0D01*
G02Y1484882I1664J1456D01*
G03X653938Y1485014I-150J132D01*
G01Y1485635D01*
G02X654141Y1485838I203J0D01*
G37*
G36*
G01X671464D02*
X674284D01*
G02X674486Y1485635I-1J-203D01*
G01Y1485016D01*
G03X674536Y1484884I200J0D01*
G02Y1481968I-1661J-1458D01*
G03X674486Y1481836I150J-132D01*
G01Y1479898D01*
G03X674536Y1479766I200J0D01*
G02Y1476850I-1661J-1458D01*
G03X674486Y1476718I150J-132D01*
G01Y1476097D01*
G02X674284Y1475894I-202J-1D01*
G01X671464D01*
G02X671262Y1476097I1J203D01*
G01Y1476718D01*
G03X671212Y1476850I-200J0D01*
G02Y1479766I1661J1458D01*
G03X671262Y1479898I-150J132D01*
G01Y1481836D01*
G03X671212Y1481968I-200J0D01*
G02Y1484884I1661J1458D01*
G03X671262Y1485016I-150J132D01*
G01Y1485635D01*
G02X671464Y1485838I202J1D01*
G37*
G36*
G01X688787D02*
X691607D01*
G02X691810Y1485635I0J-203D01*
G01Y1485014D01*
G03X691860Y1484882I200J0D01*
G02Y1481970I-1664J-1456D01*
G03X691810Y1481838I150J-132D01*
G01Y1479896D01*
G03X691860Y1479764I200J0D01*
G02Y1476852I-1664J-1456D01*
G03X691810Y1476720I150J-132D01*
G01Y1476097D01*
G02X691607Y1475894I-203J0D01*
G01X688787D01*
G02X688584Y1476097I0J203D01*
G01Y1476720D01*
G03X688534Y1476852I-200J0D01*
G02Y1479764I1664J1456D01*
G03X688584Y1479896I-150J132D01*
G01Y1481838D01*
G03X688534Y1481970I-200J0D01*
G02Y1484882I1664J1456D01*
G03X688584Y1485014I-150J132D01*
G01Y1485635D01*
G02X688787Y1485838I203J0D01*
G37*
G36*
G01X1173747D02*
X1176567D01*
G02X1176770Y1485635I0J-203D01*
G01Y1485014D01*
G03X1176820Y1484882I200J0D01*
G02Y1481970I-1664J-1456D01*
G03X1176770Y1481838I150J-132D01*
G01Y1479896D01*
G03X1176820Y1479764I200J0D01*
G02Y1476852I-1664J-1456D01*
G03X1176770Y1476720I150J-132D01*
G01Y1476097D01*
G02X1176567Y1475894I-203J0D01*
G01X1173747D01*
G02X1173544Y1476097I0J203D01*
G01Y1476720D01*
G03X1173494Y1476852I-200J0D01*
G02Y1479764I1664J1456D01*
G03X1173544Y1479896I-150J132D01*
G01Y1481838D01*
G03X1173494Y1481970I-200J0D01*
G02Y1484882I1664J1456D01*
G03X1173544Y1485014I-150J132D01*
G01Y1485635D01*
G02X1173747Y1485838I203J0D01*
G37*
G36*
G01X1191070D02*
X1193890D01*
G02X1194092Y1485635I-1J-203D01*
G01Y1485016D01*
G03X1194142Y1484884I200J0D01*
G02Y1481968I-1661J-1458D01*
G03X1194092Y1481836I150J-132D01*
G01Y1479898D01*
G03X1194142Y1479766I200J0D01*
G02Y1476850I-1661J-1458D01*
G03X1194092Y1476718I150J-132D01*
G01Y1476097D01*
G02X1193890Y1475894I-202J-1D01*
G01X1191070D01*
G02X1190868Y1476097I1J203D01*
G01Y1476718D01*
G03X1190818Y1476850I-200J0D01*
G02Y1479766I1661J1458D01*
G03X1190868Y1479898I-150J132D01*
G01Y1481836D01*
G03X1190818Y1481968I-200J0D01*
G02Y1484884I1661J1458D01*
G03X1190868Y1485016I-150J132D01*
G01Y1485635D01*
G02X1191070Y1485838I202J1D01*
G37*
G36*
G01X1312330D02*
X1315150D01*
G02X1315352Y1485635I-1J-203D01*
G01Y1485016D01*
G03X1315402Y1484884I200J0D01*
G02Y1481968I-1661J-1458D01*
G03X1315352Y1481836I150J-132D01*
G01Y1479898D01*
G03X1315402Y1479766I200J0D01*
G02Y1476850I-1661J-1458D01*
G03X1315352Y1476718I150J-132D01*
G01Y1476097D01*
G02X1315150Y1475894I-202J-1D01*
G01X1312330D01*
G02X1312128Y1476097I1J203D01*
G01Y1476718D01*
G03X1312078Y1476850I-200J0D01*
G02Y1479766I1661J1458D01*
G03X1312128Y1479898I-150J132D01*
G01Y1481836D01*
G03X1312078Y1481968I-200J0D01*
G02Y1484884I1661J1458D01*
G03X1312128Y1485016I-150J132D01*
G01Y1485635D01*
G02X1312330Y1485838I202J1D01*
G37*
G36*
G01X1329653D02*
X1332473D01*
G02X1332676Y1485635I0J-203D01*
G01Y1485014D01*
G03X1332726Y1484882I200J0D01*
G02Y1481970I-1664J-1456D01*
G03X1332676Y1481838I150J-132D01*
G01Y1479896D01*
G03X1332726Y1479764I200J0D01*
G02Y1476852I-1664J-1456D01*
G03X1332676Y1476720I150J-132D01*
G01Y1476097D01*
G02X1332473Y1475894I-203J0D01*
G01X1329653D01*
G02X1329450Y1476097I0J203D01*
G01Y1476720D01*
G03X1329400Y1476852I-200J0D01*
G02Y1479764I1664J1456D01*
G03X1329450Y1479896I-150J132D01*
G01Y1481838D01*
G03X1329400Y1481970I-200J0D01*
G02Y1484882I1664J1456D01*
G03X1329450Y1485014I-150J132D01*
G01Y1485635D01*
G02X1329653Y1485838I203J0D01*
G37*
G36*
G01X1346976D02*
X1349796D01*
G02X1349998Y1485635I-1J-203D01*
G01Y1485016D01*
G03X1350048Y1484884I200J0D01*
G02Y1481968I-1661J-1458D01*
G03X1349998Y1481836I150J-132D01*
G01Y1479898D01*
G03X1350048Y1479766I200J0D01*
G02Y1476850I-1661J-1458D01*
G03X1349998Y1476718I150J-132D01*
G01Y1476097D01*
G02X1349796Y1475894I-202J-1D01*
G01X1346976D01*
G02X1346774Y1476097I1J203D01*
G01Y1476718D01*
G03X1346724Y1476850I-200J0D01*
G02Y1479766I1661J1458D01*
G03X1346774Y1479898I-150J132D01*
G01Y1481836D01*
G03X1346724Y1481968I-200J0D01*
G02Y1484884I1661J1458D01*
G03X1346774Y1485016I-150J132D01*
G01Y1485635D01*
G02X1346976Y1485838I202J1D01*
G37*
G36*
G01X1364299D02*
X1367119D01*
G02X1367322Y1485635I0J-203D01*
G01Y1485014D01*
G03X1367372Y1484882I200J0D01*
G02Y1481970I-1664J-1456D01*
G03X1367322Y1481838I150J-132D01*
G01Y1479896D01*
G03X1367372Y1479764I200J0D01*
G02Y1476852I-1664J-1456D01*
G03X1367322Y1476720I150J-132D01*
G01Y1476097D01*
G02X1367119Y1475894I-203J0D01*
G01X1364299D01*
G02X1364096Y1476097I0J203D01*
G01Y1476720D01*
G03X1364046Y1476852I-200J0D01*
G02Y1479764I1664J1456D01*
G03X1364096Y1479896I-150J132D01*
G01Y1481838D01*
G03X1364046Y1481970I-200J0D01*
G02Y1484882I1664J1456D01*
G03X1364096Y1485014I-150J132D01*
G01Y1485635D01*
G02X1364299Y1485838I203J0D01*
G37*
G36*
G01X1485558D02*
X1488378D01*
G02X1488580Y1485635I-1J-203D01*
G01Y1485016D01*
G03X1488630Y1484884I200J0D01*
G02Y1481968I-1661J-1458D01*
G03X1488580Y1481836I150J-132D01*
G01Y1479898D01*
G03X1488630Y1479766I200J0D01*
G02Y1476850I-1661J-1458D01*
G03X1488580Y1476718I150J-132D01*
G01Y1476097D01*
G02X1488378Y1475894I-202J-1D01*
G01X1485558D01*
G02X1485356Y1476097I1J203D01*
G01Y1476718D01*
G03X1485306Y1476850I-200J0D01*
G02Y1479766I1661J1458D01*
G03X1485356Y1479898I-150J132D01*
G01Y1481836D01*
G03X1485306Y1481968I-200J0D01*
G02Y1484884I1661J1458D01*
G03X1485356Y1485016I-150J132D01*
G01Y1485635D01*
G02X1485558Y1485838I202J1D01*
G37*
G36*
G01X1502881D02*
X1505701D01*
G02X1505904Y1485635I0J-203D01*
G01Y1485014D01*
G03X1505954Y1484882I200J0D01*
G02Y1481970I-1664J-1456D01*
G03X1505904Y1481838I150J-132D01*
G01Y1479896D01*
G03X1505954Y1479764I200J0D01*
G02Y1476852I-1664J-1456D01*
G03X1505904Y1476720I150J-132D01*
G01Y1476097D01*
G02X1505701Y1475894I-203J0D01*
G01X1502881D01*
G02X1502678Y1476097I0J203D01*
G01Y1476720D01*
G03X1502628Y1476852I-200J0D01*
G02Y1479764I1664J1456D01*
G03X1502678Y1479896I-150J132D01*
G01Y1481838D01*
G03X1502628Y1481970I-200J0D01*
G02Y1484882I1664J1456D01*
G03X1502678Y1485014I-150J132D01*
G01Y1485635D01*
G02X1502881Y1485838I203J0D01*
G37*
G36*
G01X1520204D02*
X1523024D01*
G02X1523226Y1485635I-1J-203D01*
G01Y1485016D01*
G03X1523276Y1484884I200J0D01*
G02Y1481968I-1661J-1458D01*
G03X1523226Y1481836I150J-132D01*
G01Y1479898D01*
G03X1523276Y1479766I200J0D01*
G02Y1476850I-1661J-1458D01*
G03X1523226Y1476718I150J-132D01*
G01Y1476097D01*
G02X1523024Y1475894I-202J-1D01*
G01X1520204D01*
G02X1520002Y1476097I1J203D01*
G01Y1476718D01*
G03X1519952Y1476850I-200J0D01*
G02Y1479766I1661J1458D01*
G03X1520002Y1479898I-150J132D01*
G01Y1481836D01*
G03X1519952Y1481968I-200J0D01*
G02Y1484884I1661J1458D01*
G03X1520002Y1485016I-150J132D01*
G01Y1485635D01*
G02X1520204Y1485838I202J1D01*
G37*
G36*
G01X1537527D02*
X1540347D01*
G02X1540550Y1485635I0J-203D01*
G01Y1485014D01*
G03X1540600Y1484882I200J0D01*
G02Y1481970I-1664J-1456D01*
G03X1540550Y1481838I150J-132D01*
G01Y1479896D01*
G03X1540600Y1479764I200J0D01*
G02Y1476852I-1664J-1456D01*
G03X1540550Y1476720I150J-132D01*
G01Y1476097D01*
G02X1540347Y1475894I-203J0D01*
G01X1537527D01*
G02X1537324Y1476097I0J203D01*
G01Y1476720D01*
G03X1537274Y1476852I-200J0D01*
G02Y1479764I1664J1456D01*
G03X1537324Y1479896I-150J132D01*
G01Y1481838D01*
G03X1537274Y1481970I-200J0D01*
G02Y1484882I1664J1456D01*
G03X1537324Y1485014I-150J132D01*
G01Y1485635D01*
G02X1537527Y1485838I203J0D01*
G37*
G36*
G01X1693432D02*
X1696252D01*
G02X1696454Y1485635I-1J-203D01*
G01Y1485016D01*
G03X1696504Y1484884I200J0D01*
G02Y1481968I-1661J-1458D01*
G03X1696454Y1481836I150J-132D01*
G01Y1479898D01*
G03X1696504Y1479766I200J0D01*
G02Y1476850I-1661J-1458D01*
G03X1696454Y1476718I150J-132D01*
G01Y1476097D01*
G02X1696252Y1475894I-202J-1D01*
G01X1693432D01*
G02X1693230Y1476097I1J203D01*
G01Y1476718D01*
G03X1693180Y1476850I-200J0D01*
G02Y1479766I1661J1458D01*
G03X1693230Y1479898I-150J132D01*
G01Y1481836D01*
G03X1693180Y1481968I-200J0D01*
G02Y1484884I1661J1458D01*
G03X1693230Y1485016I-150J132D01*
G01Y1485635D01*
G02X1693432Y1485838I202J1D01*
G37*
G36*
G01X1710755D02*
X1713575D01*
G02X1713778Y1485635I0J-203D01*
G01Y1485014D01*
G03X1713828Y1484882I200J0D01*
G02Y1481970I-1664J-1456D01*
G03X1713778Y1481838I150J-132D01*
G01Y1479896D01*
G03X1713828Y1479764I200J0D01*
G02Y1476852I-1664J-1456D01*
G03X1713778Y1476720I150J-132D01*
G01Y1476097D01*
G02X1713575Y1475894I-203J0D01*
G01X1710755D01*
G02X1710552Y1476097I0J203D01*
G01Y1476720D01*
G03X1710502Y1476852I-200J0D01*
G02Y1479764I1664J1456D01*
G03X1710552Y1479896I-150J132D01*
G01Y1481838D01*
G03X1710502Y1481970I-200J0D01*
G02Y1484882I1664J1456D01*
G03X1710552Y1485014I-150J132D01*
G01Y1485635D01*
G02X1710755Y1485838I203J0D01*
G37*
G36*
G01X186425D02*
X189245D01*
G02X189448Y1485636I1J-202D01*
G01Y1485014D01*
G03X189498Y1484882I200J0D01*
G02Y1481970I-1664J-1456D01*
G03X189448Y1481838I150J-132D01*
G01Y1479896D01*
G03X189498Y1479764I200J0D01*
G02Y1476852I-1664J-1456D01*
G03X189448Y1476720I150J-132D01*
G01Y1476098D01*
G02X189245Y1475896I-203J1D01*
G01X186425D01*
G02X186222Y1476098I-1J202D01*
G01Y1476720D01*
G03X186172Y1476852I-200J0D01*
G02Y1479764I1664J1456D01*
G03X186222Y1479896I-150J132D01*
G01Y1481838D01*
G03X186172Y1481970I-200J0D01*
G02Y1484882I1664J1456D01*
G03X186222Y1485014I-150J132D01*
G01Y1485636D01*
G02X186425Y1485838I203J-1D01*
G37*
G36*
G01X125795Y1496862D02*
X128615D01*
G02X128818Y1496659I0J-203D01*
G01Y1496037D01*
G03X128868Y1495905I200J0D01*
G02Y1492993I-1664J-1456D01*
G03X128818Y1492861I150J-132D01*
G01Y1490919D01*
G03X128868Y1490787I200J0D01*
G02Y1487875I-1664J-1456D01*
G03X128818Y1487743I150J-132D01*
G01Y1487121D01*
G02X128615Y1486918I-203J0D01*
G01X125795D01*
G02X125592Y1487121I0J203D01*
G01Y1487743D01*
G03X125542Y1487875I-200J0D01*
G02Y1490787I1664J1456D01*
G03X125592Y1490919I-150J132D01*
G01Y1492861D01*
G03X125542Y1492993I-200J0D01*
G02Y1495905I1664J1456D01*
G03X125592Y1496037I-150J132D01*
G01Y1496659D01*
G02X125795Y1496862I203J0D01*
G37*
G36*
G01X143118D02*
X145938D01*
G02X146140Y1496659I-1J-203D01*
G01Y1496039D01*
G03X146190Y1495907I200J0D01*
G02Y1492991I-1661J-1458D01*
G03X146140Y1492859I150J-132D01*
G01Y1490921D01*
G03X146190Y1490789I200J0D01*
G02Y1487873I-1661J-1458D01*
G03X146140Y1487741I150J-132D01*
G01Y1487121D01*
G02X145938Y1486918I-202J-1D01*
G01X143118D01*
G02X142916Y1487121I1J203D01*
G01Y1487741D01*
G03X142866Y1487873I-200J0D01*
G02Y1490789I1661J1458D01*
G03X142916Y1490921I-150J132D01*
G01Y1492859D01*
G03X142866Y1492991I-200J0D01*
G02Y1495907I1661J1458D01*
G03X142916Y1496039I-150J132D01*
G01Y1496659D01*
G02X143118Y1496862I202J1D01*
G37*
G36*
G01X160440D02*
X163260D01*
G02X163462Y1496659I-1J-203D01*
G01Y1496039D01*
G03X163512Y1495907I200J0D01*
G02Y1492991I-1661J-1458D01*
G03X163462Y1492859I150J-132D01*
G01Y1490921D01*
G03X163512Y1490789I200J0D01*
G02Y1487873I-1661J-1458D01*
G03X163462Y1487741I150J-132D01*
G01Y1487121D01*
G02X163260Y1486918I-202J-1D01*
G01X160440D01*
G02X160238Y1487121I1J203D01*
G01Y1487741D01*
G03X160188Y1487873I-200J0D01*
G02Y1490789I1661J1458D01*
G03X160238Y1490921I-150J132D01*
G01Y1492859D01*
G03X160188Y1492991I-200J0D01*
G02Y1495907I1661J1458D01*
G03X160238Y1496039I-150J132D01*
G01Y1496659D01*
G02X160440Y1496862I202J1D01*
G37*
G36*
G01X281700D02*
X284520D01*
G02X284722Y1496659I-1J-203D01*
G01Y1496039D01*
G03X284772Y1495907I200J0D01*
G02Y1492991I-1661J-1458D01*
G03X284722Y1492859I150J-132D01*
G01Y1490921D01*
G03X284772Y1490789I200J0D01*
G02Y1487873I-1661J-1458D01*
G03X284722Y1487741I150J-132D01*
G01Y1487121D01*
G02X284520Y1486918I-202J-1D01*
G01X281700D01*
G02X281498Y1487121I1J203D01*
G01Y1487741D01*
G03X281448Y1487873I-200J0D01*
G02Y1490789I1661J1458D01*
G03X281498Y1490921I-150J132D01*
G01Y1492859D01*
G03X281448Y1492991I-200J0D01*
G02Y1495907I1661J1458D01*
G03X281498Y1496039I-150J132D01*
G01Y1496659D01*
G02X281700Y1496862I202J1D01*
G37*
G36*
G01X299023D02*
X301843D01*
G02X302046Y1496659I0J-203D01*
G01Y1496037D01*
G03X302096Y1495905I200J0D01*
G02Y1492993I-1664J-1456D01*
G03X302046Y1492861I150J-132D01*
G01Y1490919D01*
G03X302096Y1490787I200J0D01*
G02Y1487875I-1664J-1456D01*
G03X302046Y1487743I150J-132D01*
G01Y1487121D01*
G02X301843Y1486918I-203J0D01*
G01X299023D01*
G02X298820Y1487121I0J203D01*
G01Y1487743D01*
G03X298770Y1487875I-200J0D01*
G02Y1490787I1664J1456D01*
G03X298820Y1490919I-150J132D01*
G01Y1492861D01*
G03X298770Y1492993I-200J0D01*
G02Y1495905I1664J1456D01*
G03X298820Y1496037I-150J132D01*
G01Y1496659D01*
G02X299023Y1496862I203J0D01*
G37*
G36*
G01X454929D02*
X457749D01*
G02X457952Y1496659I0J-203D01*
G01Y1496037D01*
G03X458002Y1495905I200J0D01*
G02Y1492993I-1664J-1456D01*
G03X457952Y1492861I150J-132D01*
G01Y1490919D01*
G03X458002Y1490787I200J0D01*
G02Y1487875I-1664J-1456D01*
G03X457952Y1487743I150J-132D01*
G01Y1487121D01*
G02X457749Y1486918I-203J0D01*
G01X454929D01*
G02X454726Y1487121I0J203D01*
G01Y1487743D01*
G03X454676Y1487875I-200J0D01*
G02Y1490787I1664J1456D01*
G03X454726Y1490919I-150J132D01*
G01Y1492861D01*
G03X454676Y1492993I-200J0D01*
G02Y1495905I1664J1456D01*
G03X454726Y1496037I-150J132D01*
G01Y1496659D01*
G02X454929Y1496862I203J0D01*
G37*
G36*
G01X472252D02*
X475072D01*
G02X475274Y1496659I-1J-203D01*
G01Y1496039D01*
G03X475324Y1495907I200J0D01*
G02Y1492991I-1661J-1458D01*
G03X475274Y1492859I150J-132D01*
G01Y1490921D01*
G03X475324Y1490789I200J0D01*
G02Y1487873I-1661J-1458D01*
G03X475274Y1487741I150J-132D01*
G01Y1487121D01*
G02X475072Y1486918I-202J-1D01*
G01X472252D01*
G02X472050Y1487121I1J203D01*
G01Y1487741D01*
G03X472000Y1487873I-200J0D01*
G02Y1490789I1661J1458D01*
G03X472050Y1490921I-150J132D01*
G01Y1492859D01*
G03X472000Y1492991I-200J0D01*
G02Y1495907I1661J1458D01*
G03X472050Y1496039I-150J132D01*
G01Y1496659D01*
G02X472252Y1496862I202J1D01*
G37*
G36*
G01X489575D02*
X492395D01*
G02X492598Y1496659I0J-203D01*
G01Y1496037D01*
G03X492648Y1495905I200J0D01*
G02Y1492993I-1664J-1456D01*
G03X492598Y1492861I150J-132D01*
G01Y1490919D01*
G03X492648Y1490787I200J0D01*
G02Y1487875I-1664J-1456D01*
G03X492598Y1487743I150J-132D01*
G01Y1487121D01*
G02X492395Y1486918I-203J0D01*
G01X489575D01*
G02X489372Y1487121I0J203D01*
G01Y1487743D01*
G03X489322Y1487875I-200J0D01*
G02Y1490787I1664J1456D01*
G03X489372Y1490919I-150J132D01*
G01Y1492861D01*
G03X489322Y1492993I-200J0D01*
G02Y1495905I1664J1456D01*
G03X489372Y1496037I-150J132D01*
G01Y1496659D01*
G02X489575Y1496862I203J0D01*
G37*
G36*
G01X506897D02*
X509717D01*
G02X509920Y1496659I0J-203D01*
G01Y1496037D01*
G03X509970Y1495905I200J0D01*
G02Y1492993I-1664J-1456D01*
G03X509920Y1492861I150J-132D01*
G01Y1490919D01*
G03X509970Y1490787I200J0D01*
G02Y1487875I-1664J-1456D01*
G03X509920Y1487743I150J-132D01*
G01Y1487121D01*
G02X509717Y1486918I-203J0D01*
G01X506897D01*
G02X506694Y1487121I0J203D01*
G01Y1487743D01*
G03X506644Y1487875I-200J0D01*
G02Y1490787I1664J1456D01*
G03X506694Y1490919I-150J132D01*
G01Y1492861D01*
G03X506644Y1492993I-200J0D01*
G02Y1495905I1664J1456D01*
G03X506694Y1496037I-150J132D01*
G01Y1496659D01*
G02X506897Y1496862I203J0D01*
G37*
G36*
G01X645480D02*
X648300D01*
G02X648502Y1496659I-1J-203D01*
G01Y1496039D01*
G03X648552Y1495907I200J0D01*
G02Y1492991I-1661J-1458D01*
G03X648502Y1492859I150J-132D01*
G01Y1490921D01*
G03X648552Y1490789I200J0D01*
G02Y1487873I-1661J-1458D01*
G03X648502Y1487741I150J-132D01*
G01Y1487121D01*
G02X648300Y1486918I-202J-1D01*
G01X645480D01*
G02X645278Y1487121I1J203D01*
G01Y1487741D01*
G03X645228Y1487873I-200J0D01*
G02Y1490789I1661J1458D01*
G03X645278Y1490921I-150J132D01*
G01Y1492859D01*
G03X645228Y1492991I-200J0D01*
G02Y1495907I1661J1458D01*
G03X645278Y1496039I-150J132D01*
G01Y1496659D01*
G02X645480Y1496862I202J1D01*
G37*
G36*
G01X662803D02*
X665623D01*
G02X665826Y1496659I0J-203D01*
G01Y1496037D01*
G03X665876Y1495905I200J0D01*
G02Y1492993I-1664J-1456D01*
G03X665826Y1492861I150J-132D01*
G01Y1490919D01*
G03X665876Y1490787I200J0D01*
G02Y1487875I-1664J-1456D01*
G03X665826Y1487743I150J-132D01*
G01Y1487121D01*
G02X665623Y1486918I-203J0D01*
G01X662803D01*
G02X662600Y1487121I0J203D01*
G01Y1487743D01*
G03X662550Y1487875I-200J0D01*
G02Y1490787I1664J1456D01*
G03X662600Y1490919I-150J132D01*
G01Y1492861D01*
G03X662550Y1492993I-200J0D01*
G02Y1495905I1664J1456D01*
G03X662600Y1496037I-150J132D01*
G01Y1496659D01*
G02X662803Y1496862I203J0D01*
G37*
G36*
G01X680125D02*
X682945D01*
G02X683148Y1496659I0J-203D01*
G01Y1496037D01*
G03X683198Y1495905I200J0D01*
G02Y1492993I-1664J-1456D01*
G03X683148Y1492861I150J-132D01*
G01Y1490919D01*
G03X683198Y1490787I200J0D01*
G02Y1487875I-1664J-1456D01*
G03X683148Y1487743I150J-132D01*
G01Y1487121D01*
G02X682945Y1486918I-203J0D01*
G01X680125D01*
G02X679922Y1487121I0J203D01*
G01Y1487743D01*
G03X679872Y1487875I-200J0D01*
G02Y1490787I1664J1456D01*
G03X679922Y1490919I-150J132D01*
G01Y1492861D01*
G03X679872Y1492993I-200J0D01*
G02Y1495905I1664J1456D01*
G03X679922Y1496037I-150J132D01*
G01Y1496659D01*
G02X680125Y1496862I203J0D01*
G37*
G36*
G01X1165086D02*
X1167906D01*
G02X1168108Y1496659I-1J-203D01*
G01Y1496039D01*
G03X1168158Y1495907I200J0D01*
G02Y1492991I-1661J-1458D01*
G03X1168108Y1492859I150J-132D01*
G01Y1490921D01*
G03X1168158Y1490789I200J0D01*
G02Y1487873I-1661J-1458D01*
G03X1168108Y1487741I150J-132D01*
G01Y1487121D01*
G02X1167906Y1486918I-202J-1D01*
G01X1165086D01*
G02X1164884Y1487121I1J203D01*
G01Y1487741D01*
G03X1164834Y1487873I-200J0D01*
G02Y1490789I1661J1458D01*
G03X1164884Y1490921I-150J132D01*
G01Y1492859D01*
G03X1164834Y1492991I-200J0D01*
G02Y1495907I1661J1458D01*
G03X1164884Y1496039I-150J132D01*
G01Y1496659D01*
G02X1165086Y1496862I202J1D01*
G37*
G36*
G01X1182408D02*
X1185228D01*
G02X1185430Y1496659I-1J-203D01*
G01Y1496039D01*
G03X1185480Y1495907I200J0D01*
G02Y1492991I-1661J-1458D01*
G03X1185430Y1492859I150J-132D01*
G01Y1490921D01*
G03X1185480Y1490789I200J0D01*
G02Y1487873I-1661J-1458D01*
G03X1185430Y1487741I150J-132D01*
G01Y1487121D01*
G02X1185228Y1486918I-202J-1D01*
G01X1182408D01*
G02X1182206Y1487121I1J203D01*
G01Y1487741D01*
G03X1182156Y1487873I-200J0D01*
G02Y1490789I1661J1458D01*
G03X1182206Y1490921I-150J132D01*
G01Y1492859D01*
G03X1182156Y1492991I-200J0D01*
G02Y1495907I1661J1458D01*
G03X1182206Y1496039I-150J132D01*
G01Y1496659D01*
G02X1182408Y1496862I202J1D01*
G37*
G36*
G01X1303669D02*
X1306489D01*
G02X1306692Y1496659I0J-203D01*
G01Y1496037D01*
G03X1306742Y1495905I200J0D01*
G02Y1492993I-1664J-1456D01*
G03X1306692Y1492861I150J-132D01*
G01Y1490919D01*
G03X1306742Y1490787I200J0D01*
G02Y1487875I-1664J-1456D01*
G03X1306692Y1487743I150J-132D01*
G01Y1487121D01*
G02X1306489Y1486918I-203J0D01*
G01X1303669D01*
G02X1303466Y1487121I0J203D01*
G01Y1487743D01*
G03X1303416Y1487875I-200J0D01*
G02Y1490787I1664J1456D01*
G03X1303466Y1490919I-150J132D01*
G01Y1492861D01*
G03X1303416Y1492993I-200J0D01*
G02Y1495905I1664J1456D01*
G03X1303466Y1496037I-150J132D01*
G01Y1496659D01*
G02X1303669Y1496862I203J0D01*
G37*
G36*
G01X1320992D02*
X1323812D01*
G02X1324014Y1496659I-1J-203D01*
G01Y1496039D01*
G03X1324064Y1495907I200J0D01*
G02Y1492991I-1661J-1458D01*
G03X1324014Y1492859I150J-132D01*
G01Y1490921D01*
G03X1324064Y1490789I200J0D01*
G02Y1487873I-1661J-1458D01*
G03X1324014Y1487741I150J-132D01*
G01Y1487121D01*
G02X1323812Y1486918I-202J-1D01*
G01X1320992D01*
G02X1320790Y1487121I1J203D01*
G01Y1487741D01*
G03X1320740Y1487873I-200J0D01*
G02Y1490789I1661J1458D01*
G03X1320790Y1490921I-150J132D01*
G01Y1492859D01*
G03X1320740Y1492991I-200J0D01*
G02Y1495907I1661J1458D01*
G03X1320790Y1496039I-150J132D01*
G01Y1496659D01*
G02X1320992Y1496862I202J1D01*
G37*
G36*
G01X1338315D02*
X1341135D01*
G02X1341338Y1496659I0J-203D01*
G01Y1496037D01*
G03X1341388Y1495905I200J0D01*
G02Y1492993I-1664J-1456D01*
G03X1341338Y1492861I150J-132D01*
G01Y1490919D01*
G03X1341388Y1490787I200J0D01*
G02Y1487875I-1664J-1456D01*
G03X1341338Y1487743I150J-132D01*
G01Y1487121D01*
G02X1341135Y1486918I-203J0D01*
G01X1338315D01*
G02X1338112Y1487121I0J203D01*
G01Y1487743D01*
G03X1338062Y1487875I-200J0D01*
G02Y1490787I1664J1456D01*
G03X1338112Y1490919I-150J132D01*
G01Y1492861D01*
G03X1338062Y1492993I-200J0D01*
G02Y1495905I1664J1456D01*
G03X1338112Y1496037I-150J132D01*
G01Y1496659D01*
G02X1338315Y1496862I203J0D01*
G37*
G36*
G01X1355637D02*
X1358457D01*
G02X1358660Y1496659I0J-203D01*
G01Y1496037D01*
G03X1358710Y1495905I200J0D01*
G02Y1492993I-1664J-1456D01*
G03X1358660Y1492861I150J-132D01*
G01Y1490919D01*
G03X1358710Y1490787I200J0D01*
G02Y1487875I-1664J-1456D01*
G03X1358660Y1487743I150J-132D01*
G01Y1487121D01*
G02X1358457Y1486918I-203J0D01*
G01X1355637D01*
G02X1355434Y1487121I0J203D01*
G01Y1487743D01*
G03X1355384Y1487875I-200J0D01*
G02Y1490787I1664J1456D01*
G03X1355434Y1490919I-150J132D01*
G01Y1492861D01*
G03X1355384Y1492993I-200J0D01*
G02Y1495905I1664J1456D01*
G03X1355434Y1496037I-150J132D01*
G01Y1496659D01*
G02X1355637Y1496862I203J0D01*
G37*
G36*
G01X1476897D02*
X1479717D01*
G02X1479920Y1496659I0J-203D01*
G01Y1496037D01*
G03X1479970Y1495905I200J0D01*
G02Y1492993I-1664J-1456D01*
G03X1479920Y1492861I150J-132D01*
G01Y1490919D01*
G03X1479970Y1490787I200J0D01*
G02Y1487875I-1664J-1456D01*
G03X1479920Y1487743I150J-132D01*
G01Y1487121D01*
G02X1479717Y1486918I-203J0D01*
G01X1476897D01*
G02X1476694Y1487121I0J203D01*
G01Y1487743D01*
G03X1476644Y1487875I-200J0D01*
G02Y1490787I1664J1456D01*
G03X1476694Y1490919I-150J132D01*
G01Y1492861D01*
G03X1476644Y1492993I-200J0D01*
G02Y1495905I1664J1456D01*
G03X1476694Y1496037I-150J132D01*
G01Y1496659D01*
G02X1476897Y1496862I203J0D01*
G37*
G36*
G01X1494220D02*
X1497040D01*
G02X1497242Y1496659I-1J-203D01*
G01Y1496039D01*
G03X1497292Y1495907I200J0D01*
G02Y1492991I-1661J-1458D01*
G03X1497242Y1492859I150J-132D01*
G01Y1490921D01*
G03X1497292Y1490789I200J0D01*
G02Y1487873I-1661J-1458D01*
G03X1497242Y1487741I150J-132D01*
G01Y1487121D01*
G02X1497040Y1486918I-202J-1D01*
G01X1494220D01*
G02X1494018Y1487121I1J203D01*
G01Y1487741D01*
G03X1493968Y1487873I-200J0D01*
G02Y1490789I1661J1458D01*
G03X1494018Y1490921I-150J132D01*
G01Y1492859D01*
G03X1493968Y1492991I-200J0D01*
G02Y1495907I1661J1458D01*
G03X1494018Y1496039I-150J132D01*
G01Y1496659D01*
G02X1494220Y1496862I202J1D01*
G37*
G36*
G01X1511543D02*
X1514363D01*
G02X1514566Y1496659I0J-203D01*
G01Y1496037D01*
G03X1514616Y1495905I200J0D01*
G02Y1492993I-1664J-1456D01*
G03X1514566Y1492861I150J-132D01*
G01Y1490919D01*
G03X1514616Y1490787I200J0D01*
G02Y1487875I-1664J-1456D01*
G03X1514566Y1487743I150J-132D01*
G01Y1487121D01*
G02X1514363Y1486918I-203J0D01*
G01X1511543D01*
G02X1511340Y1487121I0J203D01*
G01Y1487743D01*
G03X1511290Y1487875I-200J0D01*
G02Y1490787I1664J1456D01*
G03X1511340Y1490919I-150J132D01*
G01Y1492861D01*
G03X1511290Y1492993I-200J0D01*
G02Y1495905I1664J1456D01*
G03X1511340Y1496037I-150J132D01*
G01Y1496659D01*
G02X1511543Y1496862I203J0D01*
G37*
G36*
G01X1528865D02*
X1531685D01*
G02X1531888Y1496659I0J-203D01*
G01Y1496037D01*
G03X1531938Y1495905I200J0D01*
G02Y1492993I-1664J-1456D01*
G03X1531888Y1492861I150J-132D01*
G01Y1490919D01*
G03X1531938Y1490787I200J0D01*
G02Y1487875I-1664J-1456D01*
G03X1531888Y1487743I150J-132D01*
G01Y1487121D01*
G02X1531685Y1486918I-203J0D01*
G01X1528865D01*
G02X1528662Y1487121I0J203D01*
G01Y1487743D01*
G03X1528612Y1487875I-200J0D01*
G02Y1490787I1664J1456D01*
G03X1528662Y1490919I-150J132D01*
G01Y1492861D01*
G03X1528612Y1492993I-200J0D01*
G02Y1495905I1664J1456D01*
G03X1528662Y1496037I-150J132D01*
G01Y1496659D01*
G02X1528865Y1496862I203J0D01*
G37*
G36*
G01X1684771D02*
X1687591D01*
G02X1687794Y1496659I0J-203D01*
G01Y1496037D01*
G03X1687844Y1495905I200J0D01*
G02Y1492993I-1664J-1456D01*
G03X1687794Y1492861I150J-132D01*
G01Y1490919D01*
G03X1687844Y1490787I200J0D01*
G02Y1487875I-1664J-1456D01*
G03X1687794Y1487743I150J-132D01*
G01Y1487121D01*
G02X1687591Y1486918I-203J0D01*
G01X1684771D01*
G02X1684568Y1487121I0J203D01*
G01Y1487743D01*
G03X1684518Y1487875I-200J0D01*
G02Y1490787I1664J1456D01*
G03X1684568Y1490919I-150J132D01*
G01Y1492861D01*
G03X1684518Y1492993I-200J0D01*
G02Y1495905I1664J1456D01*
G03X1684568Y1496037I-150J132D01*
G01Y1496659D01*
G02X1684771Y1496862I203J0D01*
G37*
G36*
G01X1702093D02*
X1704913D01*
G02X1705116Y1496659I0J-203D01*
G01Y1496037D01*
G03X1705166Y1495905I200J0D01*
G02Y1492993I-1664J-1456D01*
G03X1705116Y1492861I150J-132D01*
G01Y1490919D01*
G03X1705166Y1490787I200J0D01*
G02Y1487875I-1664J-1456D01*
G03X1705116Y1487743I150J-132D01*
G01Y1487121D01*
G02X1704913Y1486918I-203J0D01*
G01X1702093D01*
G02X1701890Y1487121I0J203D01*
G01Y1487743D01*
G03X1701840Y1487875I-200J0D01*
G02Y1490787I1664J1456D01*
G03X1701890Y1490919I-150J132D01*
G01Y1492861D01*
G03X1701840Y1492993I-200J0D01*
G02Y1495905I1664J1456D01*
G03X1701890Y1496037I-150J132D01*
G01Y1496659D01*
G02X1702093Y1496862I203J0D01*
G37*
G36*
G01X134456Y1501192D02*
X137276D01*
G02X137478Y1500989I-1J-203D01*
G01Y1500370D01*
G03X137528Y1500238I200J0D01*
G02Y1497322I-1661J-1458D01*
G03X137478Y1497190I150J-132D01*
G01Y1495252D01*
G03X137528Y1495120I200J0D01*
G02Y1492204I-1661J-1458D01*
G03X137478Y1492072I150J-132D01*
G01Y1491451D01*
G02X137276Y1491248I-202J-1D01*
G01X134456D01*
G02X134254Y1491451I1J203D01*
G01Y1492072D01*
G03X134204Y1492204I-200J0D01*
G02Y1495120I1661J1458D01*
G03X134254Y1495252I-150J132D01*
G01Y1497190D01*
G03X134204Y1497322I-200J0D01*
G02Y1500238I1661J1458D01*
G03X134254Y1500370I-150J132D01*
G01Y1500989D01*
G02X134456Y1501192I202J1D01*
G37*
G36*
G01X151779D02*
X154599D01*
G02X154802Y1500989I0J-203D01*
G01Y1500368D01*
G03X154852Y1500236I200J0D01*
G02Y1497324I-1664J-1456D01*
G03X154802Y1497192I150J-132D01*
G01Y1495250D01*
G03X154852Y1495118I200J0D01*
G02Y1492206I-1664J-1456D01*
G03X154802Y1492074I150J-132D01*
G01Y1491451D01*
G02X154599Y1491248I-203J0D01*
G01X151779D01*
G02X151576Y1491451I0J203D01*
G01Y1492074D01*
G03X151526Y1492206I-200J0D01*
G02Y1495118I1664J1456D01*
G03X151576Y1495250I-150J132D01*
G01Y1497192D01*
G03X151526Y1497324I-200J0D01*
G02Y1500236I1664J1456D01*
G03X151576Y1500368I-150J132D01*
G01Y1500989D01*
G02X151779Y1501192I203J0D01*
G37*
G36*
G01X169102D02*
X171922D01*
G02X172124Y1500989I-1J-203D01*
G01Y1500370D01*
G03X172174Y1500238I200J0D01*
G02Y1497322I-1661J-1458D01*
G03X172124Y1497190I150J-132D01*
G01Y1495252D01*
G03X172174Y1495120I200J0D01*
G02Y1492204I-1661J-1458D01*
G03X172124Y1492072I150J-132D01*
G01Y1491451D01*
G02X171922Y1491248I-202J-1D01*
G01X169102D01*
G02X168900Y1491451I1J203D01*
G01Y1492072D01*
G03X168850Y1492204I-200J0D01*
G02Y1495120I1661J1458D01*
G03X168900Y1495252I-150J132D01*
G01Y1497190D01*
G03X168850Y1497322I-200J0D01*
G02Y1500238I1661J1458D01*
G03X168900Y1500370I-150J132D01*
G01Y1500989D01*
G02X169102Y1501192I202J1D01*
G37*
G36*
G01X290361D02*
X293181D01*
G02X293384Y1500989I0J-203D01*
G01Y1500368D01*
G03X293434Y1500236I200J0D01*
G02Y1497324I-1664J-1456D01*
G03X293384Y1497192I150J-132D01*
G01Y1495250D01*
G03X293434Y1495118I200J0D01*
G02Y1492206I-1664J-1456D01*
G03X293384Y1492074I150J-132D01*
G01Y1491451D01*
G02X293181Y1491248I-203J0D01*
G01X290361D01*
G02X290158Y1491451I0J203D01*
G01Y1492074D01*
G03X290108Y1492206I-200J0D01*
G02Y1495118I1664J1456D01*
G03X290158Y1495250I-150J132D01*
G01Y1497192D01*
G03X290108Y1497324I-200J0D01*
G02Y1500236I1664J1456D01*
G03X290158Y1500368I-150J132D01*
G01Y1500989D01*
G02X290361Y1501192I203J0D01*
G37*
G36*
G01X463590D02*
X466410D01*
G02X466612Y1500989I-1J-203D01*
G01Y1500370D01*
G03X466662Y1500238I200J0D01*
G02Y1497322I-1661J-1458D01*
G03X466612Y1497190I150J-132D01*
G01Y1495252D01*
G03X466662Y1495120I200J0D01*
G02Y1492204I-1661J-1458D01*
G03X466612Y1492072I150J-132D01*
G01Y1491451D01*
G02X466410Y1491248I-202J-1D01*
G01X463590D01*
G02X463388Y1491451I1J203D01*
G01Y1492072D01*
G03X463338Y1492204I-200J0D01*
G02Y1495120I1661J1458D01*
G03X463388Y1495252I-150J132D01*
G01Y1497190D01*
G03X463338Y1497322I-200J0D01*
G02Y1500238I1661J1458D01*
G03X463388Y1500370I-150J132D01*
G01Y1500989D01*
G02X463590Y1501192I202J1D01*
G37*
G36*
G01X480913D02*
X483733D01*
G02X483936Y1500989I0J-203D01*
G01Y1500368D01*
G03X483986Y1500236I200J0D01*
G02Y1497324I-1664J-1456D01*
G03X483936Y1497192I150J-132D01*
G01Y1495250D01*
G03X483986Y1495118I200J0D01*
G02Y1492206I-1664J-1456D01*
G03X483936Y1492074I150J-132D01*
G01Y1491451D01*
G02X483733Y1491248I-203J0D01*
G01X480913D01*
G02X480710Y1491451I0J203D01*
G01Y1492074D01*
G03X480660Y1492206I-200J0D01*
G02Y1495118I1664J1456D01*
G03X480710Y1495250I-150J132D01*
G01Y1497192D01*
G03X480660Y1497324I-200J0D01*
G02Y1500236I1664J1456D01*
G03X480710Y1500368I-150J132D01*
G01Y1500989D01*
G02X480913Y1501192I203J0D01*
G37*
G36*
G01X498236D02*
X501056D01*
G02X501258Y1500989I-1J-203D01*
G01Y1500370D01*
G03X501308Y1500238I200J0D01*
G02Y1497322I-1661J-1458D01*
G03X501258Y1497190I150J-132D01*
G01Y1495252D01*
G03X501308Y1495120I200J0D01*
G02Y1492204I-1661J-1458D01*
G03X501258Y1492072I150J-132D01*
G01Y1491451D01*
G02X501056Y1491248I-202J-1D01*
G01X498236D01*
G02X498034Y1491451I1J203D01*
G01Y1492072D01*
G03X497984Y1492204I-200J0D01*
G02Y1495120I1661J1458D01*
G03X498034Y1495252I-150J132D01*
G01Y1497190D01*
G03X497984Y1497322I-200J0D01*
G02Y1500238I1661J1458D01*
G03X498034Y1500370I-150J132D01*
G01Y1500989D01*
G02X498236Y1501192I202J1D01*
G37*
G36*
G01X515559D02*
X518379D01*
G02X518582Y1500989I0J-203D01*
G01Y1500368D01*
G03X518632Y1500236I200J0D01*
G02Y1497324I-1664J-1456D01*
G03X518582Y1497192I150J-132D01*
G01Y1495250D01*
G03X518632Y1495118I200J0D01*
G02Y1492206I-1664J-1456D01*
G03X518582Y1492074I150J-132D01*
G01Y1491451D01*
G02X518379Y1491248I-203J0D01*
G01X515559D01*
G02X515356Y1491451I0J203D01*
G01Y1492074D01*
G03X515306Y1492206I-200J0D01*
G02Y1495118I1664J1456D01*
G03X515356Y1495250I-150J132D01*
G01Y1497192D01*
G03X515306Y1497324I-200J0D01*
G02Y1500236I1664J1456D01*
G03X515356Y1500368I-150J132D01*
G01Y1500989D01*
G02X515559Y1501192I203J0D01*
G37*
G36*
G01X654141D02*
X656961D01*
G02X657164Y1500989I0J-203D01*
G01Y1500368D01*
G03X657214Y1500236I200J0D01*
G02Y1497324I-1664J-1456D01*
G03X657164Y1497192I150J-132D01*
G01Y1495250D01*
G03X657214Y1495118I200J0D01*
G02Y1492206I-1664J-1456D01*
G03X657164Y1492074I150J-132D01*
G01Y1491451D01*
G02X656961Y1491248I-203J0D01*
G01X654141D01*
G02X653938Y1491451I0J203D01*
G01Y1492074D01*
G03X653888Y1492206I-200J0D01*
G02Y1495118I1664J1456D01*
G03X653938Y1495250I-150J132D01*
G01Y1497192D01*
G03X653888Y1497324I-200J0D01*
G02Y1500236I1664J1456D01*
G03X653938Y1500368I-150J132D01*
G01Y1500989D01*
G02X654141Y1501192I203J0D01*
G37*
G36*
G01X671464D02*
X674284D01*
G02X674486Y1500989I-1J-203D01*
G01Y1500370D01*
G03X674536Y1500238I200J0D01*
G02Y1497322I-1661J-1458D01*
G03X674486Y1497190I150J-132D01*
G01Y1495252D01*
G03X674536Y1495120I200J0D01*
G02Y1492204I-1661J-1458D01*
G03X674486Y1492072I150J-132D01*
G01Y1491451D01*
G02X674284Y1491248I-202J-1D01*
G01X671464D01*
G02X671262Y1491451I1J203D01*
G01Y1492072D01*
G03X671212Y1492204I-200J0D01*
G02Y1495120I1661J1458D01*
G03X671262Y1495252I-150J132D01*
G01Y1497190D01*
G03X671212Y1497322I-200J0D01*
G02Y1500238I1661J1458D01*
G03X671262Y1500370I-150J132D01*
G01Y1500989D01*
G02X671464Y1501192I202J1D01*
G37*
G36*
G01X688787D02*
X691607D01*
G02X691810Y1500989I0J-203D01*
G01Y1500368D01*
G03X691860Y1500236I200J0D01*
G02Y1497324I-1664J-1456D01*
G03X691810Y1497192I150J-132D01*
G01Y1495250D01*
G03X691860Y1495118I200J0D01*
G02Y1492206I-1664J-1456D01*
G03X691810Y1492074I150J-132D01*
G01Y1491451D01*
G02X691607Y1491248I-203J0D01*
G01X688787D01*
G02X688584Y1491451I0J203D01*
G01Y1492074D01*
G03X688534Y1492206I-200J0D01*
G02Y1495118I1664J1456D01*
G03X688584Y1495250I-150J132D01*
G01Y1497192D01*
G03X688534Y1497324I-200J0D01*
G02Y1500236I1664J1456D01*
G03X688584Y1500368I-150J132D01*
G01Y1500989D01*
G02X688787Y1501192I203J0D01*
G37*
G36*
G01X1173747D02*
X1176567D01*
G02X1176770Y1500989I0J-203D01*
G01Y1500368D01*
G03X1176820Y1500236I200J0D01*
G02Y1497324I-1664J-1456D01*
G03X1176770Y1497192I150J-132D01*
G01Y1495250D01*
G03X1176820Y1495118I200J0D01*
G02Y1492206I-1664J-1456D01*
G03X1176770Y1492074I150J-132D01*
G01Y1491451D01*
G02X1176567Y1491248I-203J0D01*
G01X1173747D01*
G02X1173544Y1491451I0J203D01*
G01Y1492074D01*
G03X1173494Y1492206I-200J0D01*
G02Y1495118I1664J1456D01*
G03X1173544Y1495250I-150J132D01*
G01Y1497192D01*
G03X1173494Y1497324I-200J0D01*
G02Y1500236I1664J1456D01*
G03X1173544Y1500368I-150J132D01*
G01Y1500989D01*
G02X1173747Y1501192I203J0D01*
G37*
G36*
G01X1191070D02*
X1193890D01*
G02X1194092Y1500989I-1J-203D01*
G01Y1500370D01*
G03X1194142Y1500238I200J0D01*
G02Y1497322I-1661J-1458D01*
G03X1194092Y1497190I150J-132D01*
G01Y1495252D01*
G03X1194142Y1495120I200J0D01*
G02Y1492204I-1661J-1458D01*
G03X1194092Y1492072I150J-132D01*
G01Y1491451D01*
G02X1193890Y1491248I-202J-1D01*
G01X1191070D01*
G02X1190868Y1491451I1J203D01*
G01Y1492072D01*
G03X1190818Y1492204I-200J0D01*
G02Y1495120I1661J1458D01*
G03X1190868Y1495252I-150J132D01*
G01Y1497190D01*
G03X1190818Y1497322I-200J0D01*
G02Y1500238I1661J1458D01*
G03X1190868Y1500370I-150J132D01*
G01Y1500989D01*
G02X1191070Y1501192I202J1D01*
G37*
G36*
G01X1312330D02*
X1315150D01*
G02X1315352Y1500989I-1J-203D01*
G01Y1500370D01*
G03X1315402Y1500238I200J0D01*
G02Y1497322I-1661J-1458D01*
G03X1315352Y1497190I150J-132D01*
G01Y1495252D01*
G03X1315402Y1495120I200J0D01*
G02Y1492204I-1661J-1458D01*
G03X1315352Y1492072I150J-132D01*
G01Y1491451D01*
G02X1315150Y1491248I-202J-1D01*
G01X1312330D01*
G02X1312128Y1491451I1J203D01*
G01Y1492072D01*
G03X1312078Y1492204I-200J0D01*
G02Y1495120I1661J1458D01*
G03X1312128Y1495252I-150J132D01*
G01Y1497190D01*
G03X1312078Y1497322I-200J0D01*
G02Y1500238I1661J1458D01*
G03X1312128Y1500370I-150J132D01*
G01Y1500989D01*
G02X1312330Y1501192I202J1D01*
G37*
G36*
G01X1329653D02*
X1332473D01*
G02X1332676Y1500989I0J-203D01*
G01Y1500368D01*
G03X1332726Y1500236I200J0D01*
G02Y1497324I-1664J-1456D01*
G03X1332676Y1497192I150J-132D01*
G01Y1495250D01*
G03X1332726Y1495118I200J0D01*
G02Y1492206I-1664J-1456D01*
G03X1332676Y1492074I150J-132D01*
G01Y1491451D01*
G02X1332473Y1491248I-203J0D01*
G01X1329653D01*
G02X1329450Y1491451I0J203D01*
G01Y1492074D01*
G03X1329400Y1492206I-200J0D01*
G02Y1495118I1664J1456D01*
G03X1329450Y1495250I-150J132D01*
G01Y1497192D01*
G03X1329400Y1497324I-200J0D01*
G02Y1500236I1664J1456D01*
G03X1329450Y1500368I-150J132D01*
G01Y1500989D01*
G02X1329653Y1501192I203J0D01*
G37*
G36*
G01X1346976D02*
X1349796D01*
G02X1349998Y1500989I-1J-203D01*
G01Y1500370D01*
G03X1350048Y1500238I200J0D01*
G02Y1497322I-1661J-1458D01*
G03X1349998Y1497190I150J-132D01*
G01Y1495252D01*
G03X1350048Y1495120I200J0D01*
G02Y1492204I-1661J-1458D01*
G03X1349998Y1492072I150J-132D01*
G01Y1491451D01*
G02X1349796Y1491248I-202J-1D01*
G01X1346976D01*
G02X1346774Y1491451I1J203D01*
G01Y1492072D01*
G03X1346724Y1492204I-200J0D01*
G02Y1495120I1661J1458D01*
G03X1346774Y1495252I-150J132D01*
G01Y1497190D01*
G03X1346724Y1497322I-200J0D01*
G02Y1500238I1661J1458D01*
G03X1346774Y1500370I-150J132D01*
G01Y1500989D01*
G02X1346976Y1501192I202J1D01*
G37*
G36*
G01X1364299D02*
X1367119D01*
G02X1367322Y1500989I0J-203D01*
G01Y1500368D01*
G03X1367372Y1500236I200J0D01*
G02Y1497324I-1664J-1456D01*
G03X1367322Y1497192I150J-132D01*
G01Y1495250D01*
G03X1367372Y1495118I200J0D01*
G02Y1492206I-1664J-1456D01*
G03X1367322Y1492074I150J-132D01*
G01Y1491451D01*
G02X1367119Y1491248I-203J0D01*
G01X1364299D01*
G02X1364096Y1491451I0J203D01*
G01Y1492074D01*
G03X1364046Y1492206I-200J0D01*
G02Y1495118I1664J1456D01*
G03X1364096Y1495250I-150J132D01*
G01Y1497192D01*
G03X1364046Y1497324I-200J0D01*
G02Y1500236I1664J1456D01*
G03X1364096Y1500368I-150J132D01*
G01Y1500989D01*
G02X1364299Y1501192I203J0D01*
G37*
G36*
G01X1485558D02*
X1488378D01*
G02X1488580Y1500989I-1J-203D01*
G01Y1500370D01*
G03X1488630Y1500238I200J0D01*
G02Y1497322I-1661J-1458D01*
G03X1488580Y1497190I150J-132D01*
G01Y1495252D01*
G03X1488630Y1495120I200J0D01*
G02Y1492204I-1661J-1458D01*
G03X1488580Y1492072I150J-132D01*
G01Y1491451D01*
G02X1488378Y1491248I-202J-1D01*
G01X1485558D01*
G02X1485356Y1491451I1J203D01*
G01Y1492072D01*
G03X1485306Y1492204I-200J0D01*
G02Y1495120I1661J1458D01*
G03X1485356Y1495252I-150J132D01*
G01Y1497190D01*
G03X1485306Y1497322I-200J0D01*
G02Y1500238I1661J1458D01*
G03X1485356Y1500370I-150J132D01*
G01Y1500989D01*
G02X1485558Y1501192I202J1D01*
G37*
G36*
G01X1502881D02*
X1505701D01*
G02X1505904Y1500989I0J-203D01*
G01Y1500368D01*
G03X1505954Y1500236I200J0D01*
G02Y1497324I-1664J-1456D01*
G03X1505904Y1497192I150J-132D01*
G01Y1495250D01*
G03X1505954Y1495118I200J0D01*
G02Y1492206I-1664J-1456D01*
G03X1505904Y1492074I150J-132D01*
G01Y1491451D01*
G02X1505701Y1491248I-203J0D01*
G01X1502881D01*
G02X1502678Y1491451I0J203D01*
G01Y1492074D01*
G03X1502628Y1492206I-200J0D01*
G02Y1495118I1664J1456D01*
G03X1502678Y1495250I-150J132D01*
G01Y1497192D01*
G03X1502628Y1497324I-200J0D01*
G02Y1500236I1664J1456D01*
G03X1502678Y1500368I-150J132D01*
G01Y1500989D01*
G02X1502881Y1501192I203J0D01*
G37*
G36*
G01X1520204D02*
X1523024D01*
G02X1523226Y1500989I-1J-203D01*
G01Y1500370D01*
G03X1523276Y1500238I200J0D01*
G02Y1497322I-1661J-1458D01*
G03X1523226Y1497190I150J-132D01*
G01Y1495252D01*
G03X1523276Y1495120I200J0D01*
G02Y1492204I-1661J-1458D01*
G03X1523226Y1492072I150J-132D01*
G01Y1491451D01*
G02X1523024Y1491248I-202J-1D01*
G01X1520204D01*
G02X1520002Y1491451I1J203D01*
G01Y1492072D01*
G03X1519952Y1492204I-200J0D01*
G02Y1495120I1661J1458D01*
G03X1520002Y1495252I-150J132D01*
G01Y1497190D01*
G03X1519952Y1497322I-200J0D01*
G02Y1500238I1661J1458D01*
G03X1520002Y1500370I-150J132D01*
G01Y1500989D01*
G02X1520204Y1501192I202J1D01*
G37*
G36*
G01X1537527D02*
X1540347D01*
G02X1540550Y1500989I0J-203D01*
G01Y1500368D01*
G03X1540600Y1500236I200J0D01*
G02Y1497324I-1664J-1456D01*
G03X1540550Y1497192I150J-132D01*
G01Y1495250D01*
G03X1540600Y1495118I200J0D01*
G02Y1492206I-1664J-1456D01*
G03X1540550Y1492074I150J-132D01*
G01Y1491451D01*
G02X1540347Y1491248I-203J0D01*
G01X1537527D01*
G02X1537324Y1491451I0J203D01*
G01Y1492074D01*
G03X1537274Y1492206I-200J0D01*
G02Y1495118I1664J1456D01*
G03X1537324Y1495250I-150J132D01*
G01Y1497192D01*
G03X1537274Y1497324I-200J0D01*
G02Y1500236I1664J1456D01*
G03X1537324Y1500368I-150J132D01*
G01Y1500989D01*
G02X1537527Y1501192I203J0D01*
G37*
G36*
G01X1693432D02*
X1696252D01*
G02X1696454Y1500989I-1J-203D01*
G01Y1500370D01*
G03X1696504Y1500238I200J0D01*
G02Y1497322I-1661J-1458D01*
G03X1696454Y1497190I150J-132D01*
G01Y1495252D01*
G03X1696504Y1495120I200J0D01*
G02Y1492204I-1661J-1458D01*
G03X1696454Y1492072I150J-132D01*
G01Y1491451D01*
G02X1696252Y1491248I-202J-1D01*
G01X1693432D01*
G02X1693230Y1491451I1J203D01*
G01Y1492072D01*
G03X1693180Y1492204I-200J0D01*
G02Y1495120I1661J1458D01*
G03X1693230Y1495252I-150J132D01*
G01Y1497190D01*
G03X1693180Y1497322I-200J0D01*
G02Y1500238I1661J1458D01*
G03X1693230Y1500370I-150J132D01*
G01Y1500989D01*
G02X1693432Y1501192I202J1D01*
G37*
G36*
G01X1710755D02*
X1713575D01*
G02X1713778Y1500989I0J-203D01*
G01Y1500368D01*
G03X1713828Y1500236I200J0D01*
G02Y1497324I-1664J-1456D01*
G03X1713778Y1497192I150J-132D01*
G01Y1495250D01*
G03X1713828Y1495118I200J0D01*
G02Y1492206I-1664J-1456D01*
G03X1713778Y1492074I150J-132D01*
G01Y1491451D01*
G02X1713575Y1491248I-203J0D01*
G01X1710755D01*
G02X1710552Y1491451I0J203D01*
G01Y1492074D01*
G03X1710502Y1492206I-200J0D01*
G02Y1495118I1664J1456D01*
G03X1710552Y1495250I-150J132D01*
G01Y1497192D01*
G03X1710502Y1497324I-200J0D01*
G02Y1500236I1664J1456D01*
G03X1710552Y1500368I-150J132D01*
G01Y1500989D01*
G02X1710755Y1501192I203J0D01*
G37*
G36*
G01X143118Y1512216D02*
X145938D01*
G02X146140Y1512014I0J-202D01*
G01Y1511394D01*
G03X146190Y1511262I200J0D01*
G02Y1508346I-1661J-1458D01*
G03X146140Y1508214I150J-132D01*
G01Y1506275D01*
G03X146190Y1506143I200J0D01*
G02Y1503227I-1661J-1458D01*
G03X146140Y1503095I150J-132D01*
G01Y1502476D01*
G02X145938Y1502274I-202J0D01*
G01X143118D01*
G02X142916Y1502476I0J202D01*
G01Y1503095D01*
G03X142866Y1503227I-200J0D01*
G02Y1506143I1661J1458D01*
G03X142916Y1506275I-150J132D01*
G01Y1508214D01*
G03X142866Y1508346I-200J0D01*
G02Y1511262I1661J1458D01*
G03X142916Y1511394I-150J132D01*
G01Y1512014D01*
G02X143118Y1512216I202J0D01*
G37*
G36*
G01X160440D02*
X163260D01*
G02X163462Y1512014I0J-202D01*
G01Y1511394D01*
G03X163512Y1511262I200J0D01*
G02Y1508346I-1661J-1458D01*
G03X163462Y1508214I150J-132D01*
G01Y1506275D01*
G03X163512Y1506143I200J0D01*
G02Y1503227I-1661J-1458D01*
G03X163462Y1503095I150J-132D01*
G01Y1502476D01*
G02X163260Y1502274I-202J0D01*
G01X160440D01*
G02X160238Y1502476I0J202D01*
G01Y1503095D01*
G03X160188Y1503227I-200J0D01*
G02Y1506143I1661J1458D01*
G03X160238Y1506275I-150J132D01*
G01Y1508214D01*
G03X160188Y1508346I-200J0D01*
G02Y1511262I1661J1458D01*
G03X160238Y1511394I-150J132D01*
G01Y1512014D01*
G02X160440Y1512216I202J0D01*
G37*
G36*
G01X281700D02*
X284520D01*
G02X284722Y1512014I0J-202D01*
G01Y1511394D01*
G03X284772Y1511262I200J0D01*
G02Y1508346I-1661J-1458D01*
G03X284722Y1508214I150J-132D01*
G01Y1506275D01*
G03X284772Y1506143I200J0D01*
G02Y1503227I-1661J-1458D01*
G03X284722Y1503095I150J-132D01*
G01Y1502476D01*
G02X284520Y1502274I-202J0D01*
G01X281700D01*
G02X281498Y1502476I0J202D01*
G01Y1503095D01*
G03X281448Y1503227I-200J0D01*
G02Y1506143I1661J1458D01*
G03X281498Y1506275I-150J132D01*
G01Y1508214D01*
G03X281448Y1508346I-200J0D01*
G02Y1511262I1661J1458D01*
G03X281498Y1511394I-150J132D01*
G01Y1512014D01*
G02X281700Y1512216I202J0D01*
G37*
G36*
G01X472252D02*
X475072D01*
G02X475274Y1512014I0J-202D01*
G01Y1511394D01*
G03X475324Y1511262I200J0D01*
G02Y1508346I-1661J-1458D01*
G03X475274Y1508214I150J-132D01*
G01Y1506275D01*
G03X475324Y1506143I200J0D01*
G02Y1503227I-1661J-1458D01*
G03X475274Y1503095I150J-132D01*
G01Y1502476D01*
G02X475072Y1502274I-202J0D01*
G01X472252D01*
G02X472050Y1502476I0J202D01*
G01Y1503095D01*
G03X472000Y1503227I-200J0D01*
G02Y1506143I1661J1458D01*
G03X472050Y1506275I-150J132D01*
G01Y1508214D01*
G03X472000Y1508346I-200J0D01*
G02Y1511262I1661J1458D01*
G03X472050Y1511394I-150J132D01*
G01Y1512014D01*
G02X472252Y1512216I202J0D01*
G37*
G36*
G01X645480D02*
X648300D01*
G02X648502Y1512014I0J-202D01*
G01Y1511394D01*
G03X648552Y1511262I200J0D01*
G02Y1508346I-1661J-1458D01*
G03X648502Y1508214I150J-132D01*
G01Y1506275D01*
G03X648552Y1506143I200J0D01*
G02Y1503227I-1661J-1458D01*
G03X648502Y1503095I150J-132D01*
G01Y1502476D01*
G02X648300Y1502274I-202J0D01*
G01X645480D01*
G02X645278Y1502476I0J202D01*
G01Y1503095D01*
G03X645228Y1503227I-200J0D01*
G02Y1506143I1661J1458D01*
G03X645278Y1506275I-150J132D01*
G01Y1508214D01*
G03X645228Y1508346I-200J0D01*
G02Y1511262I1661J1458D01*
G03X645278Y1511394I-150J132D01*
G01Y1512014D01*
G02X645480Y1512216I202J0D01*
G37*
G36*
G01X1165086D02*
X1167906D01*
G02X1168108Y1512014I0J-202D01*
G01Y1511394D01*
G03X1168158Y1511262I200J0D01*
G02Y1508346I-1661J-1458D01*
G03X1168108Y1508214I150J-132D01*
G01Y1506275D01*
G03X1168158Y1506143I200J0D01*
G02Y1503227I-1661J-1458D01*
G03X1168108Y1503095I150J-132D01*
G01Y1502476D01*
G02X1167906Y1502274I-202J0D01*
G01X1165086D01*
G02X1164884Y1502476I0J202D01*
G01Y1503095D01*
G03X1164834Y1503227I-200J0D01*
G02Y1506143I1661J1458D01*
G03X1164884Y1506275I-150J132D01*
G01Y1508214D01*
G03X1164834Y1508346I-200J0D01*
G02Y1511262I1661J1458D01*
G03X1164884Y1511394I-150J132D01*
G01Y1512014D01*
G02X1165086Y1512216I202J0D01*
G37*
G36*
G01X1182408D02*
X1185228D01*
G02X1185430Y1512014I0J-202D01*
G01Y1511394D01*
G03X1185480Y1511262I200J0D01*
G02Y1508346I-1661J-1458D01*
G03X1185430Y1508214I150J-132D01*
G01Y1506275D01*
G03X1185480Y1506143I200J0D01*
G02Y1503227I-1661J-1458D01*
G03X1185430Y1503095I150J-132D01*
G01Y1502476D01*
G02X1185228Y1502274I-202J0D01*
G01X1182408D01*
G02X1182206Y1502476I0J202D01*
G01Y1503095D01*
G03X1182156Y1503227I-200J0D01*
G02Y1506143I1661J1458D01*
G03X1182206Y1506275I-150J132D01*
G01Y1508214D01*
G03X1182156Y1508346I-200J0D01*
G02Y1511262I1661J1458D01*
G03X1182206Y1511394I-150J132D01*
G01Y1512014D01*
G02X1182408Y1512216I202J0D01*
G37*
G36*
G01X1320992D02*
X1323812D01*
G02X1324014Y1512014I0J-202D01*
G01Y1511394D01*
G03X1324064Y1511262I200J0D01*
G02Y1508346I-1661J-1458D01*
G03X1324014Y1508214I150J-132D01*
G01Y1506275D01*
G03X1324064Y1506143I200J0D01*
G02Y1503227I-1661J-1458D01*
G03X1324014Y1503095I150J-132D01*
G01Y1502476D01*
G02X1323812Y1502274I-202J0D01*
G01X1320992D01*
G02X1320790Y1502476I0J202D01*
G01Y1503095D01*
G03X1320740Y1503227I-200J0D01*
G02Y1506143I1661J1458D01*
G03X1320790Y1506275I-150J132D01*
G01Y1508214D01*
G03X1320740Y1508346I-200J0D01*
G02Y1511262I1661J1458D01*
G03X1320790Y1511394I-150J132D01*
G01Y1512014D01*
G02X1320992Y1512216I202J0D01*
G37*
G36*
G01X1494220D02*
X1497040D01*
G02X1497242Y1512014I0J-202D01*
G01Y1511394D01*
G03X1497292Y1511262I200J0D01*
G02Y1508346I-1661J-1458D01*
G03X1497242Y1508214I150J-132D01*
G01Y1506275D01*
G03X1497292Y1506143I200J0D01*
G02Y1503227I-1661J-1458D01*
G03X1497242Y1503095I150J-132D01*
G01Y1502476D01*
G02X1497040Y1502274I-202J0D01*
G01X1494220D01*
G02X1494018Y1502476I0J202D01*
G01Y1503095D01*
G03X1493968Y1503227I-200J0D01*
G02Y1506143I1661J1458D01*
G03X1494018Y1506275I-150J132D01*
G01Y1508214D01*
G03X1493968Y1508346I-200J0D01*
G02Y1511262I1661J1458D01*
G03X1494018Y1511394I-150J132D01*
G01Y1512014D01*
G02X1494220Y1512216I202J0D01*
G37*
G36*
G01X125795D02*
X128615D01*
G02X128818Y1512014I1J-202D01*
G01Y1511392D01*
G03X128868Y1511260I200J0D01*
G02Y1508348I-1664J-1456D01*
G03X128818Y1508216I150J-132D01*
G01Y1506273D01*
G03X128868Y1506141I200J0D01*
G02Y1503229I-1664J-1456D01*
G03X128818Y1503097I150J-132D01*
G01Y1502476D01*
G02X128615Y1502274I-203J1D01*
G01X125795D01*
G02X125592Y1502476I-1J202D01*
G01Y1503097D01*
G03X125542Y1503229I-200J0D01*
G02Y1506141I1664J1456D01*
G03X125592Y1506273I-150J132D01*
G01Y1508216D01*
G03X125542Y1508348I-200J0D01*
G02Y1511260I1664J1456D01*
G03X125592Y1511392I-150J132D01*
G01Y1512014D01*
G02X125795Y1512216I203J-1D01*
G37*
G36*
G01X299023D02*
X301843D01*
G02X302046Y1512014I1J-202D01*
G01Y1511392D01*
G03X302096Y1511260I200J0D01*
G02Y1508348I-1664J-1456D01*
G03X302046Y1508216I150J-132D01*
G01Y1506273D01*
G03X302096Y1506141I200J0D01*
G02Y1503229I-1664J-1456D01*
G03X302046Y1503097I150J-132D01*
G01Y1502476D01*
G02X301843Y1502274I-203J1D01*
G01X299023D01*
G02X298820Y1502476I-1J202D01*
G01Y1503097D01*
G03X298770Y1503229I-200J0D01*
G02Y1506141I1664J1456D01*
G03X298820Y1506273I-150J132D01*
G01Y1508216D01*
G03X298770Y1508348I-200J0D01*
G02Y1511260I1664J1456D01*
G03X298820Y1511392I-150J132D01*
G01Y1512014D01*
G02X299023Y1512216I203J-1D01*
G37*
G36*
G01X454929D02*
X457749D01*
G02X457952Y1512014I1J-202D01*
G01Y1511392D01*
G03X458002Y1511260I200J0D01*
G02Y1508348I-1664J-1456D01*
G03X457952Y1508216I150J-132D01*
G01Y1506273D01*
G03X458002Y1506141I200J0D01*
G02Y1503229I-1664J-1456D01*
G03X457952Y1503097I150J-132D01*
G01Y1502476D01*
G02X457749Y1502274I-203J1D01*
G01X454929D01*
G02X454726Y1502476I-1J202D01*
G01Y1503097D01*
G03X454676Y1503229I-200J0D01*
G02Y1506141I1664J1456D01*
G03X454726Y1506273I-150J132D01*
G01Y1508216D01*
G03X454676Y1508348I-200J0D01*
G02Y1511260I1664J1456D01*
G03X454726Y1511392I-150J132D01*
G01Y1512014D01*
G02X454929Y1512216I203J-1D01*
G37*
G36*
G01X489575D02*
X492395D01*
G02X492598Y1512014I1J-202D01*
G01Y1511392D01*
G03X492648Y1511260I200J0D01*
G02Y1508348I-1664J-1456D01*
G03X492598Y1508216I150J-132D01*
G01Y1506273D01*
G03X492648Y1506141I200J0D01*
G02Y1503229I-1664J-1456D01*
G03X492598Y1503097I150J-132D01*
G01Y1502476D01*
G02X492395Y1502274I-203J1D01*
G01X489575D01*
G02X489372Y1502476I-1J202D01*
G01Y1503097D01*
G03X489322Y1503229I-200J0D01*
G02Y1506141I1664J1456D01*
G03X489372Y1506273I-150J132D01*
G01Y1508216D01*
G03X489322Y1508348I-200J0D01*
G02Y1511260I1664J1456D01*
G03X489372Y1511392I-150J132D01*
G01Y1512014D01*
G02X489575Y1512216I203J-1D01*
G37*
G36*
G01X506897D02*
X509717D01*
G02X509920Y1512014I1J-202D01*
G01Y1511392D01*
G03X509970Y1511260I200J0D01*
G02Y1508348I-1664J-1456D01*
G03X509920Y1508216I150J-132D01*
G01Y1506273D01*
G03X509970Y1506141I200J0D01*
G02Y1503229I-1664J-1456D01*
G03X509920Y1503097I150J-132D01*
G01Y1502476D01*
G02X509717Y1502274I-203J1D01*
G01X506897D01*
G02X506694Y1502476I-1J202D01*
G01Y1503097D01*
G03X506644Y1503229I-200J0D01*
G02Y1506141I1664J1456D01*
G03X506694Y1506273I-150J132D01*
G01Y1508216D01*
G03X506644Y1508348I-200J0D01*
G02Y1511260I1664J1456D01*
G03X506694Y1511392I-150J132D01*
G01Y1512014D01*
G02X506897Y1512216I203J-1D01*
G37*
G36*
G01X662803D02*
X665623D01*
G02X665826Y1512014I1J-202D01*
G01Y1511392D01*
G03X665876Y1511260I200J0D01*
G02Y1508348I-1664J-1456D01*
G03X665826Y1508216I150J-132D01*
G01Y1506273D01*
G03X665876Y1506141I200J0D01*
G02Y1503229I-1664J-1456D01*
G03X665826Y1503097I150J-132D01*
G01Y1502476D01*
G02X665623Y1502274I-203J1D01*
G01X662803D01*
G02X662600Y1502476I-1J202D01*
G01Y1503097D01*
G03X662550Y1503229I-200J0D01*
G02Y1506141I1664J1456D01*
G03X662600Y1506273I-150J132D01*
G01Y1508216D01*
G03X662550Y1508348I-200J0D01*
G02Y1511260I1664J1456D01*
G03X662600Y1511392I-150J132D01*
G01Y1512014D01*
G02X662803Y1512216I203J-1D01*
G37*
G36*
G01X680125D02*
X682945D01*
G02X683148Y1512014I1J-202D01*
G01Y1511392D01*
G03X683198Y1511260I200J0D01*
G02Y1508348I-1664J-1456D01*
G03X683148Y1508216I150J-132D01*
G01Y1506273D01*
G03X683198Y1506141I200J0D01*
G02Y1503229I-1664J-1456D01*
G03X683148Y1503097I150J-132D01*
G01Y1502476D01*
G02X682945Y1502274I-203J1D01*
G01X680125D01*
G02X679922Y1502476I-1J202D01*
G01Y1503097D01*
G03X679872Y1503229I-200J0D01*
G02Y1506141I1664J1456D01*
G03X679922Y1506273I-150J132D01*
G01Y1508216D01*
G03X679872Y1508348I-200J0D01*
G02Y1511260I1664J1456D01*
G03X679922Y1511392I-150J132D01*
G01Y1512014D01*
G02X680125Y1512216I203J-1D01*
G37*
G36*
G01X1303669D02*
X1306489D01*
G02X1306692Y1512014I1J-202D01*
G01Y1511392D01*
G03X1306742Y1511260I200J0D01*
G02Y1508348I-1664J-1456D01*
G03X1306692Y1508216I150J-132D01*
G01Y1506273D01*
G03X1306742Y1506141I200J0D01*
G02Y1503229I-1664J-1456D01*
G03X1306692Y1503097I150J-132D01*
G01Y1502476D01*
G02X1306489Y1502274I-203J1D01*
G01X1303669D01*
G02X1303466Y1502476I-1J202D01*
G01Y1503097D01*
G03X1303416Y1503229I-200J0D01*
G02Y1506141I1664J1456D01*
G03X1303466Y1506273I-150J132D01*
G01Y1508216D01*
G03X1303416Y1508348I-200J0D01*
G02Y1511260I1664J1456D01*
G03X1303466Y1511392I-150J132D01*
G01Y1512014D01*
G02X1303669Y1512216I203J-1D01*
G37*
G36*
G01X1338315D02*
X1341135D01*
G02X1341338Y1512014I1J-202D01*
G01Y1511392D01*
G03X1341388Y1511260I200J0D01*
G02Y1508348I-1664J-1456D01*
G03X1341338Y1508216I150J-132D01*
G01Y1506273D01*
G03X1341388Y1506141I200J0D01*
G02Y1503229I-1664J-1456D01*
G03X1341338Y1503097I150J-132D01*
G01Y1502476D01*
G02X1341135Y1502274I-203J1D01*
G01X1338315D01*
G02X1338112Y1502476I-1J202D01*
G01Y1503097D01*
G03X1338062Y1503229I-200J0D01*
G02Y1506141I1664J1456D01*
G03X1338112Y1506273I-150J132D01*
G01Y1508216D01*
G03X1338062Y1508348I-200J0D01*
G02Y1511260I1664J1456D01*
G03X1338112Y1511392I-150J132D01*
G01Y1512014D01*
G02X1338315Y1512216I203J-1D01*
G37*
G36*
G01X1355637D02*
X1358457D01*
G02X1358660Y1512014I1J-202D01*
G01Y1511392D01*
G03X1358710Y1511260I200J0D01*
G02Y1508348I-1664J-1456D01*
G03X1358660Y1508216I150J-132D01*
G01Y1506273D01*
G03X1358710Y1506141I200J0D01*
G02Y1503229I-1664J-1456D01*
G03X1358660Y1503097I150J-132D01*
G01Y1502476D01*
G02X1358457Y1502274I-203J1D01*
G01X1355637D01*
G02X1355434Y1502476I-1J202D01*
G01Y1503097D01*
G03X1355384Y1503229I-200J0D01*
G02Y1506141I1664J1456D01*
G03X1355434Y1506273I-150J132D01*
G01Y1508216D01*
G03X1355384Y1508348I-200J0D01*
G02Y1511260I1664J1456D01*
G03X1355434Y1511392I-150J132D01*
G01Y1512014D01*
G02X1355637Y1512216I203J-1D01*
G37*
G36*
G01X1476897D02*
X1479717D01*
G02X1479920Y1512014I1J-202D01*
G01Y1511392D01*
G03X1479970Y1511260I200J0D01*
G02Y1508348I-1664J-1456D01*
G03X1479920Y1508216I150J-132D01*
G01Y1506273D01*
G03X1479970Y1506141I200J0D01*
G02Y1503229I-1664J-1456D01*
G03X1479920Y1503097I150J-132D01*
G01Y1502476D01*
G02X1479717Y1502274I-203J1D01*
G01X1476897D01*
G02X1476694Y1502476I-1J202D01*
G01Y1503097D01*
G03X1476644Y1503229I-200J0D01*
G02Y1506141I1664J1456D01*
G03X1476694Y1506273I-150J132D01*
G01Y1508216D01*
G03X1476644Y1508348I-200J0D01*
G02Y1511260I1664J1456D01*
G03X1476694Y1511392I-150J132D01*
G01Y1512014D01*
G02X1476897Y1512216I203J-1D01*
G37*
G36*
G01X1511543D02*
X1514363D01*
G02X1514566Y1512014I1J-202D01*
G01Y1511392D01*
G03X1514616Y1511260I200J0D01*
G02Y1508348I-1664J-1456D01*
G03X1514566Y1508216I150J-132D01*
G01Y1506273D01*
G03X1514616Y1506141I200J0D01*
G02Y1503229I-1664J-1456D01*
G03X1514566Y1503097I150J-132D01*
G01Y1502476D01*
G02X1514363Y1502274I-203J1D01*
G01X1511543D01*
G02X1511340Y1502476I-1J202D01*
G01Y1503097D01*
G03X1511290Y1503229I-200J0D01*
G02Y1506141I1664J1456D01*
G03X1511340Y1506273I-150J132D01*
G01Y1508216D01*
G03X1511290Y1508348I-200J0D01*
G02Y1511260I1664J1456D01*
G03X1511340Y1511392I-150J132D01*
G01Y1512014D01*
G02X1511543Y1512216I203J-1D01*
G37*
G36*
G01X1528865D02*
X1531685D01*
G02X1531888Y1512014I1J-202D01*
G01Y1511392D01*
G03X1531938Y1511260I200J0D01*
G02Y1508348I-1664J-1456D01*
G03X1531888Y1508216I150J-132D01*
G01Y1506273D01*
G03X1531938Y1506141I200J0D01*
G02Y1503229I-1664J-1456D01*
G03X1531888Y1503097I150J-132D01*
G01Y1502476D01*
G02X1531685Y1502274I-203J1D01*
G01X1528865D01*
G02X1528662Y1502476I-1J202D01*
G01Y1503097D01*
G03X1528612Y1503229I-200J0D01*
G02Y1506141I1664J1456D01*
G03X1528662Y1506273I-150J132D01*
G01Y1508216D01*
G03X1528612Y1508348I-200J0D01*
G02Y1511260I1664J1456D01*
G03X1528662Y1511392I-150J132D01*
G01Y1512014D01*
G02X1528865Y1512216I203J-1D01*
G37*
G36*
G01X1684771D02*
X1687591D01*
G02X1687794Y1512014I1J-202D01*
G01Y1511392D01*
G03X1687844Y1511260I200J0D01*
G02Y1508348I-1664J-1456D01*
G03X1687794Y1508216I150J-132D01*
G01Y1506273D01*
G03X1687844Y1506141I200J0D01*
G02Y1503229I-1664J-1456D01*
G03X1687794Y1503097I150J-132D01*
G01Y1502476D01*
G02X1687591Y1502274I-203J1D01*
G01X1684771D01*
G02X1684568Y1502476I-1J202D01*
G01Y1503097D01*
G03X1684518Y1503229I-200J0D01*
G02Y1506141I1664J1456D01*
G03X1684568Y1506273I-150J132D01*
G01Y1508216D01*
G03X1684518Y1508348I-200J0D01*
G02Y1511260I1664J1456D01*
G03X1684568Y1511392I-150J132D01*
G01Y1512014D01*
G02X1684771Y1512216I203J-1D01*
G37*
G36*
G01X1702093D02*
X1704913D01*
G02X1705116Y1512014I1J-202D01*
G01Y1511392D01*
G03X1705166Y1511260I200J0D01*
G02Y1508348I-1664J-1456D01*
G03X1705116Y1508216I150J-132D01*
G01Y1506273D01*
G03X1705166Y1506141I200J0D01*
G02Y1503229I-1664J-1456D01*
G03X1705116Y1503097I150J-132D01*
G01Y1502476D01*
G02X1704913Y1502274I-203J1D01*
G01X1702093D01*
G02X1701890Y1502476I-1J202D01*
G01Y1503097D01*
G03X1701840Y1503229I-200J0D01*
G02Y1506141I1664J1456D01*
G03X1701890Y1506273I-150J132D01*
G01Y1508216D01*
G03X1701840Y1508348I-200J0D01*
G02Y1511260I1664J1456D01*
G03X1701890Y1511392I-150J132D01*
G01Y1512014D01*
G02X1702093Y1512216I203J-1D01*
G37*
G36*
G01X134456Y1516546D02*
X137276D01*
G02X137478Y1516344I0J-202D01*
G01Y1515724D01*
G03X137528Y1515592I200J0D01*
G02Y1512676I-1661J-1458D01*
G03X137478Y1512544I150J-132D01*
G01Y1510606D01*
G03X137528Y1510474I200J0D01*
G02Y1507558I-1661J-1458D01*
G03X137478Y1507426I150J-132D01*
G01Y1506806D01*
G02X137276Y1506604I-202J0D01*
G01X134456D01*
G02X134254Y1506806I0J202D01*
G01Y1507426D01*
G03X134204Y1507558I-200J0D01*
G02Y1510474I1661J1458D01*
G03X134254Y1510606I-150J132D01*
G01Y1512544D01*
G03X134204Y1512676I-200J0D01*
G02Y1515592I1661J1458D01*
G03X134254Y1515724I-150J132D01*
G01Y1516344D01*
G02X134456Y1516546I202J0D01*
G37*
G36*
G01X169102D02*
X171922D01*
G02X172124Y1516344I0J-202D01*
G01Y1515724D01*
G03X172174Y1515592I200J0D01*
G02Y1512676I-1661J-1458D01*
G03X172124Y1512544I150J-132D01*
G01Y1510606D01*
G03X172174Y1510474I200J0D01*
G02Y1507558I-1661J-1458D01*
G03X172124Y1507426I150J-132D01*
G01Y1506806D01*
G02X171922Y1506604I-202J0D01*
G01X169102D01*
G02X168900Y1506806I0J202D01*
G01Y1507426D01*
G03X168850Y1507558I-200J0D01*
G02Y1510474I1661J1458D01*
G03X168900Y1510606I-150J132D01*
G01Y1512544D01*
G03X168850Y1512676I-200J0D01*
G02Y1515592I1661J1458D01*
G03X168900Y1515724I-150J132D01*
G01Y1516344D01*
G02X169102Y1516546I202J0D01*
G37*
G36*
G01X463590D02*
X466410D01*
G02X466612Y1516344I0J-202D01*
G01Y1515724D01*
G03X466662Y1515592I200J0D01*
G02Y1512676I-1661J-1458D01*
G03X466612Y1512544I150J-132D01*
G01Y1510606D01*
G03X466662Y1510474I200J0D01*
G02Y1507558I-1661J-1458D01*
G03X466612Y1507426I150J-132D01*
G01Y1506806D01*
G02X466410Y1506604I-202J0D01*
G01X463590D01*
G02X463388Y1506806I0J202D01*
G01Y1507426D01*
G03X463338Y1507558I-200J0D01*
G02Y1510474I1661J1458D01*
G03X463388Y1510606I-150J132D01*
G01Y1512544D01*
G03X463338Y1512676I-200J0D01*
G02Y1515592I1661J1458D01*
G03X463388Y1515724I-150J132D01*
G01Y1516344D01*
G02X463590Y1516546I202J0D01*
G37*
G36*
G01X498236D02*
X501056D01*
G02X501258Y1516344I0J-202D01*
G01Y1515724D01*
G03X501308Y1515592I200J0D01*
G02Y1512676I-1661J-1458D01*
G03X501258Y1512544I150J-132D01*
G01Y1510606D01*
G03X501308Y1510474I200J0D01*
G02Y1507558I-1661J-1458D01*
G03X501258Y1507426I150J-132D01*
G01Y1506806D01*
G02X501056Y1506604I-202J0D01*
G01X498236D01*
G02X498034Y1506806I0J202D01*
G01Y1507426D01*
G03X497984Y1507558I-200J0D01*
G02Y1510474I1661J1458D01*
G03X498034Y1510606I-150J132D01*
G01Y1512544D01*
G03X497984Y1512676I-200J0D01*
G02Y1515592I1661J1458D01*
G03X498034Y1515724I-150J132D01*
G01Y1516344D01*
G02X498236Y1516546I202J0D01*
G37*
G36*
G01X671464D02*
X674284D01*
G02X674486Y1516344I0J-202D01*
G01Y1515724D01*
G03X674536Y1515592I200J0D01*
G02Y1512676I-1661J-1458D01*
G03X674486Y1512544I150J-132D01*
G01Y1510606D01*
G03X674536Y1510474I200J0D01*
G02Y1507558I-1661J-1458D01*
G03X674486Y1507426I150J-132D01*
G01Y1506806D01*
G02X674284Y1506604I-202J0D01*
G01X671464D01*
G02X671262Y1506806I0J202D01*
G01Y1507426D01*
G03X671212Y1507558I-200J0D01*
G02Y1510474I1661J1458D01*
G03X671262Y1510606I-150J132D01*
G01Y1512544D01*
G03X671212Y1512676I-200J0D01*
G02Y1515592I1661J1458D01*
G03X671262Y1515724I-150J132D01*
G01Y1516344D01*
G02X671464Y1516546I202J0D01*
G37*
G36*
G01X1191070D02*
X1193890D01*
G02X1194092Y1516344I0J-202D01*
G01Y1515724D01*
G03X1194142Y1515592I200J0D01*
G02Y1512676I-1661J-1458D01*
G03X1194092Y1512544I150J-132D01*
G01Y1510606D01*
G03X1194142Y1510474I200J0D01*
G02Y1507558I-1661J-1458D01*
G03X1194092Y1507426I150J-132D01*
G01Y1506806D01*
G02X1193890Y1506604I-202J0D01*
G01X1191070D01*
G02X1190868Y1506806I0J202D01*
G01Y1507426D01*
G03X1190818Y1507558I-200J0D01*
G02Y1510474I1661J1458D01*
G03X1190868Y1510606I-150J132D01*
G01Y1512544D01*
G03X1190818Y1512676I-200J0D01*
G02Y1515592I1661J1458D01*
G03X1190868Y1515724I-150J132D01*
G01Y1516344D01*
G02X1191070Y1516546I202J0D01*
G37*
G36*
G01X1312330D02*
X1315150D01*
G02X1315352Y1516344I0J-202D01*
G01Y1515724D01*
G03X1315402Y1515592I200J0D01*
G02Y1512676I-1661J-1458D01*
G03X1315352Y1512544I150J-132D01*
G01Y1510606D01*
G03X1315402Y1510474I200J0D01*
G02Y1507558I-1661J-1458D01*
G03X1315352Y1507426I150J-132D01*
G01Y1506806D01*
G02X1315150Y1506604I-202J0D01*
G01X1312330D01*
G02X1312128Y1506806I0J202D01*
G01Y1507426D01*
G03X1312078Y1507558I-200J0D01*
G02Y1510474I1661J1458D01*
G03X1312128Y1510606I-150J132D01*
G01Y1512544D01*
G03X1312078Y1512676I-200J0D01*
G02Y1515592I1661J1458D01*
G03X1312128Y1515724I-150J132D01*
G01Y1516344D01*
G02X1312330Y1516546I202J0D01*
G37*
G36*
G01X1346976D02*
X1349796D01*
G02X1349998Y1516344I0J-202D01*
G01Y1515724D01*
G03X1350048Y1515592I200J0D01*
G02Y1512676I-1661J-1458D01*
G03X1349998Y1512544I150J-132D01*
G01Y1510606D01*
G03X1350048Y1510474I200J0D01*
G02Y1507558I-1661J-1458D01*
G03X1349998Y1507426I150J-132D01*
G01Y1506806D01*
G02X1349796Y1506604I-202J0D01*
G01X1346976D01*
G02X1346774Y1506806I0J202D01*
G01Y1507426D01*
G03X1346724Y1507558I-200J0D01*
G02Y1510474I1661J1458D01*
G03X1346774Y1510606I-150J132D01*
G01Y1512544D01*
G03X1346724Y1512676I-200J0D01*
G02Y1515592I1661J1458D01*
G03X1346774Y1515724I-150J132D01*
G01Y1516344D01*
G02X1346976Y1516546I202J0D01*
G37*
G36*
G01X1485558D02*
X1488378D01*
G02X1488580Y1516344I0J-202D01*
G01Y1515724D01*
G03X1488630Y1515592I200J0D01*
G02Y1512676I-1661J-1458D01*
G03X1488580Y1512544I150J-132D01*
G01Y1510606D01*
G03X1488630Y1510474I200J0D01*
G02Y1507558I-1661J-1458D01*
G03X1488580Y1507426I150J-132D01*
G01Y1506806D01*
G02X1488378Y1506604I-202J0D01*
G01X1485558D01*
G02X1485356Y1506806I0J202D01*
G01Y1507426D01*
G03X1485306Y1507558I-200J0D01*
G02Y1510474I1661J1458D01*
G03X1485356Y1510606I-150J132D01*
G01Y1512544D01*
G03X1485306Y1512676I-200J0D01*
G02Y1515592I1661J1458D01*
G03X1485356Y1515724I-150J132D01*
G01Y1516344D01*
G02X1485558Y1516546I202J0D01*
G37*
G36*
G01X1520204D02*
X1523024D01*
G02X1523226Y1516344I0J-202D01*
G01Y1515724D01*
G03X1523276Y1515592I200J0D01*
G02Y1512676I-1661J-1458D01*
G03X1523226Y1512544I150J-132D01*
G01Y1510606D01*
G03X1523276Y1510474I200J0D01*
G02Y1507558I-1661J-1458D01*
G03X1523226Y1507426I150J-132D01*
G01Y1506806D01*
G02X1523024Y1506604I-202J0D01*
G01X1520204D01*
G02X1520002Y1506806I0J202D01*
G01Y1507426D01*
G03X1519952Y1507558I-200J0D01*
G02Y1510474I1661J1458D01*
G03X1520002Y1510606I-150J132D01*
G01Y1512544D01*
G03X1519952Y1512676I-200J0D01*
G02Y1515592I1661J1458D01*
G03X1520002Y1515724I-150J132D01*
G01Y1516344D01*
G02X1520204Y1516546I202J0D01*
G37*
G36*
G01X1693432D02*
X1696252D01*
G02X1696454Y1516344I0J-202D01*
G01Y1515724D01*
G03X1696504Y1515592I200J0D01*
G02Y1512676I-1661J-1458D01*
G03X1696454Y1512544I150J-132D01*
G01Y1510606D01*
G03X1696504Y1510474I200J0D01*
G02Y1507558I-1661J-1458D01*
G03X1696454Y1507426I150J-132D01*
G01Y1506806D01*
G02X1696252Y1506604I-202J0D01*
G01X1693432D01*
G02X1693230Y1506806I0J202D01*
G01Y1507426D01*
G03X1693180Y1507558I-200J0D01*
G02Y1510474I1661J1458D01*
G03X1693230Y1510606I-150J132D01*
G01Y1512544D01*
G03X1693180Y1512676I-200J0D01*
G02Y1515592I1661J1458D01*
G03X1693230Y1515724I-150J132D01*
G01Y1516344D01*
G02X1693432Y1516546I202J0D01*
G37*
G36*
G01X151779D02*
X154599D01*
G02X154802Y1516344I1J-202D01*
G01Y1515722D01*
G03X154852Y1515590I200J0D01*
G02Y1512678I-1664J-1456D01*
G03X154802Y1512546I150J-132D01*
G01Y1510604D01*
G03X154852Y1510472I200J0D01*
G02Y1507560I-1664J-1456D01*
G03X154802Y1507428I150J-132D01*
G01Y1506806D01*
G02X154599Y1506604I-203J1D01*
G01X151779D01*
G02X151576Y1506806I-1J202D01*
G01Y1507428D01*
G03X151526Y1507560I-200J0D01*
G02Y1510472I1664J1456D01*
G03X151576Y1510604I-150J132D01*
G01Y1512546D01*
G03X151526Y1512678I-200J0D01*
G02Y1515590I1664J1456D01*
G03X151576Y1515722I-150J132D01*
G01Y1516344D01*
G02X151779Y1516546I203J-1D01*
G37*
G36*
G01X290361D02*
X293181D01*
G02X293384Y1516344I1J-202D01*
G01Y1515722D01*
G03X293434Y1515590I200J0D01*
G02Y1512678I-1664J-1456D01*
G03X293384Y1512546I150J-132D01*
G01Y1510604D01*
G03X293434Y1510472I200J0D01*
G02Y1507560I-1664J-1456D01*
G03X293384Y1507428I150J-132D01*
G01Y1506806D01*
G02X293181Y1506604I-203J1D01*
G01X290361D01*
G02X290158Y1506806I-1J202D01*
G01Y1507428D01*
G03X290108Y1507560I-200J0D01*
G02Y1510472I1664J1456D01*
G03X290158Y1510604I-150J132D01*
G01Y1512546D01*
G03X290108Y1512678I-200J0D01*
G02Y1515590I1664J1456D01*
G03X290158Y1515722I-150J132D01*
G01Y1516344D01*
G02X290361Y1516546I203J-1D01*
G37*
G36*
G01X480913D02*
X483733D01*
G02X483936Y1516344I1J-202D01*
G01Y1515722D01*
G03X483986Y1515590I200J0D01*
G02Y1512678I-1664J-1456D01*
G03X483936Y1512546I150J-132D01*
G01Y1510604D01*
G03X483986Y1510472I200J0D01*
G02Y1507560I-1664J-1456D01*
G03X483936Y1507428I150J-132D01*
G01Y1506806D01*
G02X483733Y1506604I-203J1D01*
G01X480913D01*
G02X480710Y1506806I-1J202D01*
G01Y1507428D01*
G03X480660Y1507560I-200J0D01*
G02Y1510472I1664J1456D01*
G03X480710Y1510604I-150J132D01*
G01Y1512546D01*
G03X480660Y1512678I-200J0D01*
G02Y1515590I1664J1456D01*
G03X480710Y1515722I-150J132D01*
G01Y1516344D01*
G02X480913Y1516546I203J-1D01*
G37*
G36*
G01X515559D02*
X518379D01*
G02X518582Y1516344I1J-202D01*
G01Y1515722D01*
G03X518632Y1515590I200J0D01*
G02Y1512678I-1664J-1456D01*
G03X518582Y1512546I150J-132D01*
G01Y1510604D01*
G03X518632Y1510472I200J0D01*
G02Y1507560I-1664J-1456D01*
G03X518582Y1507428I150J-132D01*
G01Y1506806D01*
G02X518379Y1506604I-203J1D01*
G01X515559D01*
G02X515356Y1506806I-1J202D01*
G01Y1507428D01*
G03X515306Y1507560I-200J0D01*
G02Y1510472I1664J1456D01*
G03X515356Y1510604I-150J132D01*
G01Y1512546D01*
G03X515306Y1512678I-200J0D01*
G02Y1515590I1664J1456D01*
G03X515356Y1515722I-150J132D01*
G01Y1516344D01*
G02X515559Y1516546I203J-1D01*
G37*
G36*
G01X654141D02*
X656961D01*
G02X657164Y1516344I1J-202D01*
G01Y1515722D01*
G03X657214Y1515590I200J0D01*
G02Y1512678I-1664J-1456D01*
G03X657164Y1512546I150J-132D01*
G01Y1510604D01*
G03X657214Y1510472I200J0D01*
G02Y1507560I-1664J-1456D01*
G03X657164Y1507428I150J-132D01*
G01Y1506806D01*
G02X656961Y1506604I-203J1D01*
G01X654141D01*
G02X653938Y1506806I-1J202D01*
G01Y1507428D01*
G03X653888Y1507560I-200J0D01*
G02Y1510472I1664J1456D01*
G03X653938Y1510604I-150J132D01*
G01Y1512546D01*
G03X653888Y1512678I-200J0D01*
G02Y1515590I1664J1456D01*
G03X653938Y1515722I-150J132D01*
G01Y1516344D01*
G02X654141Y1516546I203J-1D01*
G37*
G36*
G01X688787D02*
X691607D01*
G02X691810Y1516344I1J-202D01*
G01Y1515722D01*
G03X691860Y1515590I200J0D01*
G02Y1512678I-1664J-1456D01*
G03X691810Y1512546I150J-132D01*
G01Y1510604D01*
G03X691860Y1510472I200J0D01*
G02Y1507560I-1664J-1456D01*
G03X691810Y1507428I150J-132D01*
G01Y1506806D01*
G02X691607Y1506604I-203J1D01*
G01X688787D01*
G02X688584Y1506806I-1J202D01*
G01Y1507428D01*
G03X688534Y1507560I-200J0D01*
G02Y1510472I1664J1456D01*
G03X688584Y1510604I-150J132D01*
G01Y1512546D01*
G03X688534Y1512678I-200J0D01*
G02Y1515590I1664J1456D01*
G03X688584Y1515722I-150J132D01*
G01Y1516344D01*
G02X688787Y1516546I203J-1D01*
G37*
G36*
G01X1173747D02*
X1176567D01*
G02X1176770Y1516344I1J-202D01*
G01Y1515722D01*
G03X1176820Y1515590I200J0D01*
G02Y1512678I-1664J-1456D01*
G03X1176770Y1512546I150J-132D01*
G01Y1510604D01*
G03X1176820Y1510472I200J0D01*
G02Y1507560I-1664J-1456D01*
G03X1176770Y1507428I150J-132D01*
G01Y1506806D01*
G02X1176567Y1506604I-203J1D01*
G01X1173747D01*
G02X1173544Y1506806I-1J202D01*
G01Y1507428D01*
G03X1173494Y1507560I-200J0D01*
G02Y1510472I1664J1456D01*
G03X1173544Y1510604I-150J132D01*
G01Y1512546D01*
G03X1173494Y1512678I-200J0D01*
G02Y1515590I1664J1456D01*
G03X1173544Y1515722I-150J132D01*
G01Y1516344D01*
G02X1173747Y1516546I203J-1D01*
G37*
G36*
G01X1329653D02*
X1332473D01*
G02X1332676Y1516344I1J-202D01*
G01Y1515722D01*
G03X1332726Y1515590I200J0D01*
G02Y1512678I-1664J-1456D01*
G03X1332676Y1512546I150J-132D01*
G01Y1510604D01*
G03X1332726Y1510472I200J0D01*
G02Y1507560I-1664J-1456D01*
G03X1332676Y1507428I150J-132D01*
G01Y1506806D01*
G02X1332473Y1506604I-203J1D01*
G01X1329653D01*
G02X1329450Y1506806I-1J202D01*
G01Y1507428D01*
G03X1329400Y1507560I-200J0D01*
G02Y1510472I1664J1456D01*
G03X1329450Y1510604I-150J132D01*
G01Y1512546D01*
G03X1329400Y1512678I-200J0D01*
G02Y1515590I1664J1456D01*
G03X1329450Y1515722I-150J132D01*
G01Y1516344D01*
G02X1329653Y1516546I203J-1D01*
G37*
G36*
G01X1364299D02*
X1367119D01*
G02X1367322Y1516344I1J-202D01*
G01Y1515722D01*
G03X1367372Y1515590I200J0D01*
G02Y1512678I-1664J-1456D01*
G03X1367322Y1512546I150J-132D01*
G01Y1510604D01*
G03X1367372Y1510472I200J0D01*
G02Y1507560I-1664J-1456D01*
G03X1367322Y1507428I150J-132D01*
G01Y1506806D01*
G02X1367119Y1506604I-203J1D01*
G01X1364299D01*
G02X1364096Y1506806I-1J202D01*
G01Y1507428D01*
G03X1364046Y1507560I-200J0D01*
G02Y1510472I1664J1456D01*
G03X1364096Y1510604I-150J132D01*
G01Y1512546D01*
G03X1364046Y1512678I-200J0D01*
G02Y1515590I1664J1456D01*
G03X1364096Y1515722I-150J132D01*
G01Y1516344D01*
G02X1364299Y1516546I203J-1D01*
G37*
G36*
G01X1502881D02*
X1505701D01*
G02X1505904Y1516344I1J-202D01*
G01Y1515722D01*
G03X1505954Y1515590I200J0D01*
G02Y1512678I-1664J-1456D01*
G03X1505904Y1512546I150J-132D01*
G01Y1510604D01*
G03X1505954Y1510472I200J0D01*
G02Y1507560I-1664J-1456D01*
G03X1505904Y1507428I150J-132D01*
G01Y1506806D01*
G02X1505701Y1506604I-203J1D01*
G01X1502881D01*
G02X1502678Y1506806I-1J202D01*
G01Y1507428D01*
G03X1502628Y1507560I-200J0D01*
G02Y1510472I1664J1456D01*
G03X1502678Y1510604I-150J132D01*
G01Y1512546D01*
G03X1502628Y1512678I-200J0D01*
G02Y1515590I1664J1456D01*
G03X1502678Y1515722I-150J132D01*
G01Y1516344D01*
G02X1502881Y1516546I203J-1D01*
G37*
G36*
G01X1537527D02*
X1540347D01*
G02X1540550Y1516344I1J-202D01*
G01Y1515722D01*
G03X1540600Y1515590I200J0D01*
G02Y1512678I-1664J-1456D01*
G03X1540550Y1512546I150J-132D01*
G01Y1510604D01*
G03X1540600Y1510472I200J0D01*
G02Y1507560I-1664J-1456D01*
G03X1540550Y1507428I150J-132D01*
G01Y1506806D01*
G02X1540347Y1506604I-203J1D01*
G01X1537527D01*
G02X1537324Y1506806I-1J202D01*
G01Y1507428D01*
G03X1537274Y1507560I-200J0D01*
G02Y1510472I1664J1456D01*
G03X1537324Y1510604I-150J132D01*
G01Y1512546D01*
G03X1537274Y1512678I-200J0D01*
G02Y1515590I1664J1456D01*
G03X1537324Y1515722I-150J132D01*
G01Y1516344D01*
G02X1537527Y1516546I203J-1D01*
G37*
G36*
G01X1710755D02*
X1713575D01*
G02X1713778Y1516344I1J-202D01*
G01Y1515722D01*
G03X1713828Y1515590I200J0D01*
G02Y1512678I-1664J-1456D01*
G03X1713778Y1512546I150J-132D01*
G01Y1510604D01*
G03X1713828Y1510472I200J0D01*
G02Y1507560I-1664J-1456D01*
G03X1713778Y1507428I150J-132D01*
G01Y1506806D01*
G02X1713575Y1506604I-203J1D01*
G01X1710755D01*
G02X1710552Y1506806I-1J202D01*
G01Y1507428D01*
G03X1710502Y1507560I-200J0D01*
G02Y1510472I1664J1456D01*
G03X1710552Y1510604I-150J132D01*
G01Y1512546D01*
G03X1710502Y1512678I-200J0D01*
G02Y1515590I1664J1456D01*
G03X1710552Y1515722I-150J132D01*
G01Y1516344D01*
G02X1710755Y1516546I203J-1D01*
G37*
G36*
G01X108472Y1568516D02*
X111292D01*
G02X111494Y1568313I-1J-203D01*
G01Y1567693D01*
G03X111544Y1567561I200J0D01*
G02Y1564645I-1661J-1458D01*
G03X111494Y1564513I150J-132D01*
G01Y1562575D01*
G03X111544Y1562443I200J0D01*
G02Y1559527I-1661J-1458D01*
G03X111494Y1559395I150J-132D01*
G01Y1558775D01*
G02X111292Y1558572I-202J-1D01*
G01X108472D01*
G02X108270Y1558775I1J203D01*
G01Y1559395D01*
G03X108220Y1559527I-200J0D01*
G02Y1562443I1661J1458D01*
G03X108270Y1562575I-150J132D01*
G01Y1564513D01*
G03X108220Y1564645I-200J0D01*
G02Y1567561I1661J1458D01*
G03X108270Y1567693I-150J132D01*
G01Y1568313D01*
G02X108472Y1568516I202J1D01*
G37*
G36*
G01X125795D02*
X128615D01*
G02X128818Y1568313I0J-203D01*
G01Y1567691D01*
G03X128868Y1567559I200J0D01*
G02Y1564647I-1664J-1456D01*
G03X128818Y1564515I150J-132D01*
G01Y1562573D01*
G03X128868Y1562441I200J0D01*
G02Y1559529I-1664J-1456D01*
G03X128818Y1559397I150J-132D01*
G01Y1558775D01*
G02X128615Y1558572I-203J0D01*
G01X125795D01*
G02X125592Y1558775I0J203D01*
G01Y1559397D01*
G03X125542Y1559529I-200J0D01*
G02Y1562441I1664J1456D01*
G03X125592Y1562573I-150J132D01*
G01Y1564515D01*
G03X125542Y1564647I-200J0D01*
G02Y1567559I1664J1456D01*
G03X125592Y1567691I-150J132D01*
G01Y1568313D01*
G02X125795Y1568516I203J0D01*
G37*
G36*
G01X143118D02*
X145938D01*
G02X146140Y1568313I-1J-203D01*
G01Y1567693D01*
G03X146190Y1567561I200J0D01*
G02Y1564645I-1661J-1458D01*
G03X146140Y1564513I150J-132D01*
G01Y1562575D01*
G03X146190Y1562443I200J0D01*
G02Y1559527I-1661J-1458D01*
G03X146140Y1559395I150J-132D01*
G01Y1558775D01*
G02X145938Y1558572I-202J-1D01*
G01X143118D01*
G02X142916Y1558775I1J203D01*
G01Y1559395D01*
G03X142866Y1559527I-200J0D01*
G02Y1562443I1661J1458D01*
G03X142916Y1562575I-150J132D01*
G01Y1564513D01*
G03X142866Y1564645I-200J0D01*
G02Y1567561I1661J1458D01*
G03X142916Y1567693I-150J132D01*
G01Y1568313D01*
G02X143118Y1568516I202J1D01*
G37*
G36*
G01X160440D02*
X163260D01*
G02X163462Y1568313I-1J-203D01*
G01Y1567693D01*
G03X163512Y1567561I200J0D01*
G02Y1564645I-1661J-1458D01*
G03X163462Y1564513I150J-132D01*
G01Y1562575D01*
G03X163512Y1562443I200J0D01*
G02Y1559527I-1661J-1458D01*
G03X163462Y1559395I150J-132D01*
G01Y1558775D01*
G02X163260Y1558572I-202J-1D01*
G01X160440D01*
G02X160238Y1558775I1J203D01*
G01Y1559395D01*
G03X160188Y1559527I-200J0D01*
G02Y1562443I1661J1458D01*
G03X160238Y1562575I-150J132D01*
G01Y1564513D01*
G03X160188Y1564645I-200J0D01*
G02Y1567561I1661J1458D01*
G03X160238Y1567693I-150J132D01*
G01Y1568313D01*
G02X160440Y1568516I202J1D01*
G37*
G36*
G01X281700D02*
X284520D01*
G02X284722Y1568313I-1J-203D01*
G01Y1567693D01*
G03X284772Y1567561I200J0D01*
G02Y1564645I-1661J-1458D01*
G03X284722Y1564513I150J-132D01*
G01Y1562575D01*
G03X284772Y1562443I200J0D01*
G02Y1559527I-1661J-1458D01*
G03X284722Y1559395I150J-132D01*
G01Y1558775D01*
G02X284520Y1558572I-202J-1D01*
G01X281700D01*
G02X281498Y1558775I1J203D01*
G01Y1559395D01*
G03X281448Y1559527I-200J0D01*
G02Y1562443I1661J1458D01*
G03X281498Y1562575I-150J132D01*
G01Y1564513D01*
G03X281448Y1564645I-200J0D01*
G02Y1567561I1661J1458D01*
G03X281498Y1567693I-150J132D01*
G01Y1568313D01*
G02X281700Y1568516I202J1D01*
G37*
G36*
G01X299023D02*
X301843D01*
G02X302046Y1568313I0J-203D01*
G01Y1567691D01*
G03X302096Y1567559I200J0D01*
G02Y1564647I-1664J-1456D01*
G03X302046Y1564515I150J-132D01*
G01Y1562573D01*
G03X302096Y1562441I200J0D01*
G02Y1559529I-1664J-1456D01*
G03X302046Y1559397I150J-132D01*
G01Y1558775D01*
G02X301843Y1558572I-203J0D01*
G01X299023D01*
G02X298820Y1558775I0J203D01*
G01Y1559397D01*
G03X298770Y1559529I-200J0D01*
G02Y1562441I1664J1456D01*
G03X298820Y1562573I-150J132D01*
G01Y1564515D01*
G03X298770Y1564647I-200J0D01*
G02Y1567559I1664J1456D01*
G03X298820Y1567691I-150J132D01*
G01Y1568313D01*
G02X299023Y1568516I203J0D01*
G37*
G36*
G01X316346D02*
X319166D01*
G02X319368Y1568313I-1J-203D01*
G01Y1567693D01*
G03X319418Y1567561I200J0D01*
G02Y1564645I-1661J-1458D01*
G03X319368Y1564513I150J-132D01*
G01Y1562575D01*
G03X319418Y1562443I200J0D01*
G02Y1559527I-1661J-1458D01*
G03X319368Y1559395I150J-132D01*
G01Y1558775D01*
G02X319166Y1558572I-202J-1D01*
G01X316346D01*
G02X316144Y1558775I1J203D01*
G01Y1559395D01*
G03X316094Y1559527I-200J0D01*
G02Y1562443I1661J1458D01*
G03X316144Y1562575I-150J132D01*
G01Y1564513D01*
G03X316094Y1564645I-200J0D01*
G02Y1567561I1661J1458D01*
G03X316144Y1567693I-150J132D01*
G01Y1568313D01*
G02X316346Y1568516I202J1D01*
G37*
G36*
G01X333668D02*
X336488D01*
G02X336690Y1568313I-1J-203D01*
G01Y1567693D01*
G03X336740Y1567561I200J0D01*
G02Y1564645I-1661J-1458D01*
G03X336690Y1564513I150J-132D01*
G01Y1562575D01*
G03X336740Y1562443I200J0D01*
G02Y1559527I-1661J-1458D01*
G03X336690Y1559395I150J-132D01*
G01Y1558775D01*
G02X336488Y1558572I-202J-1D01*
G01X333668D01*
G02X333466Y1558775I1J203D01*
G01Y1559395D01*
G03X333416Y1559527I-200J0D01*
G02Y1562443I1661J1458D01*
G03X333466Y1562575I-150J132D01*
G01Y1564513D01*
G03X333416Y1564645I-200J0D01*
G02Y1567561I1661J1458D01*
G03X333466Y1567693I-150J132D01*
G01Y1568313D01*
G02X333668Y1568516I202J1D01*
G37*
G36*
G01X628157D02*
X630977D01*
G02X631180Y1568313I0J-203D01*
G01Y1567691D01*
G03X631230Y1567559I200J0D01*
G02Y1564647I-1664J-1456D01*
G03X631180Y1564515I150J-132D01*
G01Y1562573D01*
G03X631230Y1562441I200J0D01*
G02Y1559529I-1664J-1456D01*
G03X631180Y1559397I150J-132D01*
G01Y1558775D01*
G02X630977Y1558572I-203J0D01*
G01X628157D01*
G02X627954Y1558775I0J203D01*
G01Y1559397D01*
G03X627904Y1559529I-200J0D01*
G02Y1562441I1664J1456D01*
G03X627954Y1562573I-150J132D01*
G01Y1564515D01*
G03X627904Y1564647I-200J0D01*
G02Y1567559I1664J1456D01*
G03X627954Y1567691I-150J132D01*
G01Y1568313D01*
G02X628157Y1568516I203J0D01*
G37*
G36*
G01X645480D02*
X648300D01*
G02X648502Y1568313I-1J-203D01*
G01Y1567693D01*
G03X648552Y1567561I200J0D01*
G02Y1564645I-1661J-1458D01*
G03X648502Y1564513I150J-132D01*
G01Y1562575D01*
G03X648552Y1562443I200J0D01*
G02Y1559527I-1661J-1458D01*
G03X648502Y1559395I150J-132D01*
G01Y1558775D01*
G02X648300Y1558572I-202J-1D01*
G01X645480D01*
G02X645278Y1558775I1J203D01*
G01Y1559395D01*
G03X645228Y1559527I-200J0D01*
G02Y1562443I1661J1458D01*
G03X645278Y1562575I-150J132D01*
G01Y1564513D01*
G03X645228Y1564645I-200J0D01*
G02Y1567561I1661J1458D01*
G03X645278Y1567693I-150J132D01*
G01Y1568313D01*
G02X645480Y1568516I202J1D01*
G37*
G36*
G01X662803D02*
X665623D01*
G02X665826Y1568313I0J-203D01*
G01Y1567691D01*
G03X665876Y1567559I200J0D01*
G02Y1564647I-1664J-1456D01*
G03X665826Y1564515I150J-132D01*
G01Y1562573D01*
G03X665876Y1562441I200J0D01*
G02Y1559529I-1664J-1456D01*
G03X665826Y1559397I150J-132D01*
G01Y1558775D01*
G02X665623Y1558572I-203J0D01*
G01X662803D01*
G02X662600Y1558775I0J203D01*
G01Y1559397D01*
G03X662550Y1559529I-200J0D01*
G02Y1562441I1664J1456D01*
G03X662600Y1562573I-150J132D01*
G01Y1564515D01*
G03X662550Y1564647I-200J0D01*
G02Y1567559I1664J1456D01*
G03X662600Y1567691I-150J132D01*
G01Y1568313D01*
G02X662803Y1568516I203J0D01*
G37*
G36*
G01X680125D02*
X682945D01*
G02X683148Y1568313I0J-203D01*
G01Y1567691D01*
G03X683198Y1567559I200J0D01*
G02Y1564647I-1664J-1456D01*
G03X683148Y1564515I150J-132D01*
G01Y1562573D01*
G03X683198Y1562441I200J0D01*
G02Y1559529I-1664J-1456D01*
G03X683148Y1559397I150J-132D01*
G01Y1558775D01*
G02X682945Y1558572I-203J0D01*
G01X680125D01*
G02X679922Y1558775I0J203D01*
G01Y1559397D01*
G03X679872Y1559529I-200J0D01*
G02Y1562441I1664J1456D01*
G03X679922Y1562573I-150J132D01*
G01Y1564515D01*
G03X679872Y1564647I-200J0D01*
G02Y1567559I1664J1456D01*
G03X679922Y1567691I-150J132D01*
G01Y1568313D01*
G02X680125Y1568516I203J0D01*
G37*
G36*
G01X1130440D02*
X1133260D01*
G02X1133462Y1568313I-1J-203D01*
G01Y1567693D01*
G03X1133512Y1567561I200J0D01*
G02Y1564645I-1661J-1458D01*
G03X1133462Y1564513I150J-132D01*
G01Y1562575D01*
G03X1133512Y1562443I200J0D01*
G02Y1559527I-1661J-1458D01*
G03X1133462Y1559395I150J-132D01*
G01Y1558775D01*
G02X1133260Y1558572I-202J-1D01*
G01X1130440D01*
G02X1130238Y1558775I1J203D01*
G01Y1559395D01*
G03X1130188Y1559527I-200J0D01*
G02Y1562443I1661J1458D01*
G03X1130238Y1562575I-150J132D01*
G01Y1564513D01*
G03X1130188Y1564645I-200J0D01*
G02Y1567561I1661J1458D01*
G03X1130238Y1567693I-150J132D01*
G01Y1568313D01*
G02X1130440Y1568516I202J1D01*
G37*
G36*
G01X1147763D02*
X1150583D01*
G02X1150786Y1568313I0J-203D01*
G01Y1567691D01*
G03X1150836Y1567559I200J0D01*
G02Y1564647I-1664J-1456D01*
G03X1150786Y1564515I150J-132D01*
G01Y1562573D01*
G03X1150836Y1562441I200J0D01*
G02Y1559529I-1664J-1456D01*
G03X1150786Y1559397I150J-132D01*
G01Y1558775D01*
G02X1150583Y1558572I-203J0D01*
G01X1147763D01*
G02X1147560Y1558775I0J203D01*
G01Y1559397D01*
G03X1147510Y1559529I-200J0D01*
G02Y1562441I1664J1456D01*
G03X1147560Y1562573I-150J132D01*
G01Y1564515D01*
G03X1147510Y1564647I-200J0D01*
G02Y1567559I1664J1456D01*
G03X1147560Y1567691I-150J132D01*
G01Y1568313D01*
G02X1147763Y1568516I203J0D01*
G37*
G36*
G01X1165086D02*
X1167906D01*
G02X1168108Y1568313I-1J-203D01*
G01Y1567693D01*
G03X1168158Y1567561I200J0D01*
G02Y1564645I-1661J-1458D01*
G03X1168108Y1564513I150J-132D01*
G01Y1562575D01*
G03X1168158Y1562443I200J0D01*
G02Y1559527I-1661J-1458D01*
G03X1168108Y1559395I150J-132D01*
G01Y1558775D01*
G02X1167906Y1558572I-202J-1D01*
G01X1165086D01*
G02X1164884Y1558775I1J203D01*
G01Y1559395D01*
G03X1164834Y1559527I-200J0D01*
G02Y1562443I1661J1458D01*
G03X1164884Y1562575I-150J132D01*
G01Y1564513D01*
G03X1164834Y1564645I-200J0D01*
G02Y1567561I1661J1458D01*
G03X1164884Y1567693I-150J132D01*
G01Y1568313D01*
G02X1165086Y1568516I202J1D01*
G37*
G36*
G01X1182408D02*
X1185228D01*
G02X1185430Y1568313I-1J-203D01*
G01Y1567693D01*
G03X1185480Y1567561I200J0D01*
G02Y1564645I-1661J-1458D01*
G03X1185430Y1564513I150J-132D01*
G01Y1562575D01*
G03X1185480Y1562443I200J0D01*
G02Y1559527I-1661J-1458D01*
G03X1185430Y1559395I150J-132D01*
G01Y1558775D01*
G02X1185228Y1558572I-202J-1D01*
G01X1182408D01*
G02X1182206Y1558775I1J203D01*
G01Y1559395D01*
G03X1182156Y1559527I-200J0D01*
G02Y1562443I1661J1458D01*
G03X1182206Y1562575I-150J132D01*
G01Y1564513D01*
G03X1182156Y1564645I-200J0D01*
G02Y1567561I1661J1458D01*
G03X1182206Y1567693I-150J132D01*
G01Y1568313D01*
G02X1182408Y1568516I202J1D01*
G37*
G36*
G01X1303669D02*
X1306489D01*
G02X1306692Y1568313I0J-203D01*
G01Y1567691D01*
G03X1306742Y1567559I200J0D01*
G02Y1564647I-1664J-1456D01*
G03X1306692Y1564515I150J-132D01*
G01Y1562573D01*
G03X1306742Y1562441I200J0D01*
G02Y1559529I-1664J-1456D01*
G03X1306692Y1559397I150J-132D01*
G01Y1558775D01*
G02X1306489Y1558572I-203J0D01*
G01X1303669D01*
G02X1303466Y1558775I0J203D01*
G01Y1559397D01*
G03X1303416Y1559529I-200J0D01*
G02Y1562441I1664J1456D01*
G03X1303466Y1562573I-150J132D01*
G01Y1564515D01*
G03X1303416Y1564647I-200J0D01*
G02Y1567559I1664J1456D01*
G03X1303466Y1567691I-150J132D01*
G01Y1568313D01*
G02X1303669Y1568516I203J0D01*
G37*
G36*
G01X1320992D02*
X1323812D01*
G02X1324014Y1568313I-1J-203D01*
G01Y1567693D01*
G03X1324064Y1567561I200J0D01*
G02Y1564645I-1661J-1458D01*
G03X1324014Y1564513I150J-132D01*
G01Y1562575D01*
G03X1324064Y1562443I200J0D01*
G02Y1559527I-1661J-1458D01*
G03X1324014Y1559395I150J-132D01*
G01Y1558775D01*
G02X1323812Y1558572I-202J-1D01*
G01X1320992D01*
G02X1320790Y1558775I1J203D01*
G01Y1559395D01*
G03X1320740Y1559527I-200J0D01*
G02Y1562443I1661J1458D01*
G03X1320790Y1562575I-150J132D01*
G01Y1564513D01*
G03X1320740Y1564645I-200J0D01*
G02Y1567561I1661J1458D01*
G03X1320790Y1567693I-150J132D01*
G01Y1568313D01*
G02X1320992Y1568516I202J1D01*
G37*
G36*
G01X1338315D02*
X1341135D01*
G02X1341338Y1568313I0J-203D01*
G01Y1567691D01*
G03X1341388Y1567559I200J0D01*
G02Y1564647I-1664J-1456D01*
G03X1341338Y1564515I150J-132D01*
G01Y1562573D01*
G03X1341388Y1562441I200J0D01*
G02Y1559529I-1664J-1456D01*
G03X1341338Y1559397I150J-132D01*
G01Y1558775D01*
G02X1341135Y1558572I-203J0D01*
G01X1338315D01*
G02X1338112Y1558775I0J203D01*
G01Y1559397D01*
G03X1338062Y1559529I-200J0D01*
G02Y1562441I1664J1456D01*
G03X1338112Y1562573I-150J132D01*
G01Y1564515D01*
G03X1338062Y1564647I-200J0D01*
G02Y1567559I1664J1456D01*
G03X1338112Y1567691I-150J132D01*
G01Y1568313D01*
G02X1338315Y1568516I203J0D01*
G37*
G36*
G01X1355637D02*
X1358457D01*
G02X1358660Y1568313I0J-203D01*
G01Y1567691D01*
G03X1358710Y1567559I200J0D01*
G02Y1564647I-1664J-1456D01*
G03X1358660Y1564515I150J-132D01*
G01Y1562573D01*
G03X1358710Y1562441I200J0D01*
G02Y1559529I-1664J-1456D01*
G03X1358660Y1559397I150J-132D01*
G01Y1558775D01*
G02X1358457Y1558572I-203J0D01*
G01X1355637D01*
G02X1355434Y1558775I0J203D01*
G01Y1559397D01*
G03X1355384Y1559529I-200J0D01*
G02Y1562441I1664J1456D01*
G03X1355434Y1562573I-150J132D01*
G01Y1564515D01*
G03X1355384Y1564647I-200J0D01*
G02Y1567559I1664J1456D01*
G03X1355434Y1567691I-150J132D01*
G01Y1568313D01*
G02X1355637Y1568516I203J0D01*
G37*
G36*
G01X1476897D02*
X1479717D01*
G02X1479920Y1568313I0J-203D01*
G01Y1567691D01*
G03X1479970Y1567559I200J0D01*
G02Y1564647I-1664J-1456D01*
G03X1479920Y1564515I150J-132D01*
G01Y1562573D01*
G03X1479970Y1562441I200J0D01*
G02Y1559529I-1664J-1456D01*
G03X1479920Y1559397I150J-132D01*
G01Y1558775D01*
G02X1479717Y1558572I-203J0D01*
G01X1476897D01*
G02X1476694Y1558775I0J203D01*
G01Y1559397D01*
G03X1476644Y1559529I-200J0D01*
G02Y1562441I1664J1456D01*
G03X1476694Y1562573I-150J132D01*
G01Y1564515D01*
G03X1476644Y1564647I-200J0D01*
G02Y1567559I1664J1456D01*
G03X1476694Y1567691I-150J132D01*
G01Y1568313D01*
G02X1476897Y1568516I203J0D01*
G37*
G36*
G01X1650125D02*
X1652945D01*
G02X1653148Y1568313I0J-203D01*
G01Y1567691D01*
G03X1653198Y1567559I200J0D01*
G02Y1564647I-1664J-1456D01*
G03X1653148Y1564515I150J-132D01*
G01Y1562573D01*
G03X1653198Y1562441I200J0D01*
G02Y1559529I-1664J-1456D01*
G03X1653148Y1559397I150J-132D01*
G01Y1558775D01*
G02X1652945Y1558572I-203J0D01*
G01X1650125D01*
G02X1649922Y1558775I0J203D01*
G01Y1559397D01*
G03X1649872Y1559529I-200J0D01*
G02Y1562441I1664J1456D01*
G03X1649922Y1562573I-150J132D01*
G01Y1564515D01*
G03X1649872Y1564647I-200J0D01*
G02Y1567559I1664J1456D01*
G03X1649922Y1567691I-150J132D01*
G01Y1568313D01*
G02X1650125Y1568516I203J0D01*
G37*
G36*
G01X1667448D02*
X1670268D01*
G02X1670470Y1568313I-1J-203D01*
G01Y1567693D01*
G03X1670520Y1567561I200J0D01*
G02Y1564645I-1661J-1458D01*
G03X1670470Y1564513I150J-132D01*
G01Y1562575D01*
G03X1670520Y1562443I200J0D01*
G02Y1559527I-1661J-1458D01*
G03X1670470Y1559395I150J-132D01*
G01Y1558775D01*
G02X1670268Y1558572I-202J-1D01*
G01X1667448D01*
G02X1667246Y1558775I1J203D01*
G01Y1559395D01*
G03X1667196Y1559527I-200J0D01*
G02Y1562443I1661J1458D01*
G03X1667246Y1562575I-150J132D01*
G01Y1564513D01*
G03X1667196Y1564645I-200J0D01*
G02Y1567561I1661J1458D01*
G03X1667246Y1567693I-150J132D01*
G01Y1568313D01*
G02X1667448Y1568516I202J1D01*
G37*
G36*
G01X1684771D02*
X1687591D01*
G02X1687794Y1568313I0J-203D01*
G01Y1567691D01*
G03X1687844Y1567559I200J0D01*
G02Y1564647I-1664J-1456D01*
G03X1687794Y1564515I150J-132D01*
G01Y1562573D01*
G03X1687844Y1562441I200J0D01*
G02Y1559529I-1664J-1456D01*
G03X1687794Y1559397I150J-132D01*
G01Y1558775D01*
G02X1687591Y1558572I-203J0D01*
G01X1684771D01*
G02X1684568Y1558775I0J203D01*
G01Y1559397D01*
G03X1684518Y1559529I-200J0D01*
G02Y1562441I1664J1456D01*
G03X1684568Y1562573I-150J132D01*
G01Y1564515D01*
G03X1684518Y1564647I-200J0D01*
G02Y1567559I1664J1456D01*
G03X1684568Y1567691I-150J132D01*
G01Y1568313D01*
G02X1684771Y1568516I203J0D01*
G37*
G36*
G01X1702093D02*
X1704913D01*
G02X1705116Y1568313I0J-203D01*
G01Y1567691D01*
G03X1705166Y1567559I200J0D01*
G02Y1564647I-1664J-1456D01*
G03X1705116Y1564515I150J-132D01*
G01Y1562573D01*
G03X1705166Y1562441I200J0D01*
G02Y1559529I-1664J-1456D01*
G03X1705116Y1559397I150J-132D01*
G01Y1558775D01*
G02X1704913Y1558572I-203J0D01*
G01X1702093D01*
G02X1701890Y1558775I0J203D01*
G01Y1559397D01*
G03X1701840Y1559529I-200J0D01*
G02Y1562441I1664J1456D01*
G03X1701890Y1562573I-150J132D01*
G01Y1564515D01*
G03X1701840Y1564647I-200J0D01*
G02Y1567559I1664J1456D01*
G03X1701890Y1567691I-150J132D01*
G01Y1568313D01*
G02X1702093Y1568516I203J0D01*
G37*
G36*
G01X134456Y1572846D02*
X137276D01*
G02X137478Y1572644I0J-202D01*
G01Y1572024D01*
G03X137528Y1571892I200J0D01*
G02Y1568976I-1661J-1458D01*
G03X137478Y1568844I150J-132D01*
G01Y1566905D01*
G03X137528Y1566773I200J0D01*
G02Y1563857I-1661J-1458D01*
G03X137478Y1563725I150J-132D01*
G01Y1563106D01*
G02X137276Y1562904I-202J0D01*
G01X134456D01*
G02X134254Y1563106I0J202D01*
G01Y1563725D01*
G03X134204Y1563857I-200J0D01*
G02Y1566773I1661J1458D01*
G03X134254Y1566905I-150J132D01*
G01Y1568844D01*
G03X134204Y1568976I-200J0D01*
G02Y1571892I1661J1458D01*
G03X134254Y1572024I-150J132D01*
G01Y1572644D01*
G02X134456Y1572846I202J0D01*
G37*
G36*
G01X169102D02*
X171922D01*
G02X172124Y1572644I0J-202D01*
G01Y1572024D01*
G03X172174Y1571892I200J0D01*
G02Y1568976I-1661J-1458D01*
G03X172124Y1568844I150J-132D01*
G01Y1566905D01*
G03X172174Y1566773I200J0D01*
G02Y1563857I-1661J-1458D01*
G03X172124Y1563725I150J-132D01*
G01Y1563106D01*
G02X171922Y1562904I-202J0D01*
G01X169102D01*
G02X168900Y1563106I0J202D01*
G01Y1563725D01*
G03X168850Y1563857I-200J0D01*
G02Y1566773I1661J1458D01*
G03X168900Y1566905I-150J132D01*
G01Y1568844D01*
G03X168850Y1568976I-200J0D01*
G02Y1571892I1661J1458D01*
G03X168900Y1572024I-150J132D01*
G01Y1572644D01*
G02X169102Y1572846I202J0D01*
G37*
G36*
G01X307684D02*
X310504D01*
G02X310706Y1572644I0J-202D01*
G01Y1572024D01*
G03X310756Y1571892I200J0D01*
G02Y1568976I-1661J-1458D01*
G03X310706Y1568844I150J-132D01*
G01Y1566905D01*
G03X310756Y1566773I200J0D01*
G02Y1563857I-1661J-1458D01*
G03X310706Y1563725I150J-132D01*
G01Y1563106D01*
G02X310504Y1562904I-202J0D01*
G01X307684D01*
G02X307482Y1563106I0J202D01*
G01Y1563725D01*
G03X307432Y1563857I-200J0D01*
G02Y1566773I1661J1458D01*
G03X307482Y1566905I-150J132D01*
G01Y1568844D01*
G03X307432Y1568976I-200J0D01*
G02Y1571892I1661J1458D01*
G03X307482Y1572024I-150J132D01*
G01Y1572644D01*
G02X307684Y1572846I202J0D01*
G37*
G36*
G01X342330D02*
X345150D01*
G02X345352Y1572644I0J-202D01*
G01Y1572024D01*
G03X345402Y1571892I200J0D01*
G02Y1568976I-1661J-1458D01*
G03X345352Y1568844I150J-132D01*
G01Y1566905D01*
G03X345402Y1566773I200J0D01*
G02Y1563857I-1661J-1458D01*
G03X345352Y1563725I150J-132D01*
G01Y1563106D01*
G02X345150Y1562904I-202J0D01*
G01X342330D01*
G02X342128Y1563106I0J202D01*
G01Y1563725D01*
G03X342078Y1563857I-200J0D01*
G02Y1566773I1661J1458D01*
G03X342128Y1566905I-150J132D01*
G01Y1568844D01*
G03X342078Y1568976I-200J0D01*
G02Y1571892I1661J1458D01*
G03X342128Y1572024I-150J132D01*
G01Y1572644D01*
G02X342330Y1572846I202J0D01*
G37*
G36*
G01X636818D02*
X639638D01*
G02X639840Y1572644I0J-202D01*
G01Y1572024D01*
G03X639890Y1571892I200J0D01*
G02Y1568976I-1661J-1458D01*
G03X639840Y1568844I150J-132D01*
G01Y1566905D01*
G03X639890Y1566773I200J0D01*
G02Y1563857I-1661J-1458D01*
G03X639840Y1563725I150J-132D01*
G01Y1563106D01*
G02X639638Y1562904I-202J0D01*
G01X636818D01*
G02X636616Y1563106I0J202D01*
G01Y1563725D01*
G03X636566Y1563857I-200J0D01*
G02Y1566773I1661J1458D01*
G03X636616Y1566905I-150J132D01*
G01Y1568844D01*
G03X636566Y1568976I-200J0D01*
G02Y1571892I1661J1458D01*
G03X636616Y1572024I-150J132D01*
G01Y1572644D01*
G02X636818Y1572846I202J0D01*
G37*
G36*
G01X671464D02*
X674284D01*
G02X674486Y1572644I0J-202D01*
G01Y1572024D01*
G03X674536Y1571892I200J0D01*
G02Y1568976I-1661J-1458D01*
G03X674486Y1568844I150J-132D01*
G01Y1566905D01*
G03X674536Y1566773I200J0D01*
G02Y1563857I-1661J-1458D01*
G03X674486Y1563725I150J-132D01*
G01Y1563106D01*
G02X674284Y1562904I-202J0D01*
G01X671464D01*
G02X671262Y1563106I0J202D01*
G01Y1563725D01*
G03X671212Y1563857I-200J0D01*
G02Y1566773I1661J1458D01*
G03X671262Y1566905I-150J132D01*
G01Y1568844D01*
G03X671212Y1568976I-200J0D01*
G02Y1571892I1661J1458D01*
G03X671262Y1572024I-150J132D01*
G01Y1572644D01*
G02X671464Y1572846I202J0D01*
G37*
G36*
G01X1156424D02*
X1159244D01*
G02X1159446Y1572644I0J-202D01*
G01Y1572024D01*
G03X1159496Y1571892I200J0D01*
G02Y1568976I-1661J-1458D01*
G03X1159446Y1568844I150J-132D01*
G01Y1566905D01*
G03X1159496Y1566773I200J0D01*
G02Y1563857I-1661J-1458D01*
G03X1159446Y1563725I150J-132D01*
G01Y1563106D01*
G02X1159244Y1562904I-202J0D01*
G01X1156424D01*
G02X1156222Y1563106I0J202D01*
G01Y1563725D01*
G03X1156172Y1563857I-200J0D01*
G02Y1566773I1661J1458D01*
G03X1156222Y1566905I-150J132D01*
G01Y1568844D01*
G03X1156172Y1568976I-200J0D01*
G02Y1571892I1661J1458D01*
G03X1156222Y1572024I-150J132D01*
G01Y1572644D01*
G02X1156424Y1572846I202J0D01*
G37*
G36*
G01X1191070D02*
X1193890D01*
G02X1194092Y1572644I0J-202D01*
G01Y1572024D01*
G03X1194142Y1571892I200J0D01*
G02Y1568976I-1661J-1458D01*
G03X1194092Y1568844I150J-132D01*
G01Y1566905D01*
G03X1194142Y1566773I200J0D01*
G02Y1563857I-1661J-1458D01*
G03X1194092Y1563725I150J-132D01*
G01Y1563106D01*
G02X1193890Y1562904I-202J0D01*
G01X1191070D01*
G02X1190868Y1563106I0J202D01*
G01Y1563725D01*
G03X1190818Y1563857I-200J0D01*
G02Y1566773I1661J1458D01*
G03X1190868Y1566905I-150J132D01*
G01Y1568844D01*
G03X1190818Y1568976I-200J0D01*
G02Y1571892I1661J1458D01*
G03X1190868Y1572024I-150J132D01*
G01Y1572644D01*
G02X1191070Y1572846I202J0D01*
G37*
G36*
G01X1312330D02*
X1315150D01*
G02X1315352Y1572644I0J-202D01*
G01Y1572024D01*
G03X1315402Y1571892I200J0D01*
G02Y1568976I-1661J-1458D01*
G03X1315352Y1568844I150J-132D01*
G01Y1566905D01*
G03X1315402Y1566773I200J0D01*
G02Y1563857I-1661J-1458D01*
G03X1315352Y1563725I150J-132D01*
G01Y1563106D01*
G02X1315150Y1562904I-202J0D01*
G01X1312330D01*
G02X1312128Y1563106I0J202D01*
G01Y1563725D01*
G03X1312078Y1563857I-200J0D01*
G02Y1566773I1661J1458D01*
G03X1312128Y1566905I-150J132D01*
G01Y1568844D01*
G03X1312078Y1568976I-200J0D01*
G02Y1571892I1661J1458D01*
G03X1312128Y1572024I-150J132D01*
G01Y1572644D01*
G02X1312330Y1572846I202J0D01*
G37*
G36*
G01X1346976D02*
X1349796D01*
G02X1349998Y1572644I0J-202D01*
G01Y1572024D01*
G03X1350048Y1571892I200J0D01*
G02Y1568976I-1661J-1458D01*
G03X1349998Y1568844I150J-132D01*
G01Y1566905D01*
G03X1350048Y1566773I200J0D01*
G02Y1563857I-1661J-1458D01*
G03X1349998Y1563725I150J-132D01*
G01Y1563106D01*
G02X1349796Y1562904I-202J0D01*
G01X1346976D01*
G02X1346774Y1563106I0J202D01*
G01Y1563725D01*
G03X1346724Y1563857I-200J0D01*
G02Y1566773I1661J1458D01*
G03X1346774Y1566905I-150J132D01*
G01Y1568844D01*
G03X1346724Y1568976I-200J0D01*
G02Y1571892I1661J1458D01*
G03X1346774Y1572024I-150J132D01*
G01Y1572644D01*
G02X1346976Y1572846I202J0D01*
G37*
G36*
G01X1658786D02*
X1661606D01*
G02X1661808Y1572644I0J-202D01*
G01Y1572024D01*
G03X1661858Y1571892I200J0D01*
G02Y1568976I-1661J-1458D01*
G03X1661808Y1568844I150J-132D01*
G01Y1566905D01*
G03X1661858Y1566773I200J0D01*
G02Y1563857I-1661J-1458D01*
G03X1661808Y1563725I150J-132D01*
G01Y1563106D01*
G02X1661606Y1562904I-202J0D01*
G01X1658786D01*
G02X1658584Y1563106I0J202D01*
G01Y1563725D01*
G03X1658534Y1563857I-200J0D01*
G02Y1566773I1661J1458D01*
G03X1658584Y1566905I-150J132D01*
G01Y1568844D01*
G03X1658534Y1568976I-200J0D01*
G02Y1571892I1661J1458D01*
G03X1658584Y1572024I-150J132D01*
G01Y1572644D01*
G02X1658786Y1572846I202J0D01*
G37*
G36*
G01X1693432D02*
X1696252D01*
G02X1696454Y1572644I0J-202D01*
G01Y1572024D01*
G03X1696504Y1571892I200J0D01*
G02Y1568976I-1661J-1458D01*
G03X1696454Y1568844I150J-132D01*
G01Y1566905D01*
G03X1696504Y1566773I200J0D01*
G02Y1563857I-1661J-1458D01*
G03X1696454Y1563725I150J-132D01*
G01Y1563106D01*
G02X1696252Y1562904I-202J0D01*
G01X1693432D01*
G02X1693230Y1563106I0J202D01*
G01Y1563725D01*
G03X1693180Y1563857I-200J0D01*
G02Y1566773I1661J1458D01*
G03X1693230Y1566905I-150J132D01*
G01Y1568844D01*
G03X1693180Y1568976I-200J0D01*
G02Y1571892I1661J1458D01*
G03X1693230Y1572024I-150J132D01*
G01Y1572644D01*
G02X1693432Y1572846I202J0D01*
G37*
G36*
G01X117133D02*
X119953D01*
G02X120156Y1572644I1J-202D01*
G01Y1572022D01*
G03X120206Y1571890I200J0D01*
G02Y1568978I-1664J-1456D01*
G03X120156Y1568846I150J-132D01*
G01Y1566903D01*
G03X120206Y1566771I200J0D01*
G02Y1563859I-1664J-1456D01*
G03X120156Y1563727I150J-132D01*
G01Y1563106D01*
G02X119953Y1562904I-203J1D01*
G01X117133D01*
G02X116930Y1563106I-1J202D01*
G01Y1563727D01*
G03X116880Y1563859I-200J0D01*
G02Y1566771I1664J1456D01*
G03X116930Y1566903I-150J132D01*
G01Y1568846D01*
G03X116880Y1568978I-200J0D01*
G02Y1571890I1664J1456D01*
G03X116930Y1572022I-150J132D01*
G01Y1572644D01*
G02X117133Y1572846I203J-1D01*
G37*
G36*
G01X151779D02*
X154599D01*
G02X154802Y1572644I1J-202D01*
G01Y1572022D01*
G03X154852Y1571890I200J0D01*
G02Y1568978I-1664J-1456D01*
G03X154802Y1568846I150J-132D01*
G01Y1566903D01*
G03X154852Y1566771I200J0D01*
G02Y1563859I-1664J-1456D01*
G03X154802Y1563727I150J-132D01*
G01Y1563106D01*
G02X154599Y1562904I-203J1D01*
G01X151779D01*
G02X151576Y1563106I-1J202D01*
G01Y1563727D01*
G03X151526Y1563859I-200J0D01*
G02Y1566771I1664J1456D01*
G03X151576Y1566903I-150J132D01*
G01Y1568846D01*
G03X151526Y1568978I-200J0D01*
G02Y1571890I1664J1456D01*
G03X151576Y1572022I-150J132D01*
G01Y1572644D01*
G02X151779Y1572846I203J-1D01*
G37*
G36*
G01X290361D02*
X293181D01*
G02X293384Y1572644I1J-202D01*
G01Y1572022D01*
G03X293434Y1571890I200J0D01*
G02Y1568978I-1664J-1456D01*
G03X293384Y1568846I150J-132D01*
G01Y1566903D01*
G03X293434Y1566771I200J0D01*
G02Y1563859I-1664J-1456D01*
G03X293384Y1563727I150J-132D01*
G01Y1563106D01*
G02X293181Y1562904I-203J1D01*
G01X290361D01*
G02X290158Y1563106I-1J202D01*
G01Y1563727D01*
G03X290108Y1563859I-200J0D01*
G02Y1566771I1664J1456D01*
G03X290158Y1566903I-150J132D01*
G01Y1568846D01*
G03X290108Y1568978I-200J0D01*
G02Y1571890I1664J1456D01*
G03X290158Y1572022I-150J132D01*
G01Y1572644D01*
G02X290361Y1572846I203J-1D01*
G37*
G36*
G01X325007D02*
X327827D01*
G02X328030Y1572644I1J-202D01*
G01Y1572022D01*
G03X328080Y1571890I200J0D01*
G02Y1568978I-1664J-1456D01*
G03X328030Y1568846I150J-132D01*
G01Y1566903D01*
G03X328080Y1566771I200J0D01*
G02Y1563859I-1664J-1456D01*
G03X328030Y1563727I150J-132D01*
G01Y1563106D01*
G02X327827Y1562904I-203J1D01*
G01X325007D01*
G02X324804Y1563106I-1J202D01*
G01Y1563727D01*
G03X324754Y1563859I-200J0D01*
G02Y1566771I1664J1456D01*
G03X324804Y1566903I-150J132D01*
G01Y1568846D01*
G03X324754Y1568978I-200J0D01*
G02Y1571890I1664J1456D01*
G03X324804Y1572022I-150J132D01*
G01Y1572644D01*
G02X325007Y1572846I203J-1D01*
G37*
G36*
G01X515559D02*
X518379D01*
G02X518582Y1572644I1J-202D01*
G01Y1572022D01*
G03X518632Y1571890I200J0D01*
G02Y1568978I-1664J-1456D01*
G03X518582Y1568846I150J-132D01*
G01Y1566903D01*
G03X518632Y1566771I200J0D01*
G02Y1563859I-1664J-1456D01*
G03X518582Y1563727I150J-132D01*
G01Y1563106D01*
G02X518379Y1562904I-203J1D01*
G01X515559D01*
G02X515356Y1563106I-1J202D01*
G01Y1563727D01*
G03X515306Y1563859I-200J0D01*
G02Y1566771I1664J1456D01*
G03X515356Y1566903I-150J132D01*
G01Y1568846D01*
G03X515306Y1568978I-200J0D01*
G02Y1571890I1664J1456D01*
G03X515356Y1572022I-150J132D01*
G01Y1572644D01*
G02X515559Y1572846I203J-1D01*
G37*
G36*
G01X654141D02*
X656961D01*
G02X657164Y1572644I1J-202D01*
G01Y1572022D01*
G03X657214Y1571890I200J0D01*
G02Y1568978I-1664J-1456D01*
G03X657164Y1568846I150J-132D01*
G01Y1566903D01*
G03X657214Y1566771I200J0D01*
G02Y1563859I-1664J-1456D01*
G03X657164Y1563727I150J-132D01*
G01Y1563106D01*
G02X656961Y1562904I-203J1D01*
G01X654141D01*
G02X653938Y1563106I-1J202D01*
G01Y1563727D01*
G03X653888Y1563859I-200J0D01*
G02Y1566771I1664J1456D01*
G03X653938Y1566903I-150J132D01*
G01Y1568846D01*
G03X653888Y1568978I-200J0D01*
G02Y1571890I1664J1456D01*
G03X653938Y1572022I-150J132D01*
G01Y1572644D01*
G02X654141Y1572846I203J-1D01*
G37*
G36*
G01X688787D02*
X691607D01*
G02X691810Y1572644I1J-202D01*
G01Y1572022D01*
G03X691860Y1571890I200J0D01*
G02Y1568978I-1664J-1456D01*
G03X691810Y1568846I150J-132D01*
G01Y1566903D01*
G03X691860Y1566771I200J0D01*
G02Y1563859I-1664J-1456D01*
G03X691810Y1563727I150J-132D01*
G01Y1563106D01*
G02X691607Y1562904I-203J1D01*
G01X688787D01*
G02X688584Y1563106I-1J202D01*
G01Y1563727D01*
G03X688534Y1563859I-200J0D01*
G02Y1566771I1664J1456D01*
G03X688584Y1566903I-150J132D01*
G01Y1568846D01*
G03X688534Y1568978I-200J0D01*
G02Y1571890I1664J1456D01*
G03X688584Y1572022I-150J132D01*
G01Y1572644D01*
G02X688787Y1572846I203J-1D01*
G37*
G36*
G01X1139101D02*
X1141921D01*
G02X1142124Y1572644I1J-202D01*
G01Y1572022D01*
G03X1142174Y1571890I200J0D01*
G02Y1568978I-1664J-1456D01*
G03X1142124Y1568846I150J-132D01*
G01Y1566903D01*
G03X1142174Y1566771I200J0D01*
G02Y1563859I-1664J-1456D01*
G03X1142124Y1563727I150J-132D01*
G01Y1563106D01*
G02X1141921Y1562904I-203J1D01*
G01X1139101D01*
G02X1138898Y1563106I-1J202D01*
G01Y1563727D01*
G03X1138848Y1563859I-200J0D01*
G02Y1566771I1664J1456D01*
G03X1138898Y1566903I-150J132D01*
G01Y1568846D01*
G03X1138848Y1568978I-200J0D01*
G02Y1571890I1664J1456D01*
G03X1138898Y1572022I-150J132D01*
G01Y1572644D01*
G02X1139101Y1572846I203J-1D01*
G37*
G36*
G01X1173747D02*
X1176567D01*
G02X1176770Y1572644I1J-202D01*
G01Y1572022D01*
G03X1176820Y1571890I200J0D01*
G02Y1568978I-1664J-1456D01*
G03X1176770Y1568846I150J-132D01*
G01Y1566903D01*
G03X1176820Y1566771I200J0D01*
G02Y1563859I-1664J-1456D01*
G03X1176770Y1563727I150J-132D01*
G01Y1563106D01*
G02X1176567Y1562904I-203J1D01*
G01X1173747D01*
G02X1173544Y1563106I-1J202D01*
G01Y1563727D01*
G03X1173494Y1563859I-200J0D01*
G02Y1566771I1664J1456D01*
G03X1173544Y1566903I-150J132D01*
G01Y1568846D01*
G03X1173494Y1568978I-200J0D01*
G02Y1571890I1664J1456D01*
G03X1173544Y1572022I-150J132D01*
G01Y1572644D01*
G02X1173747Y1572846I203J-1D01*
G37*
G36*
G01X1329653D02*
X1332473D01*
G02X1332676Y1572644I1J-202D01*
G01Y1572022D01*
G03X1332726Y1571890I200J0D01*
G02Y1568978I-1664J-1456D01*
G03X1332676Y1568846I150J-132D01*
G01Y1566903D01*
G03X1332726Y1566771I200J0D01*
G02Y1563859I-1664J-1456D01*
G03X1332676Y1563727I150J-132D01*
G01Y1563106D01*
G02X1332473Y1562904I-203J1D01*
G01X1329653D01*
G02X1329450Y1563106I-1J202D01*
G01Y1563727D01*
G03X1329400Y1563859I-200J0D01*
G02Y1566771I1664J1456D01*
G03X1329450Y1566903I-150J132D01*
G01Y1568846D01*
G03X1329400Y1568978I-200J0D01*
G02Y1571890I1664J1456D01*
G03X1329450Y1572022I-150J132D01*
G01Y1572644D01*
G02X1329653Y1572846I203J-1D01*
G37*
G36*
G01X1364299D02*
X1367119D01*
G02X1367322Y1572644I1J-202D01*
G01Y1572022D01*
G03X1367372Y1571890I200J0D01*
G02Y1568978I-1664J-1456D01*
G03X1367322Y1568846I150J-132D01*
G01Y1566903D01*
G03X1367372Y1566771I200J0D01*
G02Y1563859I-1664J-1456D01*
G03X1367322Y1563727I150J-132D01*
G01Y1563106D01*
G02X1367119Y1562904I-203J1D01*
G01X1364299D01*
G02X1364096Y1563106I-1J202D01*
G01Y1563727D01*
G03X1364046Y1563859I-200J0D01*
G02Y1566771I1664J1456D01*
G03X1364096Y1566903I-150J132D01*
G01Y1568846D01*
G03X1364046Y1568978I-200J0D01*
G02Y1571890I1664J1456D01*
G03X1364096Y1572022I-150J132D01*
G01Y1572644D01*
G02X1364299Y1572846I203J-1D01*
G37*
G36*
G01X1676109D02*
X1678929D01*
G02X1679132Y1572644I1J-202D01*
G01Y1572022D01*
G03X1679182Y1571890I200J0D01*
G02Y1568978I-1664J-1456D01*
G03X1679132Y1568846I150J-132D01*
G01Y1566903D01*
G03X1679182Y1566771I200J0D01*
G02Y1563859I-1664J-1456D01*
G03X1679132Y1563727I150J-132D01*
G01Y1563106D01*
G02X1678929Y1562904I-203J1D01*
G01X1676109D01*
G02X1675906Y1563106I-1J202D01*
G01Y1563727D01*
G03X1675856Y1563859I-200J0D01*
G02Y1566771I1664J1456D01*
G03X1675906Y1566903I-150J132D01*
G01Y1568846D01*
G03X1675856Y1568978I-200J0D01*
G02Y1571890I1664J1456D01*
G03X1675906Y1572022I-150J132D01*
G01Y1572644D01*
G02X1676109Y1572846I203J-1D01*
G37*
G36*
G01X1710755D02*
X1713575D01*
G02X1713778Y1572644I1J-202D01*
G01Y1572022D01*
G03X1713828Y1571890I200J0D01*
G02Y1568978I-1664J-1456D01*
G03X1713778Y1568846I150J-132D01*
G01Y1566903D01*
G03X1713828Y1566771I200J0D01*
G02Y1563859I-1664J-1456D01*
G03X1713778Y1563727I150J-132D01*
G01Y1563106D01*
G02X1713575Y1562904I-203J1D01*
G01X1710755D01*
G02X1710552Y1563106I-1J202D01*
G01Y1563727D01*
G03X1710502Y1563859I-200J0D01*
G02Y1566771I1664J1456D01*
G03X1710552Y1566903I-150J132D01*
G01Y1568846D01*
G03X1710502Y1568978I-200J0D01*
G02Y1571890I1664J1456D01*
G03X1710552Y1572022I-150J132D01*
G01Y1572644D01*
G02X1710755Y1572846I203J-1D01*
G37*
G36*
G01X108472Y1583870D02*
X111292D01*
G02X111494Y1583667I-1J-203D01*
G01Y1583047D01*
G03X111544Y1582915I200J0D01*
G02Y1579999I-1661J-1458D01*
G03X111494Y1579867I150J-132D01*
G01Y1577929D01*
G03X111544Y1577797I200J0D01*
G02Y1574881I-1661J-1458D01*
G03X111494Y1574749I150J-132D01*
G01Y1574129D01*
G02X111292Y1573926I-202J-1D01*
G01X108472D01*
G02X108270Y1574129I1J203D01*
G01Y1574749D01*
G03X108220Y1574881I-200J0D01*
G02Y1577797I1661J1458D01*
G03X108270Y1577929I-150J132D01*
G01Y1579867D01*
G03X108220Y1579999I-200J0D01*
G02Y1582915I1661J1458D01*
G03X108270Y1583047I-150J132D01*
G01Y1583667D01*
G02X108472Y1583870I202J1D01*
G37*
G36*
G01X125795D02*
X128615D01*
G02X128818Y1583667I0J-203D01*
G01Y1583045D01*
G03X128868Y1582913I200J0D01*
G02Y1580001I-1664J-1456D01*
G03X128818Y1579869I150J-132D01*
G01Y1577927D01*
G03X128868Y1577795I200J0D01*
G02Y1574883I-1664J-1456D01*
G03X128818Y1574751I150J-132D01*
G01Y1574129D01*
G02X128615Y1573926I-203J0D01*
G01X125795D01*
G02X125592Y1574129I0J203D01*
G01Y1574751D01*
G03X125542Y1574883I-200J0D01*
G02Y1577795I1664J1456D01*
G03X125592Y1577927I-150J132D01*
G01Y1579869D01*
G03X125542Y1580001I-200J0D01*
G02Y1582913I1664J1456D01*
G03X125592Y1583045I-150J132D01*
G01Y1583667D01*
G02X125795Y1583870I203J0D01*
G37*
G36*
G01X143118D02*
X145938D01*
G02X146140Y1583667I-1J-203D01*
G01Y1583047D01*
G03X146190Y1582915I200J0D01*
G02Y1579999I-1661J-1458D01*
G03X146140Y1579867I150J-132D01*
G01Y1577929D01*
G03X146190Y1577797I200J0D01*
G02Y1574881I-1661J-1458D01*
G03X146140Y1574749I150J-132D01*
G01Y1574129D01*
G02X145938Y1573926I-202J-1D01*
G01X143118D01*
G02X142916Y1574129I1J203D01*
G01Y1574749D01*
G03X142866Y1574881I-200J0D01*
G02Y1577797I1661J1458D01*
G03X142916Y1577929I-150J132D01*
G01Y1579867D01*
G03X142866Y1579999I-200J0D01*
G02Y1582915I1661J1458D01*
G03X142916Y1583047I-150J132D01*
G01Y1583667D01*
G02X143118Y1583870I202J1D01*
G37*
G36*
G01X160440D02*
X163260D01*
G02X163462Y1583667I-1J-203D01*
G01Y1583047D01*
G03X163512Y1582915I200J0D01*
G02Y1579999I-1661J-1458D01*
G03X163462Y1579867I150J-132D01*
G01Y1577929D01*
G03X163512Y1577797I200J0D01*
G02Y1574881I-1661J-1458D01*
G03X163462Y1574749I150J-132D01*
G01Y1574129D01*
G02X163260Y1573926I-202J-1D01*
G01X160440D01*
G02X160238Y1574129I1J203D01*
G01Y1574749D01*
G03X160188Y1574881I-200J0D01*
G02Y1577797I1661J1458D01*
G03X160238Y1577929I-150J132D01*
G01Y1579867D01*
G03X160188Y1579999I-200J0D01*
G02Y1582915I1661J1458D01*
G03X160238Y1583047I-150J132D01*
G01Y1583667D01*
G02X160440Y1583870I202J1D01*
G37*
G36*
G01X281700D02*
X284520D01*
G02X284722Y1583667I-1J-203D01*
G01Y1583047D01*
G03X284772Y1582915I200J0D01*
G02Y1579999I-1661J-1458D01*
G03X284722Y1579867I150J-132D01*
G01Y1577929D01*
G03X284772Y1577797I200J0D01*
G02Y1574881I-1661J-1458D01*
G03X284722Y1574749I150J-132D01*
G01Y1574129D01*
G02X284520Y1573926I-202J-1D01*
G01X281700D01*
G02X281498Y1574129I1J203D01*
G01Y1574749D01*
G03X281448Y1574881I-200J0D01*
G02Y1577797I1661J1458D01*
G03X281498Y1577929I-150J132D01*
G01Y1579867D01*
G03X281448Y1579999I-200J0D01*
G02Y1582915I1661J1458D01*
G03X281498Y1583047I-150J132D01*
G01Y1583667D01*
G02X281700Y1583870I202J1D01*
G37*
G36*
G01X299023D02*
X301843D01*
G02X302046Y1583667I0J-203D01*
G01Y1583045D01*
G03X302096Y1582913I200J0D01*
G02Y1580001I-1664J-1456D01*
G03X302046Y1579869I150J-132D01*
G01Y1577927D01*
G03X302096Y1577795I200J0D01*
G02Y1574883I-1664J-1456D01*
G03X302046Y1574751I150J-132D01*
G01Y1574129D01*
G02X301843Y1573926I-203J0D01*
G01X299023D01*
G02X298820Y1574129I0J203D01*
G01Y1574751D01*
G03X298770Y1574883I-200J0D01*
G02Y1577795I1664J1456D01*
G03X298820Y1577927I-150J132D01*
G01Y1579869D01*
G03X298770Y1580001I-200J0D01*
G02Y1582913I1664J1456D01*
G03X298820Y1583045I-150J132D01*
G01Y1583667D01*
G02X299023Y1583870I203J0D01*
G37*
G36*
G01X316346D02*
X319166D01*
G02X319368Y1583667I-1J-203D01*
G01Y1583047D01*
G03X319418Y1582915I200J0D01*
G02Y1579999I-1661J-1458D01*
G03X319368Y1579867I150J-132D01*
G01Y1577929D01*
G03X319418Y1577797I200J0D01*
G02Y1574881I-1661J-1458D01*
G03X319368Y1574749I150J-132D01*
G01Y1574129D01*
G02X319166Y1573926I-202J-1D01*
G01X316346D01*
G02X316144Y1574129I1J203D01*
G01Y1574749D01*
G03X316094Y1574881I-200J0D01*
G02Y1577797I1661J1458D01*
G03X316144Y1577929I-150J132D01*
G01Y1579867D01*
G03X316094Y1579999I-200J0D01*
G02Y1582915I1661J1458D01*
G03X316144Y1583047I-150J132D01*
G01Y1583667D01*
G02X316346Y1583870I202J1D01*
G37*
G36*
G01X333668D02*
X336488D01*
G02X336690Y1583667I-1J-203D01*
G01Y1583047D01*
G03X336740Y1582915I200J0D01*
G02Y1579999I-1661J-1458D01*
G03X336690Y1579867I150J-132D01*
G01Y1577929D01*
G03X336740Y1577797I200J0D01*
G02Y1574881I-1661J-1458D01*
G03X336690Y1574749I150J-132D01*
G01Y1574129D01*
G02X336488Y1573926I-202J-1D01*
G01X333668D01*
G02X333466Y1574129I1J203D01*
G01Y1574749D01*
G03X333416Y1574881I-200J0D01*
G02Y1577797I1661J1458D01*
G03X333466Y1577929I-150J132D01*
G01Y1579867D01*
G03X333416Y1579999I-200J0D01*
G02Y1582915I1661J1458D01*
G03X333466Y1583047I-150J132D01*
G01Y1583667D01*
G02X333668Y1583870I202J1D01*
G37*
G36*
G01X628157D02*
X630977D01*
G02X631180Y1583667I0J-203D01*
G01Y1583045D01*
G03X631230Y1582913I200J0D01*
G02Y1580001I-1664J-1456D01*
G03X631180Y1579869I150J-132D01*
G01Y1577927D01*
G03X631230Y1577795I200J0D01*
G02Y1574883I-1664J-1456D01*
G03X631180Y1574751I150J-132D01*
G01Y1574129D01*
G02X630977Y1573926I-203J0D01*
G01X628157D01*
G02X627954Y1574129I0J203D01*
G01Y1574751D01*
G03X627904Y1574883I-200J0D01*
G02Y1577795I1664J1456D01*
G03X627954Y1577927I-150J132D01*
G01Y1579869D01*
G03X627904Y1580001I-200J0D01*
G02Y1582913I1664J1456D01*
G03X627954Y1583045I-150J132D01*
G01Y1583667D01*
G02X628157Y1583870I203J0D01*
G37*
G36*
G01X645480D02*
X648300D01*
G02X648502Y1583667I-1J-203D01*
G01Y1583047D01*
G03X648552Y1582915I200J0D01*
G02Y1579999I-1661J-1458D01*
G03X648502Y1579867I150J-132D01*
G01Y1577929D01*
G03X648552Y1577797I200J0D01*
G02Y1574881I-1661J-1458D01*
G03X648502Y1574749I150J-132D01*
G01Y1574129D01*
G02X648300Y1573926I-202J-1D01*
G01X645480D01*
G02X645278Y1574129I1J203D01*
G01Y1574749D01*
G03X645228Y1574881I-200J0D01*
G02Y1577797I1661J1458D01*
G03X645278Y1577929I-150J132D01*
G01Y1579867D01*
G03X645228Y1579999I-200J0D01*
G02Y1582915I1661J1458D01*
G03X645278Y1583047I-150J132D01*
G01Y1583667D01*
G02X645480Y1583870I202J1D01*
G37*
G36*
G01X662803D02*
X665623D01*
G02X665826Y1583667I0J-203D01*
G01Y1583045D01*
G03X665876Y1582913I200J0D01*
G02Y1580001I-1664J-1456D01*
G03X665826Y1579869I150J-132D01*
G01Y1577927D01*
G03X665876Y1577795I200J0D01*
G02Y1574883I-1664J-1456D01*
G03X665826Y1574751I150J-132D01*
G01Y1574129D01*
G02X665623Y1573926I-203J0D01*
G01X662803D01*
G02X662600Y1574129I0J203D01*
G01Y1574751D01*
G03X662550Y1574883I-200J0D01*
G02Y1577795I1664J1456D01*
G03X662600Y1577927I-150J132D01*
G01Y1579869D01*
G03X662550Y1580001I-200J0D01*
G02Y1582913I1664J1456D01*
G03X662600Y1583045I-150J132D01*
G01Y1583667D01*
G02X662803Y1583870I203J0D01*
G37*
G36*
G01X680125D02*
X682945D01*
G02X683148Y1583667I0J-203D01*
G01Y1583045D01*
G03X683198Y1582913I200J0D01*
G02Y1580001I-1664J-1456D01*
G03X683148Y1579869I150J-132D01*
G01Y1577927D01*
G03X683198Y1577795I200J0D01*
G02Y1574883I-1664J-1456D01*
G03X683148Y1574751I150J-132D01*
G01Y1574129D01*
G02X682945Y1573926I-203J0D01*
G01X680125D01*
G02X679922Y1574129I0J203D01*
G01Y1574751D01*
G03X679872Y1574883I-200J0D01*
G02Y1577795I1664J1456D01*
G03X679922Y1577927I-150J132D01*
G01Y1579869D01*
G03X679872Y1580001I-200J0D01*
G02Y1582913I1664J1456D01*
G03X679922Y1583045I-150J132D01*
G01Y1583667D01*
G02X680125Y1583870I203J0D01*
G37*
G36*
G01X1130440D02*
X1133260D01*
G02X1133462Y1583667I-1J-203D01*
G01Y1583047D01*
G03X1133512Y1582915I200J0D01*
G02Y1579999I-1661J-1458D01*
G03X1133462Y1579867I150J-132D01*
G01Y1577929D01*
G03X1133512Y1577797I200J0D01*
G02Y1574881I-1661J-1458D01*
G03X1133462Y1574749I150J-132D01*
G01Y1574129D01*
G02X1133260Y1573926I-202J-1D01*
G01X1130440D01*
G02X1130238Y1574129I1J203D01*
G01Y1574749D01*
G03X1130188Y1574881I-200J0D01*
G02Y1577797I1661J1458D01*
G03X1130238Y1577929I-150J132D01*
G01Y1579867D01*
G03X1130188Y1579999I-200J0D01*
G02Y1582915I1661J1458D01*
G03X1130238Y1583047I-150J132D01*
G01Y1583667D01*
G02X1130440Y1583870I202J1D01*
G37*
G36*
G01X1147763D02*
X1150583D01*
G02X1150786Y1583667I0J-203D01*
G01Y1583045D01*
G03X1150836Y1582913I200J0D01*
G02Y1580001I-1664J-1456D01*
G03X1150786Y1579869I150J-132D01*
G01Y1577927D01*
G03X1150836Y1577795I200J0D01*
G02Y1574883I-1664J-1456D01*
G03X1150786Y1574751I150J-132D01*
G01Y1574129D01*
G02X1150583Y1573926I-203J0D01*
G01X1147763D01*
G02X1147560Y1574129I0J203D01*
G01Y1574751D01*
G03X1147510Y1574883I-200J0D01*
G02Y1577795I1664J1456D01*
G03X1147560Y1577927I-150J132D01*
G01Y1579869D01*
G03X1147510Y1580001I-200J0D01*
G02Y1582913I1664J1456D01*
G03X1147560Y1583045I-150J132D01*
G01Y1583667D01*
G02X1147763Y1583870I203J0D01*
G37*
G36*
G01X1165086D02*
X1167906D01*
G02X1168108Y1583667I-1J-203D01*
G01Y1583047D01*
G03X1168158Y1582915I200J0D01*
G02Y1579999I-1661J-1458D01*
G03X1168108Y1579867I150J-132D01*
G01Y1577929D01*
G03X1168158Y1577797I200J0D01*
G02Y1574881I-1661J-1458D01*
G03X1168108Y1574749I150J-132D01*
G01Y1574129D01*
G02X1167906Y1573926I-202J-1D01*
G01X1165086D01*
G02X1164884Y1574129I1J203D01*
G01Y1574749D01*
G03X1164834Y1574881I-200J0D01*
G02Y1577797I1661J1458D01*
G03X1164884Y1577929I-150J132D01*
G01Y1579867D01*
G03X1164834Y1579999I-200J0D01*
G02Y1582915I1661J1458D01*
G03X1164884Y1583047I-150J132D01*
G01Y1583667D01*
G02X1165086Y1583870I202J1D01*
G37*
G36*
G01X1182408D02*
X1185228D01*
G02X1185430Y1583667I-1J-203D01*
G01Y1583047D01*
G03X1185480Y1582915I200J0D01*
G02Y1579999I-1661J-1458D01*
G03X1185430Y1579867I150J-132D01*
G01Y1577929D01*
G03X1185480Y1577797I200J0D01*
G02Y1574881I-1661J-1458D01*
G03X1185430Y1574749I150J-132D01*
G01Y1574129D01*
G02X1185228Y1573926I-202J-1D01*
G01X1182408D01*
G02X1182206Y1574129I1J203D01*
G01Y1574749D01*
G03X1182156Y1574881I-200J0D01*
G02Y1577797I1661J1458D01*
G03X1182206Y1577929I-150J132D01*
G01Y1579867D01*
G03X1182156Y1579999I-200J0D01*
G02Y1582915I1661J1458D01*
G03X1182206Y1583047I-150J132D01*
G01Y1583667D01*
G02X1182408Y1583870I202J1D01*
G37*
G36*
G01X1303669D02*
X1306489D01*
G02X1306692Y1583667I0J-203D01*
G01Y1583045D01*
G03X1306742Y1582913I200J0D01*
G02Y1580001I-1664J-1456D01*
G03X1306692Y1579869I150J-132D01*
G01Y1577927D01*
G03X1306742Y1577795I200J0D01*
G02Y1574883I-1664J-1456D01*
G03X1306692Y1574751I150J-132D01*
G01Y1574129D01*
G02X1306489Y1573926I-203J0D01*
G01X1303669D01*
G02X1303466Y1574129I0J203D01*
G01Y1574751D01*
G03X1303416Y1574883I-200J0D01*
G02Y1577795I1664J1456D01*
G03X1303466Y1577927I-150J132D01*
G01Y1579869D01*
G03X1303416Y1580001I-200J0D01*
G02Y1582913I1664J1456D01*
G03X1303466Y1583045I-150J132D01*
G01Y1583667D01*
G02X1303669Y1583870I203J0D01*
G37*
G36*
G01X1320992D02*
X1323812D01*
G02X1324014Y1583667I-1J-203D01*
G01Y1583047D01*
G03X1324064Y1582915I200J0D01*
G02Y1579999I-1661J-1458D01*
G03X1324014Y1579867I150J-132D01*
G01Y1577929D01*
G03X1324064Y1577797I200J0D01*
G02Y1574881I-1661J-1458D01*
G03X1324014Y1574749I150J-132D01*
G01Y1574129D01*
G02X1323812Y1573926I-202J-1D01*
G01X1320992D01*
G02X1320790Y1574129I1J203D01*
G01Y1574749D01*
G03X1320740Y1574881I-200J0D01*
G02Y1577797I1661J1458D01*
G03X1320790Y1577929I-150J132D01*
G01Y1579867D01*
G03X1320740Y1579999I-200J0D01*
G02Y1582915I1661J1458D01*
G03X1320790Y1583047I-150J132D01*
G01Y1583667D01*
G02X1320992Y1583870I202J1D01*
G37*
G36*
G01X1338315D02*
X1341135D01*
G02X1341338Y1583667I0J-203D01*
G01Y1583045D01*
G03X1341388Y1582913I200J0D01*
G02Y1580001I-1664J-1456D01*
G03X1341338Y1579869I150J-132D01*
G01Y1577927D01*
G03X1341388Y1577795I200J0D01*
G02Y1574883I-1664J-1456D01*
G03X1341338Y1574751I150J-132D01*
G01Y1574129D01*
G02X1341135Y1573926I-203J0D01*
G01X1338315D01*
G02X1338112Y1574129I0J203D01*
G01Y1574751D01*
G03X1338062Y1574883I-200J0D01*
G02Y1577795I1664J1456D01*
G03X1338112Y1577927I-150J132D01*
G01Y1579869D01*
G03X1338062Y1580001I-200J0D01*
G02Y1582913I1664J1456D01*
G03X1338112Y1583045I-150J132D01*
G01Y1583667D01*
G02X1338315Y1583870I203J0D01*
G37*
G36*
G01X1355637D02*
X1358457D01*
G02X1358660Y1583667I0J-203D01*
G01Y1583045D01*
G03X1358710Y1582913I200J0D01*
G02Y1580001I-1664J-1456D01*
G03X1358660Y1579869I150J-132D01*
G01Y1577927D01*
G03X1358710Y1577795I200J0D01*
G02Y1574883I-1664J-1456D01*
G03X1358660Y1574751I150J-132D01*
G01Y1574129D01*
G02X1358457Y1573926I-203J0D01*
G01X1355637D01*
G02X1355434Y1574129I0J203D01*
G01Y1574751D01*
G03X1355384Y1574883I-200J0D01*
G02Y1577795I1664J1456D01*
G03X1355434Y1577927I-150J132D01*
G01Y1579869D01*
G03X1355384Y1580001I-200J0D01*
G02Y1582913I1664J1456D01*
G03X1355434Y1583045I-150J132D01*
G01Y1583667D01*
G02X1355637Y1583870I203J0D01*
G37*
G36*
G01X1476897D02*
X1479717D01*
G02X1479920Y1583667I0J-203D01*
G01Y1583045D01*
G03X1479970Y1582913I200J0D01*
G02Y1580001I-1664J-1456D01*
G03X1479920Y1579869I150J-132D01*
G01Y1577927D01*
G03X1479970Y1577795I200J0D01*
G02Y1574883I-1664J-1456D01*
G03X1479920Y1574751I150J-132D01*
G01Y1574129D01*
G02X1479717Y1573926I-203J0D01*
G01X1476897D01*
G02X1476694Y1574129I0J203D01*
G01Y1574751D01*
G03X1476644Y1574883I-200J0D01*
G02Y1577795I1664J1456D01*
G03X1476694Y1577927I-150J132D01*
G01Y1579869D01*
G03X1476644Y1580001I-200J0D01*
G02Y1582913I1664J1456D01*
G03X1476694Y1583045I-150J132D01*
G01Y1583667D01*
G02X1476897Y1583870I203J0D01*
G37*
G36*
G01X1650125D02*
X1652945D01*
G02X1653148Y1583667I0J-203D01*
G01Y1583045D01*
G03X1653198Y1582913I200J0D01*
G02Y1580001I-1664J-1456D01*
G03X1653148Y1579869I150J-132D01*
G01Y1577927D01*
G03X1653198Y1577795I200J0D01*
G02Y1574883I-1664J-1456D01*
G03X1653148Y1574751I150J-132D01*
G01Y1574129D01*
G02X1652945Y1573926I-203J0D01*
G01X1650125D01*
G02X1649922Y1574129I0J203D01*
G01Y1574751D01*
G03X1649872Y1574883I-200J0D01*
G02Y1577795I1664J1456D01*
G03X1649922Y1577927I-150J132D01*
G01Y1579869D01*
G03X1649872Y1580001I-200J0D01*
G02Y1582913I1664J1456D01*
G03X1649922Y1583045I-150J132D01*
G01Y1583667D01*
G02X1650125Y1583870I203J0D01*
G37*
G36*
G01X1667448D02*
X1670268D01*
G02X1670470Y1583667I-1J-203D01*
G01Y1583047D01*
G03X1670520Y1582915I200J0D01*
G02Y1579999I-1661J-1458D01*
G03X1670470Y1579867I150J-132D01*
G01Y1577929D01*
G03X1670520Y1577797I200J0D01*
G02Y1574881I-1661J-1458D01*
G03X1670470Y1574749I150J-132D01*
G01Y1574129D01*
G02X1670268Y1573926I-202J-1D01*
G01X1667448D01*
G02X1667246Y1574129I1J203D01*
G01Y1574749D01*
G03X1667196Y1574881I-200J0D01*
G02Y1577797I1661J1458D01*
G03X1667246Y1577929I-150J132D01*
G01Y1579867D01*
G03X1667196Y1579999I-200J0D01*
G02Y1582915I1661J1458D01*
G03X1667246Y1583047I-150J132D01*
G01Y1583667D01*
G02X1667448Y1583870I202J1D01*
G37*
G36*
G01X1684771D02*
X1687591D01*
G02X1687794Y1583667I0J-203D01*
G01Y1583045D01*
G03X1687844Y1582913I200J0D01*
G02Y1580001I-1664J-1456D01*
G03X1687794Y1579869I150J-132D01*
G01Y1577927D01*
G03X1687844Y1577795I200J0D01*
G02Y1574883I-1664J-1456D01*
G03X1687794Y1574751I150J-132D01*
G01Y1574129D01*
G02X1687591Y1573926I-203J0D01*
G01X1684771D01*
G02X1684568Y1574129I0J203D01*
G01Y1574751D01*
G03X1684518Y1574883I-200J0D01*
G02Y1577795I1664J1456D01*
G03X1684568Y1577927I-150J132D01*
G01Y1579869D01*
G03X1684518Y1580001I-200J0D01*
G02Y1582913I1664J1456D01*
G03X1684568Y1583045I-150J132D01*
G01Y1583667D01*
G02X1684771Y1583870I203J0D01*
G37*
G36*
G01X1702093D02*
X1704913D01*
G02X1705116Y1583667I0J-203D01*
G01Y1583045D01*
G03X1705166Y1582913I200J0D01*
G02Y1580001I-1664J-1456D01*
G03X1705116Y1579869I150J-132D01*
G01Y1577927D01*
G03X1705166Y1577795I200J0D01*
G02Y1574883I-1664J-1456D01*
G03X1705116Y1574751I150J-132D01*
G01Y1574129D01*
G02X1704913Y1573926I-203J0D01*
G01X1702093D01*
G02X1701890Y1574129I0J203D01*
G01Y1574751D01*
G03X1701840Y1574883I-200J0D01*
G02Y1577795I1664J1456D01*
G03X1701890Y1577927I-150J132D01*
G01Y1579869D01*
G03X1701840Y1580001I-200J0D01*
G02Y1582913I1664J1456D01*
G03X1701890Y1583045I-150J132D01*
G01Y1583667D01*
G02X1702093Y1583870I203J0D01*
G37*
G36*
G01X134456Y1588200D02*
X137276D01*
G02X137478Y1587998I0J-202D01*
G01Y1587378D01*
G03X137528Y1587246I200J0D01*
G02Y1584330I-1661J-1458D01*
G03X137478Y1584198I150J-132D01*
G01Y1582260D01*
G03X137528Y1582128I200J0D01*
G02Y1579212I-1661J-1458D01*
G03X137478Y1579080I150J-132D01*
G01Y1578460D01*
G02X137276Y1578258I-202J0D01*
G01X134456D01*
G02X134254Y1578460I0J202D01*
G01Y1579080D01*
G03X134204Y1579212I-200J0D01*
G02Y1582128I1661J1458D01*
G03X134254Y1582260I-150J132D01*
G01Y1584198D01*
G03X134204Y1584330I-200J0D01*
G02Y1587246I1661J1458D01*
G03X134254Y1587378I-150J132D01*
G01Y1587998D01*
G02X134456Y1588200I202J0D01*
G37*
G36*
G01X169102D02*
X171922D01*
G02X172124Y1587998I0J-202D01*
G01Y1587378D01*
G03X172174Y1587246I200J0D01*
G02Y1584330I-1661J-1458D01*
G03X172124Y1584198I150J-132D01*
G01Y1582260D01*
G03X172174Y1582128I200J0D01*
G02Y1579212I-1661J-1458D01*
G03X172124Y1579080I150J-132D01*
G01Y1578460D01*
G02X171922Y1578258I-202J0D01*
G01X169102D01*
G02X168900Y1578460I0J202D01*
G01Y1579080D01*
G03X168850Y1579212I-200J0D01*
G02Y1582128I1661J1458D01*
G03X168900Y1582260I-150J132D01*
G01Y1584198D01*
G03X168850Y1584330I-200J0D01*
G02Y1587246I1661J1458D01*
G03X168900Y1587378I-150J132D01*
G01Y1587998D01*
G02X169102Y1588200I202J0D01*
G37*
G36*
G01X307684D02*
X310504D01*
G02X310706Y1587998I0J-202D01*
G01Y1587378D01*
G03X310756Y1587246I200J0D01*
G02Y1584330I-1661J-1458D01*
G03X310706Y1584198I150J-132D01*
G01Y1582260D01*
G03X310756Y1582128I200J0D01*
G02Y1579212I-1661J-1458D01*
G03X310706Y1579080I150J-132D01*
G01Y1578460D01*
G02X310504Y1578258I-202J0D01*
G01X307684D01*
G02X307482Y1578460I0J202D01*
G01Y1579080D01*
G03X307432Y1579212I-200J0D01*
G02Y1582128I1661J1458D01*
G03X307482Y1582260I-150J132D01*
G01Y1584198D01*
G03X307432Y1584330I-200J0D01*
G02Y1587246I1661J1458D01*
G03X307482Y1587378I-150J132D01*
G01Y1587998D01*
G02X307684Y1588200I202J0D01*
G37*
G36*
G01X342330D02*
X345150D01*
G02X345352Y1587998I0J-202D01*
G01Y1587378D01*
G03X345402Y1587246I200J0D01*
G02Y1584330I-1661J-1458D01*
G03X345352Y1584198I150J-132D01*
G01Y1582260D01*
G03X345402Y1582128I200J0D01*
G02Y1579212I-1661J-1458D01*
G03X345352Y1579080I150J-132D01*
G01Y1578460D01*
G02X345150Y1578258I-202J0D01*
G01X342330D01*
G02X342128Y1578460I0J202D01*
G01Y1579080D01*
G03X342078Y1579212I-200J0D01*
G02Y1582128I1661J1458D01*
G03X342128Y1582260I-150J132D01*
G01Y1584198D01*
G03X342078Y1584330I-200J0D01*
G02Y1587246I1661J1458D01*
G03X342128Y1587378I-150J132D01*
G01Y1587998D01*
G02X342330Y1588200I202J0D01*
G37*
G36*
G01X636818D02*
X639638D01*
G02X639840Y1587998I0J-202D01*
G01Y1587378D01*
G03X639890Y1587246I200J0D01*
G02Y1584330I-1661J-1458D01*
G03X639840Y1584198I150J-132D01*
G01Y1582260D01*
G03X639890Y1582128I200J0D01*
G02Y1579212I-1661J-1458D01*
G03X639840Y1579080I150J-132D01*
G01Y1578460D01*
G02X639638Y1578258I-202J0D01*
G01X636818D01*
G02X636616Y1578460I0J202D01*
G01Y1579080D01*
G03X636566Y1579212I-200J0D01*
G02Y1582128I1661J1458D01*
G03X636616Y1582260I-150J132D01*
G01Y1584198D01*
G03X636566Y1584330I-200J0D01*
G02Y1587246I1661J1458D01*
G03X636616Y1587378I-150J132D01*
G01Y1587998D01*
G02X636818Y1588200I202J0D01*
G37*
G36*
G01X671464D02*
X674284D01*
G02X674486Y1587998I0J-202D01*
G01Y1587378D01*
G03X674536Y1587246I200J0D01*
G02Y1584330I-1661J-1458D01*
G03X674486Y1584198I150J-132D01*
G01Y1582260D01*
G03X674536Y1582128I200J0D01*
G02Y1579212I-1661J-1458D01*
G03X674486Y1579080I150J-132D01*
G01Y1578460D01*
G02X674284Y1578258I-202J0D01*
G01X671464D01*
G02X671262Y1578460I0J202D01*
G01Y1579080D01*
G03X671212Y1579212I-200J0D01*
G02Y1582128I1661J1458D01*
G03X671262Y1582260I-150J132D01*
G01Y1584198D01*
G03X671212Y1584330I-200J0D01*
G02Y1587246I1661J1458D01*
G03X671262Y1587378I-150J132D01*
G01Y1587998D01*
G02X671464Y1588200I202J0D01*
G37*
G36*
G01X1156424D02*
X1159244D01*
G02X1159446Y1587998I0J-202D01*
G01Y1587378D01*
G03X1159496Y1587246I200J0D01*
G02Y1584330I-1661J-1458D01*
G03X1159446Y1584198I150J-132D01*
G01Y1582260D01*
G03X1159496Y1582128I200J0D01*
G02Y1579212I-1661J-1458D01*
G03X1159446Y1579080I150J-132D01*
G01Y1578460D01*
G02X1159244Y1578258I-202J0D01*
G01X1156424D01*
G02X1156222Y1578460I0J202D01*
G01Y1579080D01*
G03X1156172Y1579212I-200J0D01*
G02Y1582128I1661J1458D01*
G03X1156222Y1582260I-150J132D01*
G01Y1584198D01*
G03X1156172Y1584330I-200J0D01*
G02Y1587246I1661J1458D01*
G03X1156222Y1587378I-150J132D01*
G01Y1587998D01*
G02X1156424Y1588200I202J0D01*
G37*
G36*
G01X1191070D02*
X1193890D01*
G02X1194092Y1587998I0J-202D01*
G01Y1587378D01*
G03X1194142Y1587246I200J0D01*
G02Y1584330I-1661J-1458D01*
G03X1194092Y1584198I150J-132D01*
G01Y1582260D01*
G03X1194142Y1582128I200J0D01*
G02Y1579212I-1661J-1458D01*
G03X1194092Y1579080I150J-132D01*
G01Y1578460D01*
G02X1193890Y1578258I-202J0D01*
G01X1191070D01*
G02X1190868Y1578460I0J202D01*
G01Y1579080D01*
G03X1190818Y1579212I-200J0D01*
G02Y1582128I1661J1458D01*
G03X1190868Y1582260I-150J132D01*
G01Y1584198D01*
G03X1190818Y1584330I-200J0D01*
G02Y1587246I1661J1458D01*
G03X1190868Y1587378I-150J132D01*
G01Y1587998D01*
G02X1191070Y1588200I202J0D01*
G37*
G36*
G01X1312330D02*
X1315150D01*
G02X1315352Y1587998I0J-202D01*
G01Y1587378D01*
G03X1315402Y1587246I200J0D01*
G02Y1584330I-1661J-1458D01*
G03X1315352Y1584198I150J-132D01*
G01Y1582260D01*
G03X1315402Y1582128I200J0D01*
G02Y1579212I-1661J-1458D01*
G03X1315352Y1579080I150J-132D01*
G01Y1578460D01*
G02X1315150Y1578258I-202J0D01*
G01X1312330D01*
G02X1312128Y1578460I0J202D01*
G01Y1579080D01*
G03X1312078Y1579212I-200J0D01*
G02Y1582128I1661J1458D01*
G03X1312128Y1582260I-150J132D01*
G01Y1584198D01*
G03X1312078Y1584330I-200J0D01*
G02Y1587246I1661J1458D01*
G03X1312128Y1587378I-150J132D01*
G01Y1587998D01*
G02X1312330Y1588200I202J0D01*
G37*
G36*
G01X1346976D02*
X1349796D01*
G02X1349998Y1587998I0J-202D01*
G01Y1587378D01*
G03X1350048Y1587246I200J0D01*
G02Y1584330I-1661J-1458D01*
G03X1349998Y1584198I150J-132D01*
G01Y1582260D01*
G03X1350048Y1582128I200J0D01*
G02Y1579212I-1661J-1458D01*
G03X1349998Y1579080I150J-132D01*
G01Y1578460D01*
G02X1349796Y1578258I-202J0D01*
G01X1346976D01*
G02X1346774Y1578460I0J202D01*
G01Y1579080D01*
G03X1346724Y1579212I-200J0D01*
G02Y1582128I1661J1458D01*
G03X1346774Y1582260I-150J132D01*
G01Y1584198D01*
G03X1346724Y1584330I-200J0D01*
G02Y1587246I1661J1458D01*
G03X1346774Y1587378I-150J132D01*
G01Y1587998D01*
G02X1346976Y1588200I202J0D01*
G37*
G36*
G01X1658786D02*
X1661606D01*
G02X1661808Y1587998I0J-202D01*
G01Y1587378D01*
G03X1661858Y1587246I200J0D01*
G02Y1584330I-1661J-1458D01*
G03X1661808Y1584198I150J-132D01*
G01Y1582260D01*
G03X1661858Y1582128I200J0D01*
G02Y1579212I-1661J-1458D01*
G03X1661808Y1579080I150J-132D01*
G01Y1578460D01*
G02X1661606Y1578258I-202J0D01*
G01X1658786D01*
G02X1658584Y1578460I0J202D01*
G01Y1579080D01*
G03X1658534Y1579212I-200J0D01*
G02Y1582128I1661J1458D01*
G03X1658584Y1582260I-150J132D01*
G01Y1584198D01*
G03X1658534Y1584330I-200J0D01*
G02Y1587246I1661J1458D01*
G03X1658584Y1587378I-150J132D01*
G01Y1587998D01*
G02X1658786Y1588200I202J0D01*
G37*
G36*
G01X1693432D02*
X1696252D01*
G02X1696454Y1587998I0J-202D01*
G01Y1587378D01*
G03X1696504Y1587246I200J0D01*
G02Y1584330I-1661J-1458D01*
G03X1696454Y1584198I150J-132D01*
G01Y1582260D01*
G03X1696504Y1582128I200J0D01*
G02Y1579212I-1661J-1458D01*
G03X1696454Y1579080I150J-132D01*
G01Y1578460D01*
G02X1696252Y1578258I-202J0D01*
G01X1693432D01*
G02X1693230Y1578460I0J202D01*
G01Y1579080D01*
G03X1693180Y1579212I-200J0D01*
G02Y1582128I1661J1458D01*
G03X1693230Y1582260I-150J132D01*
G01Y1584198D01*
G03X1693180Y1584330I-200J0D01*
G02Y1587246I1661J1458D01*
G03X1693230Y1587378I-150J132D01*
G01Y1587998D01*
G02X1693432Y1588200I202J0D01*
G37*
G36*
G01X117133D02*
X119953D01*
G02X120156Y1587998I1J-202D01*
G01Y1587376D01*
G03X120206Y1587244I200J0D01*
G02Y1584332I-1664J-1456D01*
G03X120156Y1584200I150J-132D01*
G01Y1582258D01*
G03X120206Y1582126I200J0D01*
G02Y1579214I-1664J-1456D01*
G03X120156Y1579082I150J-132D01*
G01Y1578460D01*
G02X119953Y1578258I-203J1D01*
G01X117133D01*
G02X116930Y1578460I-1J202D01*
G01Y1579082D01*
G03X116880Y1579214I-200J0D01*
G02Y1582126I1664J1456D01*
G03X116930Y1582258I-150J132D01*
G01Y1584200D01*
G03X116880Y1584332I-200J0D01*
G02Y1587244I1664J1456D01*
G03X116930Y1587376I-150J132D01*
G01Y1587998D01*
G02X117133Y1588200I203J-1D01*
G37*
G36*
G01X151779D02*
X154599D01*
G02X154802Y1587998I1J-202D01*
G01Y1587376D01*
G03X154852Y1587244I200J0D01*
G02Y1584332I-1664J-1456D01*
G03X154802Y1584200I150J-132D01*
G01Y1582258D01*
G03X154852Y1582126I200J0D01*
G02Y1579214I-1664J-1456D01*
G03X154802Y1579082I150J-132D01*
G01Y1578460D01*
G02X154599Y1578258I-203J1D01*
G01X151779D01*
G02X151576Y1578460I-1J202D01*
G01Y1579082D01*
G03X151526Y1579214I-200J0D01*
G02Y1582126I1664J1456D01*
G03X151576Y1582258I-150J132D01*
G01Y1584200D01*
G03X151526Y1584332I-200J0D01*
G02Y1587244I1664J1456D01*
G03X151576Y1587376I-150J132D01*
G01Y1587998D01*
G02X151779Y1588200I203J-1D01*
G37*
G36*
G01X290361D02*
X293181D01*
G02X293384Y1587998I1J-202D01*
G01Y1587376D01*
G03X293434Y1587244I200J0D01*
G02Y1584332I-1664J-1456D01*
G03X293384Y1584200I150J-132D01*
G01Y1582258D01*
G03X293434Y1582126I200J0D01*
G02Y1579214I-1664J-1456D01*
G03X293384Y1579082I150J-132D01*
G01Y1578460D01*
G02X293181Y1578258I-203J1D01*
G01X290361D01*
G02X290158Y1578460I-1J202D01*
G01Y1579082D01*
G03X290108Y1579214I-200J0D01*
G02Y1582126I1664J1456D01*
G03X290158Y1582258I-150J132D01*
G01Y1584200D01*
G03X290108Y1584332I-200J0D01*
G02Y1587244I1664J1456D01*
G03X290158Y1587376I-150J132D01*
G01Y1587998D01*
G02X290361Y1588200I203J-1D01*
G37*
G36*
G01X325007D02*
X327827D01*
G02X328030Y1587998I1J-202D01*
G01Y1587376D01*
G03X328080Y1587244I200J0D01*
G02Y1584332I-1664J-1456D01*
G03X328030Y1584200I150J-132D01*
G01Y1582258D01*
G03X328080Y1582126I200J0D01*
G02Y1579214I-1664J-1456D01*
G03X328030Y1579082I150J-132D01*
G01Y1578460D01*
G02X327827Y1578258I-203J1D01*
G01X325007D01*
G02X324804Y1578460I-1J202D01*
G01Y1579082D01*
G03X324754Y1579214I-200J0D01*
G02Y1582126I1664J1456D01*
G03X324804Y1582258I-150J132D01*
G01Y1584200D01*
G03X324754Y1584332I-200J0D01*
G02Y1587244I1664J1456D01*
G03X324804Y1587376I-150J132D01*
G01Y1587998D01*
G02X325007Y1588200I203J-1D01*
G37*
G36*
G01X515559D02*
X518379D01*
G02X518582Y1587998I1J-202D01*
G01Y1587376D01*
G03X518632Y1587244I200J0D01*
G02Y1584332I-1664J-1456D01*
G03X518582Y1584200I150J-132D01*
G01Y1582258D01*
G03X518632Y1582126I200J0D01*
G02Y1579214I-1664J-1456D01*
G03X518582Y1579082I150J-132D01*
G01Y1578460D01*
G02X518379Y1578258I-203J1D01*
G01X515559D01*
G02X515356Y1578460I-1J202D01*
G01Y1579082D01*
G03X515306Y1579214I-200J0D01*
G02Y1582126I1664J1456D01*
G03X515356Y1582258I-150J132D01*
G01Y1584200D01*
G03X515306Y1584332I-200J0D01*
G02Y1587244I1664J1456D01*
G03X515356Y1587376I-150J132D01*
G01Y1587998D01*
G02X515559Y1588200I203J-1D01*
G37*
G36*
G01X654141D02*
X656961D01*
G02X657164Y1587998I1J-202D01*
G01Y1587376D01*
G03X657214Y1587244I200J0D01*
G02Y1584332I-1664J-1456D01*
G03X657164Y1584200I150J-132D01*
G01Y1582258D01*
G03X657214Y1582126I200J0D01*
G02Y1579214I-1664J-1456D01*
G03X657164Y1579082I150J-132D01*
G01Y1578460D01*
G02X656961Y1578258I-203J1D01*
G01X654141D01*
G02X653938Y1578460I-1J202D01*
G01Y1579082D01*
G03X653888Y1579214I-200J0D01*
G02Y1582126I1664J1456D01*
G03X653938Y1582258I-150J132D01*
G01Y1584200D01*
G03X653888Y1584332I-200J0D01*
G02Y1587244I1664J1456D01*
G03X653938Y1587376I-150J132D01*
G01Y1587998D01*
G02X654141Y1588200I203J-1D01*
G37*
G36*
G01X688787D02*
X691607D01*
G02X691810Y1587998I1J-202D01*
G01Y1587376D01*
G03X691860Y1587244I200J0D01*
G02Y1584332I-1664J-1456D01*
G03X691810Y1584200I150J-132D01*
G01Y1582258D01*
G03X691860Y1582126I200J0D01*
G02Y1579214I-1664J-1456D01*
G03X691810Y1579082I150J-132D01*
G01Y1578460D01*
G02X691607Y1578258I-203J1D01*
G01X688787D01*
G02X688584Y1578460I-1J202D01*
G01Y1579082D01*
G03X688534Y1579214I-200J0D01*
G02Y1582126I1664J1456D01*
G03X688584Y1582258I-150J132D01*
G01Y1584200D01*
G03X688534Y1584332I-200J0D01*
G02Y1587244I1664J1456D01*
G03X688584Y1587376I-150J132D01*
G01Y1587998D01*
G02X688787Y1588200I203J-1D01*
G37*
G36*
G01X1139101D02*
X1141921D01*
G02X1142124Y1587998I1J-202D01*
G01Y1587376D01*
G03X1142174Y1587244I200J0D01*
G02Y1584332I-1664J-1456D01*
G03X1142124Y1584200I150J-132D01*
G01Y1582258D01*
G03X1142174Y1582126I200J0D01*
G02Y1579214I-1664J-1456D01*
G03X1142124Y1579082I150J-132D01*
G01Y1578460D01*
G02X1141921Y1578258I-203J1D01*
G01X1139101D01*
G02X1138898Y1578460I-1J202D01*
G01Y1579082D01*
G03X1138848Y1579214I-200J0D01*
G02Y1582126I1664J1456D01*
G03X1138898Y1582258I-150J132D01*
G01Y1584200D01*
G03X1138848Y1584332I-200J0D01*
G02Y1587244I1664J1456D01*
G03X1138898Y1587376I-150J132D01*
G01Y1587998D01*
G02X1139101Y1588200I203J-1D01*
G37*
G36*
G01X1173747D02*
X1176567D01*
G02X1176770Y1587998I1J-202D01*
G01Y1587376D01*
G03X1176820Y1587244I200J0D01*
G02Y1584332I-1664J-1456D01*
G03X1176770Y1584200I150J-132D01*
G01Y1582258D01*
G03X1176820Y1582126I200J0D01*
G02Y1579214I-1664J-1456D01*
G03X1176770Y1579082I150J-132D01*
G01Y1578460D01*
G02X1176567Y1578258I-203J1D01*
G01X1173747D01*
G02X1173544Y1578460I-1J202D01*
G01Y1579082D01*
G03X1173494Y1579214I-200J0D01*
G02Y1582126I1664J1456D01*
G03X1173544Y1582258I-150J132D01*
G01Y1584200D01*
G03X1173494Y1584332I-200J0D01*
G02Y1587244I1664J1456D01*
G03X1173544Y1587376I-150J132D01*
G01Y1587998D01*
G02X1173747Y1588200I203J-1D01*
G37*
G36*
G01X1329653D02*
X1332473D01*
G02X1332676Y1587998I1J-202D01*
G01Y1587376D01*
G03X1332726Y1587244I200J0D01*
G02Y1584332I-1664J-1456D01*
G03X1332676Y1584200I150J-132D01*
G01Y1582258D01*
G03X1332726Y1582126I200J0D01*
G02Y1579214I-1664J-1456D01*
G03X1332676Y1579082I150J-132D01*
G01Y1578460D01*
G02X1332473Y1578258I-203J1D01*
G01X1329653D01*
G02X1329450Y1578460I-1J202D01*
G01Y1579082D01*
G03X1329400Y1579214I-200J0D01*
G02Y1582126I1664J1456D01*
G03X1329450Y1582258I-150J132D01*
G01Y1584200D01*
G03X1329400Y1584332I-200J0D01*
G02Y1587244I1664J1456D01*
G03X1329450Y1587376I-150J132D01*
G01Y1587998D01*
G02X1329653Y1588200I203J-1D01*
G37*
G36*
G01X1364299D02*
X1367119D01*
G02X1367322Y1587998I1J-202D01*
G01Y1587376D01*
G03X1367372Y1587244I200J0D01*
G02Y1584332I-1664J-1456D01*
G03X1367322Y1584200I150J-132D01*
G01Y1582258D01*
G03X1367372Y1582126I200J0D01*
G02Y1579214I-1664J-1456D01*
G03X1367322Y1579082I150J-132D01*
G01Y1578460D01*
G02X1367119Y1578258I-203J1D01*
G01X1364299D01*
G02X1364096Y1578460I-1J202D01*
G01Y1579082D01*
G03X1364046Y1579214I-200J0D01*
G02Y1582126I1664J1456D01*
G03X1364096Y1582258I-150J132D01*
G01Y1584200D01*
G03X1364046Y1584332I-200J0D01*
G02Y1587244I1664J1456D01*
G03X1364096Y1587376I-150J132D01*
G01Y1587998D01*
G02X1364299Y1588200I203J-1D01*
G37*
G36*
G01X1676109D02*
X1678929D01*
G02X1679132Y1587998I1J-202D01*
G01Y1587376D01*
G03X1679182Y1587244I200J0D01*
G02Y1584332I-1664J-1456D01*
G03X1679132Y1584200I150J-132D01*
G01Y1582258D01*
G03X1679182Y1582126I200J0D01*
G02Y1579214I-1664J-1456D01*
G03X1679132Y1579082I150J-132D01*
G01Y1578460D01*
G02X1678929Y1578258I-203J1D01*
G01X1676109D01*
G02X1675906Y1578460I-1J202D01*
G01Y1579082D01*
G03X1675856Y1579214I-200J0D01*
G02Y1582126I1664J1456D01*
G03X1675906Y1582258I-150J132D01*
G01Y1584200D01*
G03X1675856Y1584332I-200J0D01*
G02Y1587244I1664J1456D01*
G03X1675906Y1587376I-150J132D01*
G01Y1587998D01*
G02X1676109Y1588200I203J-1D01*
G37*
G36*
G01X1710755D02*
X1713575D01*
G02X1713778Y1587998I1J-202D01*
G01Y1587376D01*
G03X1713828Y1587244I200J0D01*
G02Y1584332I-1664J-1456D01*
G03X1713778Y1584200I150J-132D01*
G01Y1582258D01*
G03X1713828Y1582126I200J0D01*
G02Y1579214I-1664J-1456D01*
G03X1713778Y1579082I150J-132D01*
G01Y1578460D01*
G02X1713575Y1578258I-203J1D01*
G01X1710755D01*
G02X1710552Y1578460I-1J202D01*
G01Y1579082D01*
G03X1710502Y1579214I-200J0D01*
G02Y1582126I1664J1456D01*
G03X1710552Y1582258I-150J132D01*
G01Y1584200D01*
G03X1710502Y1584332I-200J0D01*
G02Y1587244I1664J1456D01*
G03X1710552Y1587376I-150J132D01*
G01Y1587998D01*
G02X1710755Y1588200I203J-1D01*
G37*
G36*
G01X108472Y1599224D02*
X111292D01*
G02X111494Y1599021I-1J-203D01*
G01Y1598401D01*
G03X111544Y1598269I200J0D01*
G02Y1595353I-1661J-1458D01*
G03X111494Y1595221I150J-132D01*
G01Y1593283D01*
G03X111544Y1593151I200J0D01*
G02Y1590235I-1661J-1458D01*
G03X111494Y1590103I150J-132D01*
G01Y1589483D01*
G02X111292Y1589280I-202J-1D01*
G01X108472D01*
G02X108270Y1589483I1J203D01*
G01Y1590103D01*
G03X108220Y1590235I-200J0D01*
G02Y1593151I1661J1458D01*
G03X108270Y1593283I-150J132D01*
G01Y1595221D01*
G03X108220Y1595353I-200J0D01*
G02Y1598269I1661J1458D01*
G03X108270Y1598401I-150J132D01*
G01Y1599021D01*
G02X108472Y1599224I202J1D01*
G37*
G36*
G01X125795D02*
X128615D01*
G02X128818Y1599021I0J-203D01*
G01Y1598399D01*
G03X128868Y1598267I200J0D01*
G02Y1595355I-1664J-1456D01*
G03X128818Y1595223I150J-132D01*
G01Y1593281D01*
G03X128868Y1593149I200J0D01*
G02Y1590237I-1664J-1456D01*
G03X128818Y1590105I150J-132D01*
G01Y1589483D01*
G02X128615Y1589280I-203J0D01*
G01X125795D01*
G02X125592Y1589483I0J203D01*
G01Y1590105D01*
G03X125542Y1590237I-200J0D01*
G02Y1593149I1664J1456D01*
G03X125592Y1593281I-150J132D01*
G01Y1595223D01*
G03X125542Y1595355I-200J0D01*
G02Y1598267I1664J1456D01*
G03X125592Y1598399I-150J132D01*
G01Y1599021D01*
G02X125795Y1599224I203J0D01*
G37*
G36*
G01X143118D02*
X145938D01*
G02X146140Y1599021I-1J-203D01*
G01Y1598401D01*
G03X146190Y1598269I200J0D01*
G02Y1595353I-1661J-1458D01*
G03X146140Y1595221I150J-132D01*
G01Y1593283D01*
G03X146190Y1593151I200J0D01*
G02Y1590235I-1661J-1458D01*
G03X146140Y1590103I150J-132D01*
G01Y1589483D01*
G02X145938Y1589280I-202J-1D01*
G01X143118D01*
G02X142916Y1589483I1J203D01*
G01Y1590103D01*
G03X142866Y1590235I-200J0D01*
G02Y1593151I1661J1458D01*
G03X142916Y1593283I-150J132D01*
G01Y1595221D01*
G03X142866Y1595353I-200J0D01*
G02Y1598269I1661J1458D01*
G03X142916Y1598401I-150J132D01*
G01Y1599021D01*
G02X143118Y1599224I202J1D01*
G37*
G36*
G01X160440D02*
X163260D01*
G02X163462Y1599021I-1J-203D01*
G01Y1598401D01*
G03X163512Y1598269I200J0D01*
G02Y1595353I-1661J-1458D01*
G03X163462Y1595221I150J-132D01*
G01Y1593283D01*
G03X163512Y1593151I200J0D01*
G02Y1590235I-1661J-1458D01*
G03X163462Y1590103I150J-132D01*
G01Y1589483D01*
G02X163260Y1589280I-202J-1D01*
G01X160440D01*
G02X160238Y1589483I1J203D01*
G01Y1590103D01*
G03X160188Y1590235I-200J0D01*
G02Y1593151I1661J1458D01*
G03X160238Y1593283I-150J132D01*
G01Y1595221D01*
G03X160188Y1595353I-200J0D01*
G02Y1598269I1661J1458D01*
G03X160238Y1598401I-150J132D01*
G01Y1599021D01*
G02X160440Y1599224I202J1D01*
G37*
G36*
G01X281700D02*
X284520D01*
G02X284722Y1599021I-1J-203D01*
G01Y1598401D01*
G03X284772Y1598269I200J0D01*
G02Y1595353I-1661J-1458D01*
G03X284722Y1595221I150J-132D01*
G01Y1593283D01*
G03X284772Y1593151I200J0D01*
G02Y1590235I-1661J-1458D01*
G03X284722Y1590103I150J-132D01*
G01Y1589483D01*
G02X284520Y1589280I-202J-1D01*
G01X281700D01*
G02X281498Y1589483I1J203D01*
G01Y1590103D01*
G03X281448Y1590235I-200J0D01*
G02Y1593151I1661J1458D01*
G03X281498Y1593283I-150J132D01*
G01Y1595221D01*
G03X281448Y1595353I-200J0D01*
G02Y1598269I1661J1458D01*
G03X281498Y1598401I-150J132D01*
G01Y1599021D01*
G02X281700Y1599224I202J1D01*
G37*
G36*
G01X299023D02*
X301843D01*
G02X302046Y1599021I0J-203D01*
G01Y1598399D01*
G03X302096Y1598267I200J0D01*
G02Y1595355I-1664J-1456D01*
G03X302046Y1595223I150J-132D01*
G01Y1593281D01*
G03X302096Y1593149I200J0D01*
G02Y1590237I-1664J-1456D01*
G03X302046Y1590105I150J-132D01*
G01Y1589483D01*
G02X301843Y1589280I-203J0D01*
G01X299023D01*
G02X298820Y1589483I0J203D01*
G01Y1590105D01*
G03X298770Y1590237I-200J0D01*
G02Y1593149I1664J1456D01*
G03X298820Y1593281I-150J132D01*
G01Y1595223D01*
G03X298770Y1595355I-200J0D01*
G02Y1598267I1664J1456D01*
G03X298820Y1598399I-150J132D01*
G01Y1599021D01*
G02X299023Y1599224I203J0D01*
G37*
G36*
G01X316346D02*
X319166D01*
G02X319368Y1599021I-1J-203D01*
G01Y1598401D01*
G03X319418Y1598269I200J0D01*
G02Y1595353I-1661J-1458D01*
G03X319368Y1595221I150J-132D01*
G01Y1593283D01*
G03X319418Y1593151I200J0D01*
G02Y1590235I-1661J-1458D01*
G03X319368Y1590103I150J-132D01*
G01Y1589483D01*
G02X319166Y1589280I-202J-1D01*
G01X316346D01*
G02X316144Y1589483I1J203D01*
G01Y1590103D01*
G03X316094Y1590235I-200J0D01*
G02Y1593151I1661J1458D01*
G03X316144Y1593283I-150J132D01*
G01Y1595221D01*
G03X316094Y1595353I-200J0D01*
G02Y1598269I1661J1458D01*
G03X316144Y1598401I-150J132D01*
G01Y1599021D01*
G02X316346Y1599224I202J1D01*
G37*
G36*
G01X333668D02*
X336488D01*
G02X336690Y1599021I-1J-203D01*
G01Y1598401D01*
G03X336740Y1598269I200J0D01*
G02Y1595353I-1661J-1458D01*
G03X336690Y1595221I150J-132D01*
G01Y1593283D01*
G03X336740Y1593151I200J0D01*
G02Y1590235I-1661J-1458D01*
G03X336690Y1590103I150J-132D01*
G01Y1589483D01*
G02X336488Y1589280I-202J-1D01*
G01X333668D01*
G02X333466Y1589483I1J203D01*
G01Y1590103D01*
G03X333416Y1590235I-200J0D01*
G02Y1593151I1661J1458D01*
G03X333466Y1593283I-150J132D01*
G01Y1595221D01*
G03X333416Y1595353I-200J0D01*
G02Y1598269I1661J1458D01*
G03X333466Y1598401I-150J132D01*
G01Y1599021D01*
G02X333668Y1599224I202J1D01*
G37*
G36*
G01X628157D02*
X630977D01*
G02X631180Y1599021I0J-203D01*
G01Y1598399D01*
G03X631230Y1598267I200J0D01*
G02Y1595355I-1664J-1456D01*
G03X631180Y1595223I150J-132D01*
G01Y1593281D01*
G03X631230Y1593149I200J0D01*
G02Y1590237I-1664J-1456D01*
G03X631180Y1590105I150J-132D01*
G01Y1589483D01*
G02X630977Y1589280I-203J0D01*
G01X628157D01*
G02X627954Y1589483I0J203D01*
G01Y1590105D01*
G03X627904Y1590237I-200J0D01*
G02Y1593149I1664J1456D01*
G03X627954Y1593281I-150J132D01*
G01Y1595223D01*
G03X627904Y1595355I-200J0D01*
G02Y1598267I1664J1456D01*
G03X627954Y1598399I-150J132D01*
G01Y1599021D01*
G02X628157Y1599224I203J0D01*
G37*
G36*
G01X645480D02*
X648300D01*
G02X648502Y1599021I-1J-203D01*
G01Y1598401D01*
G03X648552Y1598269I200J0D01*
G02Y1595353I-1661J-1458D01*
G03X648502Y1595221I150J-132D01*
G01Y1593283D01*
G03X648552Y1593151I200J0D01*
G02Y1590235I-1661J-1458D01*
G03X648502Y1590103I150J-132D01*
G01Y1589483D01*
G02X648300Y1589280I-202J-1D01*
G01X645480D01*
G02X645278Y1589483I1J203D01*
G01Y1590103D01*
G03X645228Y1590235I-200J0D01*
G02Y1593151I1661J1458D01*
G03X645278Y1593283I-150J132D01*
G01Y1595221D01*
G03X645228Y1595353I-200J0D01*
G02Y1598269I1661J1458D01*
G03X645278Y1598401I-150J132D01*
G01Y1599021D01*
G02X645480Y1599224I202J1D01*
G37*
G36*
G01X662803D02*
X665623D01*
G02X665826Y1599021I0J-203D01*
G01Y1598399D01*
G03X665876Y1598267I200J0D01*
G02Y1595355I-1664J-1456D01*
G03X665826Y1595223I150J-132D01*
G01Y1593281D01*
G03X665876Y1593149I200J0D01*
G02Y1590237I-1664J-1456D01*
G03X665826Y1590105I150J-132D01*
G01Y1589483D01*
G02X665623Y1589280I-203J0D01*
G01X662803D01*
G02X662600Y1589483I0J203D01*
G01Y1590105D01*
G03X662550Y1590237I-200J0D01*
G02Y1593149I1664J1456D01*
G03X662600Y1593281I-150J132D01*
G01Y1595223D01*
G03X662550Y1595355I-200J0D01*
G02Y1598267I1664J1456D01*
G03X662600Y1598399I-150J132D01*
G01Y1599021D01*
G02X662803Y1599224I203J0D01*
G37*
G36*
G01X680125D02*
X682945D01*
G02X683148Y1599021I0J-203D01*
G01Y1598399D01*
G03X683198Y1598267I200J0D01*
G02Y1595355I-1664J-1456D01*
G03X683148Y1595223I150J-132D01*
G01Y1593281D01*
G03X683198Y1593149I200J0D01*
G02Y1590237I-1664J-1456D01*
G03X683148Y1590105I150J-132D01*
G01Y1589483D01*
G02X682945Y1589280I-203J0D01*
G01X680125D01*
G02X679922Y1589483I0J203D01*
G01Y1590105D01*
G03X679872Y1590237I-200J0D01*
G02Y1593149I1664J1456D01*
G03X679922Y1593281I-150J132D01*
G01Y1595223D01*
G03X679872Y1595355I-200J0D01*
G02Y1598267I1664J1456D01*
G03X679922Y1598399I-150J132D01*
G01Y1599021D01*
G02X680125Y1599224I203J0D01*
G37*
G36*
G01X1130440D02*
X1133260D01*
G02X1133462Y1599021I-1J-203D01*
G01Y1598401D01*
G03X1133512Y1598269I200J0D01*
G02Y1595353I-1661J-1458D01*
G03X1133462Y1595221I150J-132D01*
G01Y1593283D01*
G03X1133512Y1593151I200J0D01*
G02Y1590235I-1661J-1458D01*
G03X1133462Y1590103I150J-132D01*
G01Y1589483D01*
G02X1133260Y1589280I-202J-1D01*
G01X1130440D01*
G02X1130238Y1589483I1J203D01*
G01Y1590103D01*
G03X1130188Y1590235I-200J0D01*
G02Y1593151I1661J1458D01*
G03X1130238Y1593283I-150J132D01*
G01Y1595221D01*
G03X1130188Y1595353I-200J0D01*
G02Y1598269I1661J1458D01*
G03X1130238Y1598401I-150J132D01*
G01Y1599021D01*
G02X1130440Y1599224I202J1D01*
G37*
G36*
G01X1147763D02*
X1150583D01*
G02X1150786Y1599021I0J-203D01*
G01Y1598399D01*
G03X1150836Y1598267I200J0D01*
G02Y1595355I-1664J-1456D01*
G03X1150786Y1595223I150J-132D01*
G01Y1593281D01*
G03X1150836Y1593149I200J0D01*
G02Y1590237I-1664J-1456D01*
G03X1150786Y1590105I150J-132D01*
G01Y1589483D01*
G02X1150583Y1589280I-203J0D01*
G01X1147763D01*
G02X1147560Y1589483I0J203D01*
G01Y1590105D01*
G03X1147510Y1590237I-200J0D01*
G02Y1593149I1664J1456D01*
G03X1147560Y1593281I-150J132D01*
G01Y1595223D01*
G03X1147510Y1595355I-200J0D01*
G02Y1598267I1664J1456D01*
G03X1147560Y1598399I-150J132D01*
G01Y1599021D01*
G02X1147763Y1599224I203J0D01*
G37*
G36*
G01X1165086D02*
X1167906D01*
G02X1168108Y1599021I-1J-203D01*
G01Y1598401D01*
G03X1168158Y1598269I200J0D01*
G02Y1595353I-1661J-1458D01*
G03X1168108Y1595221I150J-132D01*
G01Y1593283D01*
G03X1168158Y1593151I200J0D01*
G02Y1590235I-1661J-1458D01*
G03X1168108Y1590103I150J-132D01*
G01Y1589483D01*
G02X1167906Y1589280I-202J-1D01*
G01X1165086D01*
G02X1164884Y1589483I1J203D01*
G01Y1590103D01*
G03X1164834Y1590235I-200J0D01*
G02Y1593151I1661J1458D01*
G03X1164884Y1593283I-150J132D01*
G01Y1595221D01*
G03X1164834Y1595353I-200J0D01*
G02Y1598269I1661J1458D01*
G03X1164884Y1598401I-150J132D01*
G01Y1599021D01*
G02X1165086Y1599224I202J1D01*
G37*
G36*
G01X1182408D02*
X1185228D01*
G02X1185430Y1599021I-1J-203D01*
G01Y1598401D01*
G03X1185480Y1598269I200J0D01*
G02Y1595353I-1661J-1458D01*
G03X1185430Y1595221I150J-132D01*
G01Y1593283D01*
G03X1185480Y1593151I200J0D01*
G02Y1590235I-1661J-1458D01*
G03X1185430Y1590103I150J-132D01*
G01Y1589483D01*
G02X1185228Y1589280I-202J-1D01*
G01X1182408D01*
G02X1182206Y1589483I1J203D01*
G01Y1590103D01*
G03X1182156Y1590235I-200J0D01*
G02Y1593151I1661J1458D01*
G03X1182206Y1593283I-150J132D01*
G01Y1595221D01*
G03X1182156Y1595353I-200J0D01*
G02Y1598269I1661J1458D01*
G03X1182206Y1598401I-150J132D01*
G01Y1599021D01*
G02X1182408Y1599224I202J1D01*
G37*
G36*
G01X1303669D02*
X1306489D01*
G02X1306692Y1599021I0J-203D01*
G01Y1598399D01*
G03X1306742Y1598267I200J0D01*
G02Y1595355I-1664J-1456D01*
G03X1306692Y1595223I150J-132D01*
G01Y1593281D01*
G03X1306742Y1593149I200J0D01*
G02Y1590237I-1664J-1456D01*
G03X1306692Y1590105I150J-132D01*
G01Y1589483D01*
G02X1306489Y1589280I-203J0D01*
G01X1303669D01*
G02X1303466Y1589483I0J203D01*
G01Y1590105D01*
G03X1303416Y1590237I-200J0D01*
G02Y1593149I1664J1456D01*
G03X1303466Y1593281I-150J132D01*
G01Y1595223D01*
G03X1303416Y1595355I-200J0D01*
G02Y1598267I1664J1456D01*
G03X1303466Y1598399I-150J132D01*
G01Y1599021D01*
G02X1303669Y1599224I203J0D01*
G37*
G36*
G01X1320992D02*
X1323812D01*
G02X1324014Y1599021I-1J-203D01*
G01Y1598401D01*
G03X1324064Y1598269I200J0D01*
G02Y1595353I-1661J-1458D01*
G03X1324014Y1595221I150J-132D01*
G01Y1593283D01*
G03X1324064Y1593151I200J0D01*
G02Y1590235I-1661J-1458D01*
G03X1324014Y1590103I150J-132D01*
G01Y1589483D01*
G02X1323812Y1589280I-202J-1D01*
G01X1320992D01*
G02X1320790Y1589483I1J203D01*
G01Y1590103D01*
G03X1320740Y1590235I-200J0D01*
G02Y1593151I1661J1458D01*
G03X1320790Y1593283I-150J132D01*
G01Y1595221D01*
G03X1320740Y1595353I-200J0D01*
G02Y1598269I1661J1458D01*
G03X1320790Y1598401I-150J132D01*
G01Y1599021D01*
G02X1320992Y1599224I202J1D01*
G37*
G36*
G01X1338315D02*
X1341135D01*
G02X1341338Y1599021I0J-203D01*
G01Y1598399D01*
G03X1341388Y1598267I200J0D01*
G02Y1595355I-1664J-1456D01*
G03X1341338Y1595223I150J-132D01*
G01Y1593281D01*
G03X1341388Y1593149I200J0D01*
G02Y1590237I-1664J-1456D01*
G03X1341338Y1590105I150J-132D01*
G01Y1589483D01*
G02X1341135Y1589280I-203J0D01*
G01X1338315D01*
G02X1338112Y1589483I0J203D01*
G01Y1590105D01*
G03X1338062Y1590237I-200J0D01*
G02Y1593149I1664J1456D01*
G03X1338112Y1593281I-150J132D01*
G01Y1595223D01*
G03X1338062Y1595355I-200J0D01*
G02Y1598267I1664J1456D01*
G03X1338112Y1598399I-150J132D01*
G01Y1599021D01*
G02X1338315Y1599224I203J0D01*
G37*
G36*
G01X1355637D02*
X1358457D01*
G02X1358660Y1599021I0J-203D01*
G01Y1598399D01*
G03X1358710Y1598267I200J0D01*
G02Y1595355I-1664J-1456D01*
G03X1358660Y1595223I150J-132D01*
G01Y1593281D01*
G03X1358710Y1593149I200J0D01*
G02Y1590237I-1664J-1456D01*
G03X1358660Y1590105I150J-132D01*
G01Y1589483D01*
G02X1358457Y1589280I-203J0D01*
G01X1355637D01*
G02X1355434Y1589483I0J203D01*
G01Y1590105D01*
G03X1355384Y1590237I-200J0D01*
G02Y1593149I1664J1456D01*
G03X1355434Y1593281I-150J132D01*
G01Y1595223D01*
G03X1355384Y1595355I-200J0D01*
G02Y1598267I1664J1456D01*
G03X1355434Y1598399I-150J132D01*
G01Y1599021D01*
G02X1355637Y1599224I203J0D01*
G37*
G36*
G01X1476897D02*
X1479717D01*
G02X1479920Y1599021I0J-203D01*
G01Y1598399D01*
G03X1479970Y1598267I200J0D01*
G02Y1595355I-1664J-1456D01*
G03X1479920Y1595223I150J-132D01*
G01Y1593281D01*
G03X1479970Y1593149I200J0D01*
G02Y1590237I-1664J-1456D01*
G03X1479920Y1590105I150J-132D01*
G01Y1589483D01*
G02X1479717Y1589280I-203J0D01*
G01X1476897D01*
G02X1476694Y1589483I0J203D01*
G01Y1590105D01*
G03X1476644Y1590237I-200J0D01*
G02Y1593149I1664J1456D01*
G03X1476694Y1593281I-150J132D01*
G01Y1595223D01*
G03X1476644Y1595355I-200J0D01*
G02Y1598267I1664J1456D01*
G03X1476694Y1598399I-150J132D01*
G01Y1599021D01*
G02X1476897Y1599224I203J0D01*
G37*
G36*
G01X1650125D02*
X1652945D01*
G02X1653148Y1599021I0J-203D01*
G01Y1598399D01*
G03X1653198Y1598267I200J0D01*
G02Y1595355I-1664J-1456D01*
G03X1653148Y1595223I150J-132D01*
G01Y1593281D01*
G03X1653198Y1593149I200J0D01*
G02Y1590237I-1664J-1456D01*
G03X1653148Y1590105I150J-132D01*
G01Y1589483D01*
G02X1652945Y1589280I-203J0D01*
G01X1650125D01*
G02X1649922Y1589483I0J203D01*
G01Y1590105D01*
G03X1649872Y1590237I-200J0D01*
G02Y1593149I1664J1456D01*
G03X1649922Y1593281I-150J132D01*
G01Y1595223D01*
G03X1649872Y1595355I-200J0D01*
G02Y1598267I1664J1456D01*
G03X1649922Y1598399I-150J132D01*
G01Y1599021D01*
G02X1650125Y1599224I203J0D01*
G37*
G36*
G01X1667448D02*
X1670268D01*
G02X1670470Y1599021I-1J-203D01*
G01Y1598401D01*
G03X1670520Y1598269I200J0D01*
G02Y1595353I-1661J-1458D01*
G03X1670470Y1595221I150J-132D01*
G01Y1593283D01*
G03X1670520Y1593151I200J0D01*
G02Y1590235I-1661J-1458D01*
G03X1670470Y1590103I150J-132D01*
G01Y1589483D01*
G02X1670268Y1589280I-202J-1D01*
G01X1667448D01*
G02X1667246Y1589483I1J203D01*
G01Y1590103D01*
G03X1667196Y1590235I-200J0D01*
G02Y1593151I1661J1458D01*
G03X1667246Y1593283I-150J132D01*
G01Y1595221D01*
G03X1667196Y1595353I-200J0D01*
G02Y1598269I1661J1458D01*
G03X1667246Y1598401I-150J132D01*
G01Y1599021D01*
G02X1667448Y1599224I202J1D01*
G37*
G36*
G01X1684771D02*
X1687591D01*
G02X1687794Y1599021I0J-203D01*
G01Y1598399D01*
G03X1687844Y1598267I200J0D01*
G02Y1595355I-1664J-1456D01*
G03X1687794Y1595223I150J-132D01*
G01Y1593281D01*
G03X1687844Y1593149I200J0D01*
G02Y1590237I-1664J-1456D01*
G03X1687794Y1590105I150J-132D01*
G01Y1589483D01*
G02X1687591Y1589280I-203J0D01*
G01X1684771D01*
G02X1684568Y1589483I0J203D01*
G01Y1590105D01*
G03X1684518Y1590237I-200J0D01*
G02Y1593149I1664J1456D01*
G03X1684568Y1593281I-150J132D01*
G01Y1595223D01*
G03X1684518Y1595355I-200J0D01*
G02Y1598267I1664J1456D01*
G03X1684568Y1598399I-150J132D01*
G01Y1599021D01*
G02X1684771Y1599224I203J0D01*
G37*
G36*
G01X1702093D02*
X1704913D01*
G02X1705116Y1599021I0J-203D01*
G01Y1598399D01*
G03X1705166Y1598267I200J0D01*
G02Y1595355I-1664J-1456D01*
G03X1705116Y1595223I150J-132D01*
G01Y1593281D01*
G03X1705166Y1593149I200J0D01*
G02Y1590237I-1664J-1456D01*
G03X1705116Y1590105I150J-132D01*
G01Y1589483D01*
G02X1704913Y1589280I-203J0D01*
G01X1702093D01*
G02X1701890Y1589483I0J203D01*
G01Y1590105D01*
G03X1701840Y1590237I-200J0D01*
G02Y1593149I1664J1456D01*
G03X1701890Y1593281I-150J132D01*
G01Y1595223D01*
G03X1701840Y1595355I-200J0D01*
G02Y1598267I1664J1456D01*
G03X1701890Y1598399I-150J132D01*
G01Y1599021D01*
G02X1702093Y1599224I203J0D01*
G37*
G36*
G01X134456Y1603554D02*
X137276D01*
G02X137478Y1603352I0J-202D01*
G01Y1602732D01*
G03X137528Y1602600I200J0D01*
G02Y1599684I-1661J-1458D01*
G03X137478Y1599552I150J-132D01*
G01Y1597614D01*
G03X137528Y1597482I200J0D01*
G02Y1594566I-1661J-1458D01*
G03X137478Y1594434I150J-132D01*
G01Y1593814D01*
G02X137276Y1593612I-202J0D01*
G01X134456D01*
G02X134254Y1593814I0J202D01*
G01Y1594434D01*
G03X134204Y1594566I-200J0D01*
G02Y1597482I1661J1458D01*
G03X134254Y1597614I-150J132D01*
G01Y1599552D01*
G03X134204Y1599684I-200J0D01*
G02Y1602600I1661J1458D01*
G03X134254Y1602732I-150J132D01*
G01Y1603352D01*
G02X134456Y1603554I202J0D01*
G37*
G36*
G01X169102D02*
X171922D01*
G02X172124Y1603352I0J-202D01*
G01Y1602732D01*
G03X172174Y1602600I200J0D01*
G02Y1599684I-1661J-1458D01*
G03X172124Y1599552I150J-132D01*
G01Y1597614D01*
G03X172174Y1597482I200J0D01*
G02Y1594566I-1661J-1458D01*
G03X172124Y1594434I150J-132D01*
G01Y1593814D01*
G02X171922Y1593612I-202J0D01*
G01X169102D01*
G02X168900Y1593814I0J202D01*
G01Y1594434D01*
G03X168850Y1594566I-200J0D01*
G02Y1597482I1661J1458D01*
G03X168900Y1597614I-150J132D01*
G01Y1599552D01*
G03X168850Y1599684I-200J0D01*
G02Y1602600I1661J1458D01*
G03X168900Y1602732I-150J132D01*
G01Y1603352D01*
G02X169102Y1603554I202J0D01*
G37*
G36*
G01X307684D02*
X310504D01*
G02X310706Y1603352I0J-202D01*
G01Y1602732D01*
G03X310756Y1602600I200J0D01*
G02Y1599684I-1661J-1458D01*
G03X310706Y1599552I150J-132D01*
G01Y1597614D01*
G03X310756Y1597482I200J0D01*
G02Y1594566I-1661J-1458D01*
G03X310706Y1594434I150J-132D01*
G01Y1593814D01*
G02X310504Y1593612I-202J0D01*
G01X307684D01*
G02X307482Y1593814I0J202D01*
G01Y1594434D01*
G03X307432Y1594566I-200J0D01*
G02Y1597482I1661J1458D01*
G03X307482Y1597614I-150J132D01*
G01Y1599552D01*
G03X307432Y1599684I-200J0D01*
G02Y1602600I1661J1458D01*
G03X307482Y1602732I-150J132D01*
G01Y1603352D01*
G02X307684Y1603554I202J0D01*
G37*
G36*
G01X342330D02*
X345150D01*
G02X345352Y1603352I0J-202D01*
G01Y1602732D01*
G03X345402Y1602600I200J0D01*
G02Y1599684I-1661J-1458D01*
G03X345352Y1599552I150J-132D01*
G01Y1597614D01*
G03X345402Y1597482I200J0D01*
G02Y1594566I-1661J-1458D01*
G03X345352Y1594434I150J-132D01*
G01Y1593814D01*
G02X345150Y1593612I-202J0D01*
G01X342330D01*
G02X342128Y1593814I0J202D01*
G01Y1594434D01*
G03X342078Y1594566I-200J0D01*
G02Y1597482I1661J1458D01*
G03X342128Y1597614I-150J132D01*
G01Y1599552D01*
G03X342078Y1599684I-200J0D01*
G02Y1602600I1661J1458D01*
G03X342128Y1602732I-150J132D01*
G01Y1603352D01*
G02X342330Y1603554I202J0D01*
G37*
G36*
G01X636818D02*
X639638D01*
G02X639840Y1603352I0J-202D01*
G01Y1602732D01*
G03X639890Y1602600I200J0D01*
G02Y1599684I-1661J-1458D01*
G03X639840Y1599552I150J-132D01*
G01Y1597614D01*
G03X639890Y1597482I200J0D01*
G02Y1594566I-1661J-1458D01*
G03X639840Y1594434I150J-132D01*
G01Y1593814D01*
G02X639638Y1593612I-202J0D01*
G01X636818D01*
G02X636616Y1593814I0J202D01*
G01Y1594434D01*
G03X636566Y1594566I-200J0D01*
G02Y1597482I1661J1458D01*
G03X636616Y1597614I-150J132D01*
G01Y1599552D01*
G03X636566Y1599684I-200J0D01*
G02Y1602600I1661J1458D01*
G03X636616Y1602732I-150J132D01*
G01Y1603352D01*
G02X636818Y1603554I202J0D01*
G37*
G36*
G01X671464D02*
X674284D01*
G02X674486Y1603352I0J-202D01*
G01Y1602732D01*
G03X674536Y1602600I200J0D01*
G02Y1599684I-1661J-1458D01*
G03X674486Y1599552I150J-132D01*
G01Y1597614D01*
G03X674536Y1597482I200J0D01*
G02Y1594566I-1661J-1458D01*
G03X674486Y1594434I150J-132D01*
G01Y1593814D01*
G02X674284Y1593612I-202J0D01*
G01X671464D01*
G02X671262Y1593814I0J202D01*
G01Y1594434D01*
G03X671212Y1594566I-200J0D01*
G02Y1597482I1661J1458D01*
G03X671262Y1597614I-150J132D01*
G01Y1599552D01*
G03X671212Y1599684I-200J0D01*
G02Y1602600I1661J1458D01*
G03X671262Y1602732I-150J132D01*
G01Y1603352D01*
G02X671464Y1603554I202J0D01*
G37*
G36*
G01X1156424D02*
X1159244D01*
G02X1159446Y1603352I0J-202D01*
G01Y1602732D01*
G03X1159496Y1602600I200J0D01*
G02Y1599684I-1661J-1458D01*
G03X1159446Y1599552I150J-132D01*
G01Y1597614D01*
G03X1159496Y1597482I200J0D01*
G02Y1594566I-1661J-1458D01*
G03X1159446Y1594434I150J-132D01*
G01Y1593814D01*
G02X1159244Y1593612I-202J0D01*
G01X1156424D01*
G02X1156222Y1593814I0J202D01*
G01Y1594434D01*
G03X1156172Y1594566I-200J0D01*
G02Y1597482I1661J1458D01*
G03X1156222Y1597614I-150J132D01*
G01Y1599552D01*
G03X1156172Y1599684I-200J0D01*
G02Y1602600I1661J1458D01*
G03X1156222Y1602732I-150J132D01*
G01Y1603352D01*
G02X1156424Y1603554I202J0D01*
G37*
G36*
G01X1191070D02*
X1193890D01*
G02X1194092Y1603352I0J-202D01*
G01Y1602732D01*
G03X1194142Y1602600I200J0D01*
G02Y1599684I-1661J-1458D01*
G03X1194092Y1599552I150J-132D01*
G01Y1597614D01*
G03X1194142Y1597482I200J0D01*
G02Y1594566I-1661J-1458D01*
G03X1194092Y1594434I150J-132D01*
G01Y1593814D01*
G02X1193890Y1593612I-202J0D01*
G01X1191070D01*
G02X1190868Y1593814I0J202D01*
G01Y1594434D01*
G03X1190818Y1594566I-200J0D01*
G02Y1597482I1661J1458D01*
G03X1190868Y1597614I-150J132D01*
G01Y1599552D01*
G03X1190818Y1599684I-200J0D01*
G02Y1602600I1661J1458D01*
G03X1190868Y1602732I-150J132D01*
G01Y1603352D01*
G02X1191070Y1603554I202J0D01*
G37*
G36*
G01X1312330D02*
X1315150D01*
G02X1315352Y1603352I0J-202D01*
G01Y1602732D01*
G03X1315402Y1602600I200J0D01*
G02Y1599684I-1661J-1458D01*
G03X1315352Y1599552I150J-132D01*
G01Y1597614D01*
G03X1315402Y1597482I200J0D01*
G02Y1594566I-1661J-1458D01*
G03X1315352Y1594434I150J-132D01*
G01Y1593814D01*
G02X1315150Y1593612I-202J0D01*
G01X1312330D01*
G02X1312128Y1593814I0J202D01*
G01Y1594434D01*
G03X1312078Y1594566I-200J0D01*
G02Y1597482I1661J1458D01*
G03X1312128Y1597614I-150J132D01*
G01Y1599552D01*
G03X1312078Y1599684I-200J0D01*
G02Y1602600I1661J1458D01*
G03X1312128Y1602732I-150J132D01*
G01Y1603352D01*
G02X1312330Y1603554I202J0D01*
G37*
G36*
G01X1346976D02*
X1349796D01*
G02X1349998Y1603352I0J-202D01*
G01Y1602732D01*
G03X1350048Y1602600I200J0D01*
G02Y1599684I-1661J-1458D01*
G03X1349998Y1599552I150J-132D01*
G01Y1597614D01*
G03X1350048Y1597482I200J0D01*
G02Y1594566I-1661J-1458D01*
G03X1349998Y1594434I150J-132D01*
G01Y1593814D01*
G02X1349796Y1593612I-202J0D01*
G01X1346976D01*
G02X1346774Y1593814I0J202D01*
G01Y1594434D01*
G03X1346724Y1594566I-200J0D01*
G02Y1597482I1661J1458D01*
G03X1346774Y1597614I-150J132D01*
G01Y1599552D01*
G03X1346724Y1599684I-200J0D01*
G02Y1602600I1661J1458D01*
G03X1346774Y1602732I-150J132D01*
G01Y1603352D01*
G02X1346976Y1603554I202J0D01*
G37*
G36*
G01X1658786D02*
X1661606D01*
G02X1661808Y1603352I0J-202D01*
G01Y1602732D01*
G03X1661858Y1602600I200J0D01*
G02Y1599684I-1661J-1458D01*
G03X1661808Y1599552I150J-132D01*
G01Y1597614D01*
G03X1661858Y1597482I200J0D01*
G02Y1594566I-1661J-1458D01*
G03X1661808Y1594434I150J-132D01*
G01Y1593814D01*
G02X1661606Y1593612I-202J0D01*
G01X1658786D01*
G02X1658584Y1593814I0J202D01*
G01Y1594434D01*
G03X1658534Y1594566I-200J0D01*
G02Y1597482I1661J1458D01*
G03X1658584Y1597614I-150J132D01*
G01Y1599552D01*
G03X1658534Y1599684I-200J0D01*
G02Y1602600I1661J1458D01*
G03X1658584Y1602732I-150J132D01*
G01Y1603352D01*
G02X1658786Y1603554I202J0D01*
G37*
G36*
G01X1693432D02*
X1696252D01*
G02X1696454Y1603352I0J-202D01*
G01Y1602732D01*
G03X1696504Y1602600I200J0D01*
G02Y1599684I-1661J-1458D01*
G03X1696454Y1599552I150J-132D01*
G01Y1597614D01*
G03X1696504Y1597482I200J0D01*
G02Y1594566I-1661J-1458D01*
G03X1696454Y1594434I150J-132D01*
G01Y1593814D01*
G02X1696252Y1593612I-202J0D01*
G01X1693432D01*
G02X1693230Y1593814I0J202D01*
G01Y1594434D01*
G03X1693180Y1594566I-200J0D01*
G02Y1597482I1661J1458D01*
G03X1693230Y1597614I-150J132D01*
G01Y1599552D01*
G03X1693180Y1599684I-200J0D01*
G02Y1602600I1661J1458D01*
G03X1693230Y1602732I-150J132D01*
G01Y1603352D01*
G02X1693432Y1603554I202J0D01*
G37*
G36*
G01X117133D02*
X119953D01*
G02X120156Y1603352I1J-202D01*
G01Y1602730D01*
G03X120206Y1602598I200J0D01*
G02Y1599686I-1664J-1456D01*
G03X120156Y1599554I150J-132D01*
G01Y1597612D01*
G03X120206Y1597480I200J0D01*
G02Y1594568I-1664J-1456D01*
G03X120156Y1594436I150J-132D01*
G01Y1593814D01*
G02X119953Y1593612I-203J1D01*
G01X117133D01*
G02X116930Y1593814I-1J202D01*
G01Y1594436D01*
G03X116880Y1594568I-200J0D01*
G02Y1597480I1664J1456D01*
G03X116930Y1597612I-150J132D01*
G01Y1599554D01*
G03X116880Y1599686I-200J0D01*
G02Y1602598I1664J1456D01*
G03X116930Y1602730I-150J132D01*
G01Y1603352D01*
G02X117133Y1603554I203J-1D01*
G37*
G36*
G01X151779D02*
X154599D01*
G02X154802Y1603352I1J-202D01*
G01Y1602730D01*
G03X154852Y1602598I200J0D01*
G02Y1599686I-1664J-1456D01*
G03X154802Y1599554I150J-132D01*
G01Y1597612D01*
G03X154852Y1597480I200J0D01*
G02Y1594568I-1664J-1456D01*
G03X154802Y1594436I150J-132D01*
G01Y1593814D01*
G02X154599Y1593612I-203J1D01*
G01X151779D01*
G02X151576Y1593814I-1J202D01*
G01Y1594436D01*
G03X151526Y1594568I-200J0D01*
G02Y1597480I1664J1456D01*
G03X151576Y1597612I-150J132D01*
G01Y1599554D01*
G03X151526Y1599686I-200J0D01*
G02Y1602598I1664J1456D01*
G03X151576Y1602730I-150J132D01*
G01Y1603352D01*
G02X151779Y1603554I203J-1D01*
G37*
G36*
G01X186425D02*
X189245D01*
G02X189448Y1603352I1J-202D01*
G01Y1602730D01*
G03X189498Y1602598I200J0D01*
G02Y1599686I-1664J-1456D01*
G03X189448Y1599554I150J-132D01*
G01Y1597612D01*
G03X189498Y1597480I200J0D01*
G02Y1594568I-1664J-1456D01*
G03X189448Y1594436I150J-132D01*
G01Y1593814D01*
G02X189245Y1593612I-203J1D01*
G01X186425D01*
G02X186222Y1593814I-1J202D01*
G01Y1594436D01*
G03X186172Y1594568I-200J0D01*
G02Y1597480I1664J1456D01*
G03X186222Y1597612I-150J132D01*
G01Y1599554D01*
G03X186172Y1599686I-200J0D01*
G02Y1602598I1664J1456D01*
G03X186222Y1602730I-150J132D01*
G01Y1603352D01*
G02X186425Y1603554I203J-1D01*
G37*
G36*
G01X290361D02*
X293181D01*
G02X293384Y1603352I1J-202D01*
G01Y1602730D01*
G03X293434Y1602598I200J0D01*
G02Y1599686I-1664J-1456D01*
G03X293384Y1599554I150J-132D01*
G01Y1597612D01*
G03X293434Y1597480I200J0D01*
G02Y1594568I-1664J-1456D01*
G03X293384Y1594436I150J-132D01*
G01Y1593814D01*
G02X293181Y1593612I-203J1D01*
G01X290361D01*
G02X290158Y1593814I-1J202D01*
G01Y1594436D01*
G03X290108Y1594568I-200J0D01*
G02Y1597480I1664J1456D01*
G03X290158Y1597612I-150J132D01*
G01Y1599554D01*
G03X290108Y1599686I-200J0D01*
G02Y1602598I1664J1456D01*
G03X290158Y1602730I-150J132D01*
G01Y1603352D01*
G02X290361Y1603554I203J-1D01*
G37*
G36*
G01X325007D02*
X327827D01*
G02X328030Y1603352I1J-202D01*
G01Y1602730D01*
G03X328080Y1602598I200J0D01*
G02Y1599686I-1664J-1456D01*
G03X328030Y1599554I150J-132D01*
G01Y1597612D01*
G03X328080Y1597480I200J0D01*
G02Y1594568I-1664J-1456D01*
G03X328030Y1594436I150J-132D01*
G01Y1593814D01*
G02X327827Y1593612I-203J1D01*
G01X325007D01*
G02X324804Y1593814I-1J202D01*
G01Y1594436D01*
G03X324754Y1594568I-200J0D01*
G02Y1597480I1664J1456D01*
G03X324804Y1597612I-150J132D01*
G01Y1599554D01*
G03X324754Y1599686I-200J0D01*
G02Y1602598I1664J1456D01*
G03X324804Y1602730I-150J132D01*
G01Y1603352D01*
G02X325007Y1603554I203J-1D01*
G37*
G36*
G01X359653D02*
X362473D01*
G02X362676Y1603352I1J-202D01*
G01Y1602730D01*
G03X362726Y1602598I200J0D01*
G02Y1599686I-1664J-1456D01*
G03X362676Y1599554I150J-132D01*
G01Y1597612D01*
G03X362726Y1597480I200J0D01*
G02Y1594568I-1664J-1456D01*
G03X362676Y1594436I150J-132D01*
G01Y1593814D01*
G02X362473Y1593612I-203J1D01*
G01X359653D01*
G02X359450Y1593814I-1J202D01*
G01Y1594436D01*
G03X359400Y1594568I-200J0D01*
G02Y1597480I1664J1456D01*
G03X359450Y1597612I-150J132D01*
G01Y1599554D01*
G03X359400Y1599686I-200J0D01*
G02Y1602598I1664J1456D01*
G03X359450Y1602730I-150J132D01*
G01Y1603352D01*
G02X359653Y1603554I203J-1D01*
G37*
G36*
G01X515559D02*
X518379D01*
G02X518582Y1603352I1J-202D01*
G01Y1602730D01*
G03X518632Y1602598I200J0D01*
G02Y1599686I-1664J-1456D01*
G03X518582Y1599554I150J-132D01*
G01Y1597612D01*
G03X518632Y1597480I200J0D01*
G02Y1594568I-1664J-1456D01*
G03X518582Y1594436I150J-132D01*
G01Y1593814D01*
G02X518379Y1593612I-203J1D01*
G01X515559D01*
G02X515356Y1593814I-1J202D01*
G01Y1594436D01*
G03X515306Y1594568I-200J0D01*
G02Y1597480I1664J1456D01*
G03X515356Y1597612I-150J132D01*
G01Y1599554D01*
G03X515306Y1599686I-200J0D01*
G02Y1602598I1664J1456D01*
G03X515356Y1602730I-150J132D01*
G01Y1603352D01*
G02X515559Y1603554I203J-1D01*
G37*
G36*
G01X654141D02*
X656961D01*
G02X657164Y1603352I1J-202D01*
G01Y1602730D01*
G03X657214Y1602598I200J0D01*
G02Y1599686I-1664J-1456D01*
G03X657164Y1599554I150J-132D01*
G01Y1597612D01*
G03X657214Y1597480I200J0D01*
G02Y1594568I-1664J-1456D01*
G03X657164Y1594436I150J-132D01*
G01Y1593814D01*
G02X656961Y1593612I-203J1D01*
G01X654141D01*
G02X653938Y1593814I-1J202D01*
G01Y1594436D01*
G03X653888Y1594568I-200J0D01*
G02Y1597480I1664J1456D01*
G03X653938Y1597612I-150J132D01*
G01Y1599554D01*
G03X653888Y1599686I-200J0D01*
G02Y1602598I1664J1456D01*
G03X653938Y1602730I-150J132D01*
G01Y1603352D01*
G02X654141Y1603554I203J-1D01*
G37*
G36*
G01X688787D02*
X691607D01*
G02X691810Y1603352I1J-202D01*
G01Y1602730D01*
G03X691860Y1602598I200J0D01*
G02Y1599686I-1664J-1456D01*
G03X691810Y1599554I150J-132D01*
G01Y1597612D01*
G03X691860Y1597480I200J0D01*
G02Y1594568I-1664J-1456D01*
G03X691810Y1594436I150J-132D01*
G01Y1593814D01*
G02X691607Y1593612I-203J1D01*
G01X688787D01*
G02X688584Y1593814I-1J202D01*
G01Y1594436D01*
G03X688534Y1594568I-200J0D01*
G02Y1597480I1664J1456D01*
G03X688584Y1597612I-150J132D01*
G01Y1599554D01*
G03X688534Y1599686I-200J0D01*
G02Y1602598I1664J1456D01*
G03X688584Y1602730I-150J132D01*
G01Y1603352D01*
G02X688787Y1603554I203J-1D01*
G37*
G36*
G01X1139101D02*
X1141921D01*
G02X1142124Y1603352I1J-202D01*
G01Y1602730D01*
G03X1142174Y1602598I200J0D01*
G02Y1599686I-1664J-1456D01*
G03X1142124Y1599554I150J-132D01*
G01Y1597612D01*
G03X1142174Y1597480I200J0D01*
G02Y1594568I-1664J-1456D01*
G03X1142124Y1594436I150J-132D01*
G01Y1593814D01*
G02X1141921Y1593612I-203J1D01*
G01X1139101D01*
G02X1138898Y1593814I-1J202D01*
G01Y1594436D01*
G03X1138848Y1594568I-200J0D01*
G02Y1597480I1664J1456D01*
G03X1138898Y1597612I-150J132D01*
G01Y1599554D01*
G03X1138848Y1599686I-200J0D01*
G02Y1602598I1664J1456D01*
G03X1138898Y1602730I-150J132D01*
G01Y1603352D01*
G02X1139101Y1603554I203J-1D01*
G37*
G36*
G01X1173747D02*
X1176567D01*
G02X1176770Y1603352I1J-202D01*
G01Y1602730D01*
G03X1176820Y1602598I200J0D01*
G02Y1599686I-1664J-1456D01*
G03X1176770Y1599554I150J-132D01*
G01Y1597612D01*
G03X1176820Y1597480I200J0D01*
G02Y1594568I-1664J-1456D01*
G03X1176770Y1594436I150J-132D01*
G01Y1593814D01*
G02X1176567Y1593612I-203J1D01*
G01X1173747D01*
G02X1173544Y1593814I-1J202D01*
G01Y1594436D01*
G03X1173494Y1594568I-200J0D01*
G02Y1597480I1664J1456D01*
G03X1173544Y1597612I-150J132D01*
G01Y1599554D01*
G03X1173494Y1599686I-200J0D01*
G02Y1602598I1664J1456D01*
G03X1173544Y1602730I-150J132D01*
G01Y1603352D01*
G02X1173747Y1603554I203J-1D01*
G37*
G36*
G01X1329653D02*
X1332473D01*
G02X1332676Y1603352I1J-202D01*
G01Y1602730D01*
G03X1332726Y1602598I200J0D01*
G02Y1599686I-1664J-1456D01*
G03X1332676Y1599554I150J-132D01*
G01Y1597612D01*
G03X1332726Y1597480I200J0D01*
G02Y1594568I-1664J-1456D01*
G03X1332676Y1594436I150J-132D01*
G01Y1593814D01*
G02X1332473Y1593612I-203J1D01*
G01X1329653D01*
G02X1329450Y1593814I-1J202D01*
G01Y1594436D01*
G03X1329400Y1594568I-200J0D01*
G02Y1597480I1664J1456D01*
G03X1329450Y1597612I-150J132D01*
G01Y1599554D01*
G03X1329400Y1599686I-200J0D01*
G02Y1602598I1664J1456D01*
G03X1329450Y1602730I-150J132D01*
G01Y1603352D01*
G02X1329653Y1603554I203J-1D01*
G37*
G36*
G01X1364299D02*
X1367119D01*
G02X1367322Y1603352I1J-202D01*
G01Y1602730D01*
G03X1367372Y1602598I200J0D01*
G02Y1599686I-1664J-1456D01*
G03X1367322Y1599554I150J-132D01*
G01Y1597612D01*
G03X1367372Y1597480I200J0D01*
G02Y1594568I-1664J-1456D01*
G03X1367322Y1594436I150J-132D01*
G01Y1593814D01*
G02X1367119Y1593612I-203J1D01*
G01X1364299D01*
G02X1364096Y1593814I-1J202D01*
G01Y1594436D01*
G03X1364046Y1594568I-200J0D01*
G02Y1597480I1664J1456D01*
G03X1364096Y1597612I-150J132D01*
G01Y1599554D01*
G03X1364046Y1599686I-200J0D01*
G02Y1602598I1664J1456D01*
G03X1364096Y1602730I-150J132D01*
G01Y1603352D01*
G02X1364299Y1603554I203J-1D01*
G37*
G36*
G01X1676109D02*
X1678929D01*
G02X1679132Y1603352I1J-202D01*
G01Y1602730D01*
G03X1679182Y1602598I200J0D01*
G02Y1599686I-1664J-1456D01*
G03X1679132Y1599554I150J-132D01*
G01Y1597612D01*
G03X1679182Y1597480I200J0D01*
G02Y1594568I-1664J-1456D01*
G03X1679132Y1594436I150J-132D01*
G01Y1593814D01*
G02X1678929Y1593612I-203J1D01*
G01X1676109D01*
G02X1675906Y1593814I-1J202D01*
G01Y1594436D01*
G03X1675856Y1594568I-200J0D01*
G02Y1597480I1664J1456D01*
G03X1675906Y1597612I-150J132D01*
G01Y1599554D01*
G03X1675856Y1599686I-200J0D01*
G02Y1602598I1664J1456D01*
G03X1675906Y1602730I-150J132D01*
G01Y1603352D01*
G02X1676109Y1603554I203J-1D01*
G37*
G36*
G01X1710755D02*
X1713575D01*
G02X1713778Y1603352I1J-202D01*
G01Y1602730D01*
G03X1713828Y1602598I200J0D01*
G02Y1599686I-1664J-1456D01*
G03X1713778Y1599554I150J-132D01*
G01Y1597612D01*
G03X1713828Y1597480I200J0D01*
G02Y1594568I-1664J-1456D01*
G03X1713778Y1594436I150J-132D01*
G01Y1593814D01*
G02X1713575Y1593612I-203J1D01*
G01X1710755D01*
G02X1710552Y1593814I-1J202D01*
G01Y1594436D01*
G03X1710502Y1594568I-200J0D01*
G02Y1597480I1664J1456D01*
G03X1710552Y1597612I-150J132D01*
G01Y1599554D01*
G03X1710502Y1599686I-200J0D01*
G02Y1602598I1664J1456D01*
G03X1710552Y1602730I-150J132D01*
G01Y1603352D01*
G02X1710755Y1603554I203J-1D01*
G37*
G36*
G01X108472Y1614578D02*
X111292D01*
G02X111494Y1614376I0J-202D01*
G01Y1613756D01*
G03X111544Y1613624I200J0D01*
G02Y1610708I-1661J-1458D01*
G03X111494Y1610576I150J-132D01*
G01Y1608638D01*
G03X111544Y1608506I200J0D01*
G02Y1605590I-1661J-1458D01*
G03X111494Y1605458I150J-132D01*
G01Y1604838D01*
G02X111292Y1604636I-202J0D01*
G01X108472D01*
G02X108270Y1604838I0J202D01*
G01Y1605458D01*
G03X108220Y1605590I-200J0D01*
G02Y1608506I1661J1458D01*
G03X108270Y1608638I-150J132D01*
G01Y1610576D01*
G03X108220Y1610708I-200J0D01*
G02Y1613624I1661J1458D01*
G03X108270Y1613756I-150J132D01*
G01Y1614376D01*
G02X108472Y1614578I202J0D01*
G37*
G36*
G01X143118D02*
X145938D01*
G02X146140Y1614376I0J-202D01*
G01Y1613756D01*
G03X146190Y1613624I200J0D01*
G02Y1610708I-1661J-1458D01*
G03X146140Y1610576I150J-132D01*
G01Y1608638D01*
G03X146190Y1608506I200J0D01*
G02Y1605590I-1661J-1458D01*
G03X146140Y1605458I150J-132D01*
G01Y1604838D01*
G02X145938Y1604636I-202J0D01*
G01X143118D01*
G02X142916Y1604838I0J202D01*
G01Y1605458D01*
G03X142866Y1605590I-200J0D01*
G02Y1608506I1661J1458D01*
G03X142916Y1608638I-150J132D01*
G01Y1610576D01*
G03X142866Y1610708I-200J0D01*
G02Y1613624I1661J1458D01*
G03X142916Y1613756I-150J132D01*
G01Y1614376D01*
G02X143118Y1614578I202J0D01*
G37*
G36*
G01X160440D02*
X163260D01*
G02X163462Y1614376I0J-202D01*
G01Y1613756D01*
G03X163512Y1613624I200J0D01*
G02Y1610708I-1661J-1458D01*
G03X163462Y1610576I150J-132D01*
G01Y1608638D01*
G03X163512Y1608506I200J0D01*
G02Y1605590I-1661J-1458D01*
G03X163462Y1605458I150J-132D01*
G01Y1604838D01*
G02X163260Y1604636I-202J0D01*
G01X160440D01*
G02X160238Y1604838I0J202D01*
G01Y1605458D01*
G03X160188Y1605590I-200J0D01*
G02Y1608506I1661J1458D01*
G03X160238Y1608638I-150J132D01*
G01Y1610576D01*
G03X160188Y1610708I-200J0D01*
G02Y1613624I1661J1458D01*
G03X160238Y1613756I-150J132D01*
G01Y1614376D01*
G02X160440Y1614578I202J0D01*
G37*
G36*
G01X281700D02*
X284520D01*
G02X284722Y1614376I0J-202D01*
G01Y1613756D01*
G03X284772Y1613624I200J0D01*
G02Y1610708I-1661J-1458D01*
G03X284722Y1610576I150J-132D01*
G01Y1608638D01*
G03X284772Y1608506I200J0D01*
G02Y1605590I-1661J-1458D01*
G03X284722Y1605458I150J-132D01*
G01Y1604838D01*
G02X284520Y1604636I-202J0D01*
G01X281700D01*
G02X281498Y1604838I0J202D01*
G01Y1605458D01*
G03X281448Y1605590I-200J0D01*
G02Y1608506I1661J1458D01*
G03X281498Y1608638I-150J132D01*
G01Y1610576D01*
G03X281448Y1610708I-200J0D01*
G02Y1613624I1661J1458D01*
G03X281498Y1613756I-150J132D01*
G01Y1614376D01*
G02X281700Y1614578I202J0D01*
G37*
G36*
G01X316346D02*
X319166D01*
G02X319368Y1614376I0J-202D01*
G01Y1613756D01*
G03X319418Y1613624I200J0D01*
G02Y1610708I-1661J-1458D01*
G03X319368Y1610576I150J-132D01*
G01Y1608638D01*
G03X319418Y1608506I200J0D01*
G02Y1605590I-1661J-1458D01*
G03X319368Y1605458I150J-132D01*
G01Y1604838D01*
G02X319166Y1604636I-202J0D01*
G01X316346D01*
G02X316144Y1604838I0J202D01*
G01Y1605458D01*
G03X316094Y1605590I-200J0D01*
G02Y1608506I1661J1458D01*
G03X316144Y1608638I-150J132D01*
G01Y1610576D01*
G03X316094Y1610708I-200J0D01*
G02Y1613624I1661J1458D01*
G03X316144Y1613756I-150J132D01*
G01Y1614376D01*
G02X316346Y1614578I202J0D01*
G37*
G36*
G01X333668D02*
X336488D01*
G02X336690Y1614376I0J-202D01*
G01Y1613756D01*
G03X336740Y1613624I200J0D01*
G02Y1610708I-1661J-1458D01*
G03X336690Y1610576I150J-132D01*
G01Y1608638D01*
G03X336740Y1608506I200J0D01*
G02Y1605590I-1661J-1458D01*
G03X336690Y1605458I150J-132D01*
G01Y1604838D01*
G02X336488Y1604636I-202J0D01*
G01X333668D01*
G02X333466Y1604838I0J202D01*
G01Y1605458D01*
G03X333416Y1605590I-200J0D01*
G02Y1608506I1661J1458D01*
G03X333466Y1608638I-150J132D01*
G01Y1610576D01*
G03X333416Y1610708I-200J0D01*
G02Y1613624I1661J1458D01*
G03X333466Y1613756I-150J132D01*
G01Y1614376D01*
G02X333668Y1614578I202J0D01*
G37*
G36*
G01X645480D02*
X648300D01*
G02X648502Y1614376I0J-202D01*
G01Y1613756D01*
G03X648552Y1613624I200J0D01*
G02Y1610708I-1661J-1458D01*
G03X648502Y1610576I150J-132D01*
G01Y1608638D01*
G03X648552Y1608506I200J0D01*
G02Y1605590I-1661J-1458D01*
G03X648502Y1605458I150J-132D01*
G01Y1604838D01*
G02X648300Y1604636I-202J0D01*
G01X645480D01*
G02X645278Y1604838I0J202D01*
G01Y1605458D01*
G03X645228Y1605590I-200J0D01*
G02Y1608506I1661J1458D01*
G03X645278Y1608638I-150J132D01*
G01Y1610576D01*
G03X645228Y1610708I-200J0D01*
G02Y1613624I1661J1458D01*
G03X645278Y1613756I-150J132D01*
G01Y1614376D01*
G02X645480Y1614578I202J0D01*
G37*
G36*
G01X1130440D02*
X1133260D01*
G02X1133462Y1614376I0J-202D01*
G01Y1613756D01*
G03X1133512Y1613624I200J0D01*
G02Y1610708I-1661J-1458D01*
G03X1133462Y1610576I150J-132D01*
G01Y1608638D01*
G03X1133512Y1608506I200J0D01*
G02Y1605590I-1661J-1458D01*
G03X1133462Y1605458I150J-132D01*
G01Y1604838D01*
G02X1133260Y1604636I-202J0D01*
G01X1130440D01*
G02X1130238Y1604838I0J202D01*
G01Y1605458D01*
G03X1130188Y1605590I-200J0D01*
G02Y1608506I1661J1458D01*
G03X1130238Y1608638I-150J132D01*
G01Y1610576D01*
G03X1130188Y1610708I-200J0D01*
G02Y1613624I1661J1458D01*
G03X1130238Y1613756I-150J132D01*
G01Y1614376D01*
G02X1130440Y1614578I202J0D01*
G37*
G36*
G01X1165086D02*
X1167906D01*
G02X1168108Y1614376I0J-202D01*
G01Y1613756D01*
G03X1168158Y1613624I200J0D01*
G02Y1610708I-1661J-1458D01*
G03X1168108Y1610576I150J-132D01*
G01Y1608638D01*
G03X1168158Y1608506I200J0D01*
G02Y1605590I-1661J-1458D01*
G03X1168108Y1605458I150J-132D01*
G01Y1604838D01*
G02X1167906Y1604636I-202J0D01*
G01X1165086D01*
G02X1164884Y1604838I0J202D01*
G01Y1605458D01*
G03X1164834Y1605590I-200J0D01*
G02Y1608506I1661J1458D01*
G03X1164884Y1608638I-150J132D01*
G01Y1610576D01*
G03X1164834Y1610708I-200J0D01*
G02Y1613624I1661J1458D01*
G03X1164884Y1613756I-150J132D01*
G01Y1614376D01*
G02X1165086Y1614578I202J0D01*
G37*
G36*
G01X1182408D02*
X1185228D01*
G02X1185430Y1614376I0J-202D01*
G01Y1613756D01*
G03X1185480Y1613624I200J0D01*
G02Y1610708I-1661J-1458D01*
G03X1185430Y1610576I150J-132D01*
G01Y1608638D01*
G03X1185480Y1608506I200J0D01*
G02Y1605590I-1661J-1458D01*
G03X1185430Y1605458I150J-132D01*
G01Y1604838D01*
G02X1185228Y1604636I-202J0D01*
G01X1182408D01*
G02X1182206Y1604838I0J202D01*
G01Y1605458D01*
G03X1182156Y1605590I-200J0D01*
G02Y1608506I1661J1458D01*
G03X1182206Y1608638I-150J132D01*
G01Y1610576D01*
G03X1182156Y1610708I-200J0D01*
G02Y1613624I1661J1458D01*
G03X1182206Y1613756I-150J132D01*
G01Y1614376D01*
G02X1182408Y1614578I202J0D01*
G37*
G36*
G01X1320992D02*
X1323812D01*
G02X1324014Y1614376I0J-202D01*
G01Y1613756D01*
G03X1324064Y1613624I200J0D01*
G02Y1610708I-1661J-1458D01*
G03X1324014Y1610576I150J-132D01*
G01Y1608638D01*
G03X1324064Y1608506I200J0D01*
G02Y1605590I-1661J-1458D01*
G03X1324014Y1605458I150J-132D01*
G01Y1604838D01*
G02X1323812Y1604636I-202J0D01*
G01X1320992D01*
G02X1320790Y1604838I0J202D01*
G01Y1605458D01*
G03X1320740Y1605590I-200J0D01*
G02Y1608506I1661J1458D01*
G03X1320790Y1608638I-150J132D01*
G01Y1610576D01*
G03X1320740Y1610708I-200J0D01*
G02Y1613624I1661J1458D01*
G03X1320790Y1613756I-150J132D01*
G01Y1614376D01*
G02X1320992Y1614578I202J0D01*
G37*
G36*
G01X1667448D02*
X1670268D01*
G02X1670470Y1614376I0J-202D01*
G01Y1613756D01*
G03X1670520Y1613624I200J0D01*
G02Y1610708I-1661J-1458D01*
G03X1670470Y1610576I150J-132D01*
G01Y1608638D01*
G03X1670520Y1608506I200J0D01*
G02Y1605590I-1661J-1458D01*
G03X1670470Y1605458I150J-132D01*
G01Y1604838D01*
G02X1670268Y1604636I-202J0D01*
G01X1667448D01*
G02X1667246Y1604838I0J202D01*
G01Y1605458D01*
G03X1667196Y1605590I-200J0D01*
G02Y1608506I1661J1458D01*
G03X1667246Y1608638I-150J132D01*
G01Y1610576D01*
G03X1667196Y1610708I-200J0D01*
G02Y1613624I1661J1458D01*
G03X1667246Y1613756I-150J132D01*
G01Y1614376D01*
G02X1667448Y1614578I202J0D01*
G37*
G36*
G01X125795D02*
X128615D01*
G02X128818Y1614376I1J-202D01*
G01Y1613754D01*
G03X128868Y1613622I200J0D01*
G02Y1610710I-1664J-1456D01*
G03X128818Y1610578I150J-132D01*
G01Y1608636D01*
G03X128868Y1608504I200J0D01*
G02Y1605592I-1664J-1456D01*
G03X128818Y1605460I150J-132D01*
G01Y1604838D01*
G02X128615Y1604636I-203J1D01*
G01X125795D01*
G02X125592Y1604838I-1J202D01*
G01Y1605460D01*
G03X125542Y1605592I-200J0D01*
G02Y1608504I1664J1456D01*
G03X125592Y1608636I-150J132D01*
G01Y1610578D01*
G03X125542Y1610710I-200J0D01*
G02Y1613622I1664J1456D01*
G03X125592Y1613754I-150J132D01*
G01Y1614376D01*
G02X125795Y1614578I203J-1D01*
G37*
G36*
G01X299023D02*
X301843D01*
G02X302046Y1614376I1J-202D01*
G01Y1613754D01*
G03X302096Y1613622I200J0D01*
G02Y1610710I-1664J-1456D01*
G03X302046Y1610578I150J-132D01*
G01Y1608636D01*
G03X302096Y1608504I200J0D01*
G02Y1605592I-1664J-1456D01*
G03X302046Y1605460I150J-132D01*
G01Y1604838D01*
G02X301843Y1604636I-203J1D01*
G01X299023D01*
G02X298820Y1604838I-1J202D01*
G01Y1605460D01*
G03X298770Y1605592I-200J0D01*
G02Y1608504I1664J1456D01*
G03X298820Y1608636I-150J132D01*
G01Y1610578D01*
G03X298770Y1610710I-200J0D01*
G02Y1613622I1664J1456D01*
G03X298820Y1613754I-150J132D01*
G01Y1614376D01*
G02X299023Y1614578I203J-1D01*
G37*
G36*
G01X628157D02*
X630977D01*
G02X631180Y1614376I1J-202D01*
G01Y1613754D01*
G03X631230Y1613622I200J0D01*
G02Y1610710I-1664J-1456D01*
G03X631180Y1610578I150J-132D01*
G01Y1608636D01*
G03X631230Y1608504I200J0D01*
G02Y1605592I-1664J-1456D01*
G03X631180Y1605460I150J-132D01*
G01Y1604838D01*
G02X630977Y1604636I-203J1D01*
G01X628157D01*
G02X627954Y1604838I-1J202D01*
G01Y1605460D01*
G03X627904Y1605592I-200J0D01*
G02Y1608504I1664J1456D01*
G03X627954Y1608636I-150J132D01*
G01Y1610578D01*
G03X627904Y1610710I-200J0D01*
G02Y1613622I1664J1456D01*
G03X627954Y1613754I-150J132D01*
G01Y1614376D01*
G02X628157Y1614578I203J-1D01*
G37*
G36*
G01X662803D02*
X665623D01*
G02X665826Y1614376I1J-202D01*
G01Y1613754D01*
G03X665876Y1613622I200J0D01*
G02Y1610710I-1664J-1456D01*
G03X665826Y1610578I150J-132D01*
G01Y1608636D01*
G03X665876Y1608504I200J0D01*
G02Y1605592I-1664J-1456D01*
G03X665826Y1605460I150J-132D01*
G01Y1604838D01*
G02X665623Y1604636I-203J1D01*
G01X662803D01*
G02X662600Y1604838I-1J202D01*
G01Y1605460D01*
G03X662550Y1605592I-200J0D01*
G02Y1608504I1664J1456D01*
G03X662600Y1608636I-150J132D01*
G01Y1610578D01*
G03X662550Y1610710I-200J0D01*
G02Y1613622I1664J1456D01*
G03X662600Y1613754I-150J132D01*
G01Y1614376D01*
G02X662803Y1614578I203J-1D01*
G37*
G36*
G01X680125D02*
X682945D01*
G02X683148Y1614376I1J-202D01*
G01Y1613754D01*
G03X683198Y1613622I200J0D01*
G02Y1610710I-1664J-1456D01*
G03X683148Y1610578I150J-132D01*
G01Y1608636D01*
G03X683198Y1608504I200J0D01*
G02Y1605592I-1664J-1456D01*
G03X683148Y1605460I150J-132D01*
G01Y1604838D01*
G02X682945Y1604636I-203J1D01*
G01X680125D01*
G02X679922Y1604838I-1J202D01*
G01Y1605460D01*
G03X679872Y1605592I-200J0D01*
G02Y1608504I1664J1456D01*
G03X679922Y1608636I-150J132D01*
G01Y1610578D01*
G03X679872Y1610710I-200J0D01*
G02Y1613622I1664J1456D01*
G03X679922Y1613754I-150J132D01*
G01Y1614376D01*
G02X680125Y1614578I203J-1D01*
G37*
G36*
G01X1147763D02*
X1150583D01*
G02X1150786Y1614376I1J-202D01*
G01Y1613754D01*
G03X1150836Y1613622I200J0D01*
G02Y1610710I-1664J-1456D01*
G03X1150786Y1610578I150J-132D01*
G01Y1608636D01*
G03X1150836Y1608504I200J0D01*
G02Y1605592I-1664J-1456D01*
G03X1150786Y1605460I150J-132D01*
G01Y1604838D01*
G02X1150583Y1604636I-203J1D01*
G01X1147763D01*
G02X1147560Y1604838I-1J202D01*
G01Y1605460D01*
G03X1147510Y1605592I-200J0D01*
G02Y1608504I1664J1456D01*
G03X1147560Y1608636I-150J132D01*
G01Y1610578D01*
G03X1147510Y1610710I-200J0D01*
G02Y1613622I1664J1456D01*
G03X1147560Y1613754I-150J132D01*
G01Y1614376D01*
G02X1147763Y1614578I203J-1D01*
G37*
G36*
G01X1303669D02*
X1306489D01*
G02X1306692Y1614376I1J-202D01*
G01Y1613754D01*
G03X1306742Y1613622I200J0D01*
G02Y1610710I-1664J-1456D01*
G03X1306692Y1610578I150J-132D01*
G01Y1608636D01*
G03X1306742Y1608504I200J0D01*
G02Y1605592I-1664J-1456D01*
G03X1306692Y1605460I150J-132D01*
G01Y1604838D01*
G02X1306489Y1604636I-203J1D01*
G01X1303669D01*
G02X1303466Y1604838I-1J202D01*
G01Y1605460D01*
G03X1303416Y1605592I-200J0D01*
G02Y1608504I1664J1456D01*
G03X1303466Y1608636I-150J132D01*
G01Y1610578D01*
G03X1303416Y1610710I-200J0D01*
G02Y1613622I1664J1456D01*
G03X1303466Y1613754I-150J132D01*
G01Y1614376D01*
G02X1303669Y1614578I203J-1D01*
G37*
G36*
G01X1338315D02*
X1341135D01*
G02X1341338Y1614376I1J-202D01*
G01Y1613754D01*
G03X1341388Y1613622I200J0D01*
G02Y1610710I-1664J-1456D01*
G03X1341338Y1610578I150J-132D01*
G01Y1608636D01*
G03X1341388Y1608504I200J0D01*
G02Y1605592I-1664J-1456D01*
G03X1341338Y1605460I150J-132D01*
G01Y1604838D01*
G02X1341135Y1604636I-203J1D01*
G01X1338315D01*
G02X1338112Y1604838I-1J202D01*
G01Y1605460D01*
G03X1338062Y1605592I-200J0D01*
G02Y1608504I1664J1456D01*
G03X1338112Y1608636I-150J132D01*
G01Y1610578D01*
G03X1338062Y1610710I-200J0D01*
G02Y1613622I1664J1456D01*
G03X1338112Y1613754I-150J132D01*
G01Y1614376D01*
G02X1338315Y1614578I203J-1D01*
G37*
G36*
G01X1355637D02*
X1358457D01*
G02X1358660Y1614376I1J-202D01*
G01Y1613754D01*
G03X1358710Y1613622I200J0D01*
G02Y1610710I-1664J-1456D01*
G03X1358660Y1610578I150J-132D01*
G01Y1608636D01*
G03X1358710Y1608504I200J0D01*
G02Y1605592I-1664J-1456D01*
G03X1358660Y1605460I150J-132D01*
G01Y1604838D01*
G02X1358457Y1604636I-203J1D01*
G01X1355637D01*
G02X1355434Y1604838I-1J202D01*
G01Y1605460D01*
G03X1355384Y1605592I-200J0D01*
G02Y1608504I1664J1456D01*
G03X1355434Y1608636I-150J132D01*
G01Y1610578D01*
G03X1355384Y1610710I-200J0D01*
G02Y1613622I1664J1456D01*
G03X1355434Y1613754I-150J132D01*
G01Y1614376D01*
G02X1355637Y1614578I203J-1D01*
G37*
G36*
G01X1476897D02*
X1479717D01*
G02X1479920Y1614376I1J-202D01*
G01Y1613754D01*
G03X1479970Y1613622I200J0D01*
G02Y1610710I-1664J-1456D01*
G03X1479920Y1610578I150J-132D01*
G01Y1608636D01*
G03X1479970Y1608504I200J0D01*
G02Y1605592I-1664J-1456D01*
G03X1479920Y1605460I150J-132D01*
G01Y1604838D01*
G02X1479717Y1604636I-203J1D01*
G01X1476897D01*
G02X1476694Y1604838I-1J202D01*
G01Y1605460D01*
G03X1476644Y1605592I-200J0D01*
G02Y1608504I1664J1456D01*
G03X1476694Y1608636I-150J132D01*
G01Y1610578D01*
G03X1476644Y1610710I-200J0D01*
G02Y1613622I1664J1456D01*
G03X1476694Y1613754I-150J132D01*
G01Y1614376D01*
G02X1476897Y1614578I203J-1D01*
G37*
G36*
G01X1650125D02*
X1652945D01*
G02X1653148Y1614376I1J-202D01*
G01Y1613754D01*
G03X1653198Y1613622I200J0D01*
G02Y1610710I-1664J-1456D01*
G03X1653148Y1610578I150J-132D01*
G01Y1608636D01*
G03X1653198Y1608504I200J0D01*
G02Y1605592I-1664J-1456D01*
G03X1653148Y1605460I150J-132D01*
G01Y1604838D01*
G02X1652945Y1604636I-203J1D01*
G01X1650125D01*
G02X1649922Y1604838I-1J202D01*
G01Y1605460D01*
G03X1649872Y1605592I-200J0D01*
G02Y1608504I1664J1456D01*
G03X1649922Y1608636I-150J132D01*
G01Y1610578D01*
G03X1649872Y1610710I-200J0D01*
G02Y1613622I1664J1456D01*
G03X1649922Y1613754I-150J132D01*
G01Y1614376D01*
G02X1650125Y1614578I203J-1D01*
G37*
G36*
G01X1684771D02*
X1687591D01*
G02X1687794Y1614376I1J-202D01*
G01Y1613754D01*
G03X1687844Y1613622I200J0D01*
G02Y1610710I-1664J-1456D01*
G03X1687794Y1610578I150J-132D01*
G01Y1608636D01*
G03X1687844Y1608504I200J0D01*
G02Y1605592I-1664J-1456D01*
G03X1687794Y1605460I150J-132D01*
G01Y1604838D01*
G02X1687591Y1604636I-203J1D01*
G01X1684771D01*
G02X1684568Y1604838I-1J202D01*
G01Y1605460D01*
G03X1684518Y1605592I-200J0D01*
G02Y1608504I1664J1456D01*
G03X1684568Y1608636I-150J132D01*
G01Y1610578D01*
G03X1684518Y1610710I-200J0D01*
G02Y1613622I1664J1456D01*
G03X1684568Y1613754I-150J132D01*
G01Y1614376D01*
G02X1684771Y1614578I203J-1D01*
G37*
G36*
G01X1702093D02*
X1704913D01*
G02X1705116Y1614376I1J-202D01*
G01Y1613754D01*
G03X1705166Y1613622I200J0D01*
G02Y1610710I-1664J-1456D01*
G03X1705116Y1610578I150J-132D01*
G01Y1608636D01*
G03X1705166Y1608504I200J0D01*
G02Y1605592I-1664J-1456D01*
G03X1705116Y1605460I150J-132D01*
G01Y1604838D01*
G02X1704913Y1604636I-203J1D01*
G01X1702093D01*
G02X1701890Y1604838I-1J202D01*
G01Y1605460D01*
G03X1701840Y1605592I-200J0D01*
G02Y1608504I1664J1456D01*
G03X1701890Y1608636I-150J132D01*
G01Y1610578D01*
G03X1701840Y1610710I-200J0D01*
G02Y1613622I1664J1456D01*
G03X1701890Y1613754I-150J132D01*
G01Y1614376D01*
G02X1702093Y1614578I203J-1D01*
G37*
G36*
G01X134456Y1618908D02*
X137276D01*
G02X137478Y1618706I0J-202D01*
G01Y1618086D01*
G03X137528Y1617954I200J0D01*
G02Y1615038I-1661J-1458D01*
G03X137478Y1614906I150J-132D01*
G01Y1612968D01*
G03X137528Y1612836I200J0D01*
G02Y1609920I-1661J-1458D01*
G03X137478Y1609788I150J-132D01*
G01Y1609168D01*
G02X137276Y1608966I-202J0D01*
G01X134456D01*
G02X134254Y1609168I0J202D01*
G01Y1609788D01*
G03X134204Y1609920I-200J0D01*
G02Y1612836I1661J1458D01*
G03X134254Y1612968I-150J132D01*
G01Y1614906D01*
G03X134204Y1615038I-200J0D01*
G02Y1617954I1661J1458D01*
G03X134254Y1618086I-150J132D01*
G01Y1618706D01*
G02X134456Y1618908I202J0D01*
G37*
G36*
G01X169102D02*
X171922D01*
G02X172124Y1618706I0J-202D01*
G01Y1618086D01*
G03X172174Y1617954I200J0D01*
G02Y1615038I-1661J-1458D01*
G03X172124Y1614906I150J-132D01*
G01Y1612968D01*
G03X172174Y1612836I200J0D01*
G02Y1609920I-1661J-1458D01*
G03X172124Y1609788I150J-132D01*
G01Y1609168D01*
G02X171922Y1608966I-202J0D01*
G01X169102D01*
G02X168900Y1609168I0J202D01*
G01Y1609788D01*
G03X168850Y1609920I-200J0D01*
G02Y1612836I1661J1458D01*
G03X168900Y1612968I-150J132D01*
G01Y1614906D01*
G03X168850Y1615038I-200J0D01*
G02Y1617954I1661J1458D01*
G03X168900Y1618086I-150J132D01*
G01Y1618706D01*
G02X169102Y1618908I202J0D01*
G37*
G36*
G01X307684D02*
X310504D01*
G02X310706Y1618706I0J-202D01*
G01Y1618086D01*
G03X310756Y1617954I200J0D01*
G02Y1615038I-1661J-1458D01*
G03X310706Y1614906I150J-132D01*
G01Y1612968D01*
G03X310756Y1612836I200J0D01*
G02Y1609920I-1661J-1458D01*
G03X310706Y1609788I150J-132D01*
G01Y1609168D01*
G02X310504Y1608966I-202J0D01*
G01X307684D01*
G02X307482Y1609168I0J202D01*
G01Y1609788D01*
G03X307432Y1609920I-200J0D01*
G02Y1612836I1661J1458D01*
G03X307482Y1612968I-150J132D01*
G01Y1614906D01*
G03X307432Y1615038I-200J0D01*
G02Y1617954I1661J1458D01*
G03X307482Y1618086I-150J132D01*
G01Y1618706D01*
G02X307684Y1618908I202J0D01*
G37*
G36*
G01X342330D02*
X345150D01*
G02X345352Y1618706I0J-202D01*
G01Y1618086D01*
G03X345402Y1617954I200J0D01*
G02Y1615038I-1661J-1458D01*
G03X345352Y1614906I150J-132D01*
G01Y1612968D01*
G03X345402Y1612836I200J0D01*
G02Y1609920I-1661J-1458D01*
G03X345352Y1609788I150J-132D01*
G01Y1609168D01*
G02X345150Y1608966I-202J0D01*
G01X342330D01*
G02X342128Y1609168I0J202D01*
G01Y1609788D01*
G03X342078Y1609920I-200J0D01*
G02Y1612836I1661J1458D01*
G03X342128Y1612968I-150J132D01*
G01Y1614906D01*
G03X342078Y1615038I-200J0D01*
G02Y1617954I1661J1458D01*
G03X342128Y1618086I-150J132D01*
G01Y1618706D01*
G02X342330Y1618908I202J0D01*
G37*
G36*
G01X636818D02*
X639638D01*
G02X639840Y1618706I0J-202D01*
G01Y1618086D01*
G03X639890Y1617954I200J0D01*
G02Y1615038I-1661J-1458D01*
G03X639840Y1614906I150J-132D01*
G01Y1612968D01*
G03X639890Y1612836I200J0D01*
G02Y1609920I-1661J-1458D01*
G03X639840Y1609788I150J-132D01*
G01Y1609168D01*
G02X639638Y1608966I-202J0D01*
G01X636818D01*
G02X636616Y1609168I0J202D01*
G01Y1609788D01*
G03X636566Y1609920I-200J0D01*
G02Y1612836I1661J1458D01*
G03X636616Y1612968I-150J132D01*
G01Y1614906D01*
G03X636566Y1615038I-200J0D01*
G02Y1617954I1661J1458D01*
G03X636616Y1618086I-150J132D01*
G01Y1618706D01*
G02X636818Y1618908I202J0D01*
G37*
G36*
G01X671464D02*
X674284D01*
G02X674486Y1618706I0J-202D01*
G01Y1618086D01*
G03X674536Y1617954I200J0D01*
G02Y1615038I-1661J-1458D01*
G03X674486Y1614906I150J-132D01*
G01Y1612968D01*
G03X674536Y1612836I200J0D01*
G02Y1609920I-1661J-1458D01*
G03X674486Y1609788I150J-132D01*
G01Y1609168D01*
G02X674284Y1608966I-202J0D01*
G01X671464D01*
G02X671262Y1609168I0J202D01*
G01Y1609788D01*
G03X671212Y1609920I-200J0D01*
G02Y1612836I1661J1458D01*
G03X671262Y1612968I-150J132D01*
G01Y1614906D01*
G03X671212Y1615038I-200J0D01*
G02Y1617954I1661J1458D01*
G03X671262Y1618086I-150J132D01*
G01Y1618706D01*
G02X671464Y1618908I202J0D01*
G37*
G36*
G01X1156424D02*
X1159244D01*
G02X1159446Y1618706I0J-202D01*
G01Y1618086D01*
G03X1159496Y1617954I200J0D01*
G02Y1615038I-1661J-1458D01*
G03X1159446Y1614906I150J-132D01*
G01Y1612968D01*
G03X1159496Y1612836I200J0D01*
G02Y1609920I-1661J-1458D01*
G03X1159446Y1609788I150J-132D01*
G01Y1609168D01*
G02X1159244Y1608966I-202J0D01*
G01X1156424D01*
G02X1156222Y1609168I0J202D01*
G01Y1609788D01*
G03X1156172Y1609920I-200J0D01*
G02Y1612836I1661J1458D01*
G03X1156222Y1612968I-150J132D01*
G01Y1614906D01*
G03X1156172Y1615038I-200J0D01*
G02Y1617954I1661J1458D01*
G03X1156222Y1618086I-150J132D01*
G01Y1618706D01*
G02X1156424Y1618908I202J0D01*
G37*
G36*
G01X1191070D02*
X1193890D01*
G02X1194092Y1618706I0J-202D01*
G01Y1618086D01*
G03X1194142Y1617954I200J0D01*
G02Y1615038I-1661J-1458D01*
G03X1194092Y1614906I150J-132D01*
G01Y1612968D01*
G03X1194142Y1612836I200J0D01*
G02Y1609920I-1661J-1458D01*
G03X1194092Y1609788I150J-132D01*
G01Y1609168D01*
G02X1193890Y1608966I-202J0D01*
G01X1191070D01*
G02X1190868Y1609168I0J202D01*
G01Y1609788D01*
G03X1190818Y1609920I-200J0D01*
G02Y1612836I1661J1458D01*
G03X1190868Y1612968I-150J132D01*
G01Y1614906D01*
G03X1190818Y1615038I-200J0D01*
G02Y1617954I1661J1458D01*
G03X1190868Y1618086I-150J132D01*
G01Y1618706D01*
G02X1191070Y1618908I202J0D01*
G37*
G36*
G01X1312330D02*
X1315150D01*
G02X1315352Y1618706I0J-202D01*
G01Y1618086D01*
G03X1315402Y1617954I200J0D01*
G02Y1615038I-1661J-1458D01*
G03X1315352Y1614906I150J-132D01*
G01Y1612968D01*
G03X1315402Y1612836I200J0D01*
G02Y1609920I-1661J-1458D01*
G03X1315352Y1609788I150J-132D01*
G01Y1609168D01*
G02X1315150Y1608966I-202J0D01*
G01X1312330D01*
G02X1312128Y1609168I0J202D01*
G01Y1609788D01*
G03X1312078Y1609920I-200J0D01*
G02Y1612836I1661J1458D01*
G03X1312128Y1612968I-150J132D01*
G01Y1614906D01*
G03X1312078Y1615038I-200J0D01*
G02Y1617954I1661J1458D01*
G03X1312128Y1618086I-150J132D01*
G01Y1618706D01*
G02X1312330Y1618908I202J0D01*
G37*
G36*
G01X1346976D02*
X1349796D01*
G02X1349998Y1618706I0J-202D01*
G01Y1618086D01*
G03X1350048Y1617954I200J0D01*
G02Y1615038I-1661J-1458D01*
G03X1349998Y1614906I150J-132D01*
G01Y1612968D01*
G03X1350048Y1612836I200J0D01*
G02Y1609920I-1661J-1458D01*
G03X1349998Y1609788I150J-132D01*
G01Y1609168D01*
G02X1349796Y1608966I-202J0D01*
G01X1346976D01*
G02X1346774Y1609168I0J202D01*
G01Y1609788D01*
G03X1346724Y1609920I-200J0D01*
G02Y1612836I1661J1458D01*
G03X1346774Y1612968I-150J132D01*
G01Y1614906D01*
G03X1346724Y1615038I-200J0D01*
G02Y1617954I1661J1458D01*
G03X1346774Y1618086I-150J132D01*
G01Y1618706D01*
G02X1346976Y1618908I202J0D01*
G37*
G36*
G01X1658786D02*
X1661606D01*
G02X1661808Y1618706I0J-202D01*
G01Y1618086D01*
G03X1661858Y1617954I200J0D01*
G02Y1615038I-1661J-1458D01*
G03X1661808Y1614906I150J-132D01*
G01Y1612968D01*
G03X1661858Y1612836I200J0D01*
G02Y1609920I-1661J-1458D01*
G03X1661808Y1609788I150J-132D01*
G01Y1609168D01*
G02X1661606Y1608966I-202J0D01*
G01X1658786D01*
G02X1658584Y1609168I0J202D01*
G01Y1609788D01*
G03X1658534Y1609920I-200J0D01*
G02Y1612836I1661J1458D01*
G03X1658584Y1612968I-150J132D01*
G01Y1614906D01*
G03X1658534Y1615038I-200J0D01*
G02Y1617954I1661J1458D01*
G03X1658584Y1618086I-150J132D01*
G01Y1618706D01*
G02X1658786Y1618908I202J0D01*
G37*
G36*
G01X1693432D02*
X1696252D01*
G02X1696454Y1618706I0J-202D01*
G01Y1618086D01*
G03X1696504Y1617954I200J0D01*
G02Y1615038I-1661J-1458D01*
G03X1696454Y1614906I150J-132D01*
G01Y1612968D01*
G03X1696504Y1612836I200J0D01*
G02Y1609920I-1661J-1458D01*
G03X1696454Y1609788I150J-132D01*
G01Y1609168D01*
G02X1696252Y1608966I-202J0D01*
G01X1693432D01*
G02X1693230Y1609168I0J202D01*
G01Y1609788D01*
G03X1693180Y1609920I-200J0D01*
G02Y1612836I1661J1458D01*
G03X1693230Y1612968I-150J132D01*
G01Y1614906D01*
G03X1693180Y1615038I-200J0D01*
G02Y1617954I1661J1458D01*
G03X1693230Y1618086I-150J132D01*
G01Y1618706D01*
G02X1693432Y1618908I202J0D01*
G37*
G36*
G01X117133D02*
X119953D01*
G02X120156Y1618706I1J-202D01*
G01Y1618084D01*
G03X120206Y1617952I200J0D01*
G02Y1615040I-1664J-1456D01*
G03X120156Y1614908I150J-132D01*
G01Y1612966D01*
G03X120206Y1612834I200J0D01*
G02Y1609922I-1664J-1456D01*
G03X120156Y1609790I150J-132D01*
G01Y1609168D01*
G02X119953Y1608966I-203J1D01*
G01X117133D01*
G02X116930Y1609168I-1J202D01*
G01Y1609790D01*
G03X116880Y1609922I-200J0D01*
G02Y1612834I1664J1456D01*
G03X116930Y1612966I-150J132D01*
G01Y1614908D01*
G03X116880Y1615040I-200J0D01*
G02Y1617952I1664J1456D01*
G03X116930Y1618084I-150J132D01*
G01Y1618706D01*
G02X117133Y1618908I203J-1D01*
G37*
G36*
G01X151779D02*
X154599D01*
G02X154802Y1618706I1J-202D01*
G01Y1618084D01*
G03X154852Y1617952I200J0D01*
G02Y1615040I-1664J-1456D01*
G03X154802Y1614908I150J-132D01*
G01Y1612966D01*
G03X154852Y1612834I200J0D01*
G02Y1609922I-1664J-1456D01*
G03X154802Y1609790I150J-132D01*
G01Y1609168D01*
G02X154599Y1608966I-203J1D01*
G01X151779D01*
G02X151576Y1609168I-1J202D01*
G01Y1609790D01*
G03X151526Y1609922I-200J0D01*
G02Y1612834I1664J1456D01*
G03X151576Y1612966I-150J132D01*
G01Y1614908D01*
G03X151526Y1615040I-200J0D01*
G02Y1617952I1664J1456D01*
G03X151576Y1618084I-150J132D01*
G01Y1618706D01*
G02X151779Y1618908I203J-1D01*
G37*
G36*
G01X186425D02*
X189245D01*
G02X189448Y1618706I1J-202D01*
G01Y1618084D01*
G03X189498Y1617952I200J0D01*
G02Y1615040I-1664J-1456D01*
G03X189448Y1614908I150J-132D01*
G01Y1612966D01*
G03X189498Y1612834I200J0D01*
G02Y1609922I-1664J-1456D01*
G03X189448Y1609790I150J-132D01*
G01Y1609168D01*
G02X189245Y1608966I-203J1D01*
G01X186425D01*
G02X186222Y1609168I-1J202D01*
G01Y1609790D01*
G03X186172Y1609922I-200J0D01*
G02Y1612834I1664J1456D01*
G03X186222Y1612966I-150J132D01*
G01Y1614908D01*
G03X186172Y1615040I-200J0D01*
G02Y1617952I1664J1456D01*
G03X186222Y1618084I-150J132D01*
G01Y1618706D01*
G02X186425Y1618908I203J-1D01*
G37*
G36*
G01X290361D02*
X293181D01*
G02X293384Y1618706I1J-202D01*
G01Y1618084D01*
G03X293434Y1617952I200J0D01*
G02Y1615040I-1664J-1456D01*
G03X293384Y1614908I150J-132D01*
G01Y1612966D01*
G03X293434Y1612834I200J0D01*
G02Y1609922I-1664J-1456D01*
G03X293384Y1609790I150J-132D01*
G01Y1609168D01*
G02X293181Y1608966I-203J1D01*
G01X290361D01*
G02X290158Y1609168I-1J202D01*
G01Y1609790D01*
G03X290108Y1609922I-200J0D01*
G02Y1612834I1664J1456D01*
G03X290158Y1612966I-150J132D01*
G01Y1614908D01*
G03X290108Y1615040I-200J0D01*
G02Y1617952I1664J1456D01*
G03X290158Y1618084I-150J132D01*
G01Y1618706D01*
G02X290361Y1618908I203J-1D01*
G37*
G36*
G01X325007D02*
X327827D01*
G02X328030Y1618706I1J-202D01*
G01Y1618084D01*
G03X328080Y1617952I200J0D01*
G02Y1615040I-1664J-1456D01*
G03X328030Y1614908I150J-132D01*
G01Y1612966D01*
G03X328080Y1612834I200J0D01*
G02Y1609922I-1664J-1456D01*
G03X328030Y1609790I150J-132D01*
G01Y1609168D01*
G02X327827Y1608966I-203J1D01*
G01X325007D01*
G02X324804Y1609168I-1J202D01*
G01Y1609790D01*
G03X324754Y1609922I-200J0D01*
G02Y1612834I1664J1456D01*
G03X324804Y1612966I-150J132D01*
G01Y1614908D01*
G03X324754Y1615040I-200J0D01*
G02Y1617952I1664J1456D01*
G03X324804Y1618084I-150J132D01*
G01Y1618706D01*
G02X325007Y1618908I203J-1D01*
G37*
G36*
G01X359653D02*
X362473D01*
G02X362676Y1618706I1J-202D01*
G01Y1618084D01*
G03X362726Y1617952I200J0D01*
G02Y1615040I-1664J-1456D01*
G03X362676Y1614908I150J-132D01*
G01Y1612966D01*
G03X362726Y1612834I200J0D01*
G02Y1609922I-1664J-1456D01*
G03X362676Y1609790I150J-132D01*
G01Y1609168D01*
G02X362473Y1608966I-203J1D01*
G01X359653D01*
G02X359450Y1609168I-1J202D01*
G01Y1609790D01*
G03X359400Y1609922I-200J0D01*
G02Y1612834I1664J1456D01*
G03X359450Y1612966I-150J132D01*
G01Y1614908D01*
G03X359400Y1615040I-200J0D01*
G02Y1617952I1664J1456D01*
G03X359450Y1618084I-150J132D01*
G01Y1618706D01*
G02X359653Y1618908I203J-1D01*
G37*
G36*
G01X515559D02*
X518379D01*
G02X518582Y1618706I1J-202D01*
G01Y1618084D01*
G03X518632Y1617952I200J0D01*
G02Y1615040I-1664J-1456D01*
G03X518582Y1614908I150J-132D01*
G01Y1612966D01*
G03X518632Y1612834I200J0D01*
G02Y1609922I-1664J-1456D01*
G03X518582Y1609790I150J-132D01*
G01Y1609168D01*
G02X518379Y1608966I-203J1D01*
G01X515559D01*
G02X515356Y1609168I-1J202D01*
G01Y1609790D01*
G03X515306Y1609922I-200J0D01*
G02Y1612834I1664J1456D01*
G03X515356Y1612966I-150J132D01*
G01Y1614908D01*
G03X515306Y1615040I-200J0D01*
G02Y1617952I1664J1456D01*
G03X515356Y1618084I-150J132D01*
G01Y1618706D01*
G02X515559Y1618908I203J-1D01*
G37*
G36*
G01X654141D02*
X656961D01*
G02X657164Y1618706I1J-202D01*
G01Y1618084D01*
G03X657214Y1617952I200J0D01*
G02Y1615040I-1664J-1456D01*
G03X657164Y1614908I150J-132D01*
G01Y1612966D01*
G03X657214Y1612834I200J0D01*
G02Y1609922I-1664J-1456D01*
G03X657164Y1609790I150J-132D01*
G01Y1609168D01*
G02X656961Y1608966I-203J1D01*
G01X654141D01*
G02X653938Y1609168I-1J202D01*
G01Y1609790D01*
G03X653888Y1609922I-200J0D01*
G02Y1612834I1664J1456D01*
G03X653938Y1612966I-150J132D01*
G01Y1614908D01*
G03X653888Y1615040I-200J0D01*
G02Y1617952I1664J1456D01*
G03X653938Y1618084I-150J132D01*
G01Y1618706D01*
G02X654141Y1618908I203J-1D01*
G37*
G36*
G01X688787D02*
X691607D01*
G02X691810Y1618706I1J-202D01*
G01Y1618084D01*
G03X691860Y1617952I200J0D01*
G02Y1615040I-1664J-1456D01*
G03X691810Y1614908I150J-132D01*
G01Y1612966D01*
G03X691860Y1612834I200J0D01*
G02Y1609922I-1664J-1456D01*
G03X691810Y1609790I150J-132D01*
G01Y1609168D01*
G02X691607Y1608966I-203J1D01*
G01X688787D01*
G02X688584Y1609168I-1J202D01*
G01Y1609790D01*
G03X688534Y1609922I-200J0D01*
G02Y1612834I1664J1456D01*
G03X688584Y1612966I-150J132D01*
G01Y1614908D01*
G03X688534Y1615040I-200J0D01*
G02Y1617952I1664J1456D01*
G03X688584Y1618084I-150J132D01*
G01Y1618706D01*
G02X688787Y1618908I203J-1D01*
G37*
G36*
G01X1139101D02*
X1141921D01*
G02X1142124Y1618706I1J-202D01*
G01Y1618084D01*
G03X1142174Y1617952I200J0D01*
G02Y1615040I-1664J-1456D01*
G03X1142124Y1614908I150J-132D01*
G01Y1612966D01*
G03X1142174Y1612834I200J0D01*
G02Y1609922I-1664J-1456D01*
G03X1142124Y1609790I150J-132D01*
G01Y1609168D01*
G02X1141921Y1608966I-203J1D01*
G01X1139101D01*
G02X1138898Y1609168I-1J202D01*
G01Y1609790D01*
G03X1138848Y1609922I-200J0D01*
G02Y1612834I1664J1456D01*
G03X1138898Y1612966I-150J132D01*
G01Y1614908D01*
G03X1138848Y1615040I-200J0D01*
G02Y1617952I1664J1456D01*
G03X1138898Y1618084I-150J132D01*
G01Y1618706D01*
G02X1139101Y1618908I203J-1D01*
G37*
G36*
G01X1173747D02*
X1176567D01*
G02X1176770Y1618706I1J-202D01*
G01Y1618084D01*
G03X1176820Y1617952I200J0D01*
G02Y1615040I-1664J-1456D01*
G03X1176770Y1614908I150J-132D01*
G01Y1612966D01*
G03X1176820Y1612834I200J0D01*
G02Y1609922I-1664J-1456D01*
G03X1176770Y1609790I150J-132D01*
G01Y1609168D01*
G02X1176567Y1608966I-203J1D01*
G01X1173747D01*
G02X1173544Y1609168I-1J202D01*
G01Y1609790D01*
G03X1173494Y1609922I-200J0D01*
G02Y1612834I1664J1456D01*
G03X1173544Y1612966I-150J132D01*
G01Y1614908D01*
G03X1173494Y1615040I-200J0D01*
G02Y1617952I1664J1456D01*
G03X1173544Y1618084I-150J132D01*
G01Y1618706D01*
G02X1173747Y1618908I203J-1D01*
G37*
G36*
G01X1329653D02*
X1332473D01*
G02X1332676Y1618706I1J-202D01*
G01Y1618084D01*
G03X1332726Y1617952I200J0D01*
G02Y1615040I-1664J-1456D01*
G03X1332676Y1614908I150J-132D01*
G01Y1612966D01*
G03X1332726Y1612834I200J0D01*
G02Y1609922I-1664J-1456D01*
G03X1332676Y1609790I150J-132D01*
G01Y1609168D01*
G02X1332473Y1608966I-203J1D01*
G01X1329653D01*
G02X1329450Y1609168I-1J202D01*
G01Y1609790D01*
G03X1329400Y1609922I-200J0D01*
G02Y1612834I1664J1456D01*
G03X1329450Y1612966I-150J132D01*
G01Y1614908D01*
G03X1329400Y1615040I-200J0D01*
G02Y1617952I1664J1456D01*
G03X1329450Y1618084I-150J132D01*
G01Y1618706D01*
G02X1329653Y1618908I203J-1D01*
G37*
G36*
G01X1364299D02*
X1367119D01*
G02X1367322Y1618706I1J-202D01*
G01Y1618084D01*
G03X1367372Y1617952I200J0D01*
G02Y1615040I-1664J-1456D01*
G03X1367322Y1614908I150J-132D01*
G01Y1612966D01*
G03X1367372Y1612834I200J0D01*
G02Y1609922I-1664J-1456D01*
G03X1367322Y1609790I150J-132D01*
G01Y1609168D01*
G02X1367119Y1608966I-203J1D01*
G01X1364299D01*
G02X1364096Y1609168I-1J202D01*
G01Y1609790D01*
G03X1364046Y1609922I-200J0D01*
G02Y1612834I1664J1456D01*
G03X1364096Y1612966I-150J132D01*
G01Y1614908D01*
G03X1364046Y1615040I-200J0D01*
G02Y1617952I1664J1456D01*
G03X1364096Y1618084I-150J132D01*
G01Y1618706D01*
G02X1364299Y1618908I203J-1D01*
G37*
G36*
G01X1676109D02*
X1678929D01*
G02X1679132Y1618706I1J-202D01*
G01Y1618084D01*
G03X1679182Y1617952I200J0D01*
G02Y1615040I-1664J-1456D01*
G03X1679132Y1614908I150J-132D01*
G01Y1612966D01*
G03X1679182Y1612834I200J0D01*
G02Y1609922I-1664J-1456D01*
G03X1679132Y1609790I150J-132D01*
G01Y1609168D01*
G02X1678929Y1608966I-203J1D01*
G01X1676109D01*
G02X1675906Y1609168I-1J202D01*
G01Y1609790D01*
G03X1675856Y1609922I-200J0D01*
G02Y1612834I1664J1456D01*
G03X1675906Y1612966I-150J132D01*
G01Y1614908D01*
G03X1675856Y1615040I-200J0D01*
G02Y1617952I1664J1456D01*
G03X1675906Y1618084I-150J132D01*
G01Y1618706D01*
G02X1676109Y1618908I203J-1D01*
G37*
G36*
G01X1710755D02*
X1713575D01*
G02X1713778Y1618706I1J-202D01*
G01Y1618084D01*
G03X1713828Y1617952I200J0D01*
G02Y1615040I-1664J-1456D01*
G03X1713778Y1614908I150J-132D01*
G01Y1612966D01*
G03X1713828Y1612834I200J0D01*
G02Y1609922I-1664J-1456D01*
G03X1713778Y1609790I150J-132D01*
G01Y1609168D01*
G02X1713575Y1608966I-203J1D01*
G01X1710755D01*
G02X1710552Y1609168I-1J202D01*
G01Y1609790D01*
G03X1710502Y1609922I-200J0D01*
G02Y1612834I1664J1456D01*
G03X1710552Y1612966I-150J132D01*
G01Y1614908D01*
G03X1710502Y1615040I-200J0D01*
G02Y1617952I1664J1456D01*
G03X1710552Y1618084I-150J132D01*
G01Y1618706D01*
G02X1710755Y1618908I203J-1D01*
G37*
G36*
G01X267902Y488314D02*
Y492276D01*
G02X268105Y492478I203J-1D01*
G01X272756D01*
G02X272958Y492276I0J-202D01*
G01Y488314D01*
G02X272755Y488112I-203J1D01*
G01X268104D01*
G02X267902Y488314I0J202D01*
G37*
G36*
G01Y481228D02*
Y485190D01*
G02X268105Y485392I203J-1D01*
G01X272756D01*
G02X272958Y485190I0J-202D01*
G01Y481228D01*
G02X272755Y481026I-203J1D01*
G01X268104D01*
G02X267902Y481228I0J202D01*
G37*
G36*
G01X196728Y469102D02*
Y473064D01*
G02X196930Y473266I202J0D01*
G01X201580D01*
G02X201782Y473064I0J-202D01*
G01Y469102D01*
G02X201580Y468900I-202J0D01*
G01X196930D01*
G02X196728Y469102I0J202D01*
G37*
G36*
G01X196930Y480354D02*
X201580D01*
G02X201782Y480151I-1J-203D01*
G01Y476188D01*
G02X201580Y475986I-202J0D01*
G01X196930D01*
G02X196728Y476189I1J203D01*
G01Y480152D01*
G02X196930Y480354I202J0D01*
G37*
G36*
G01X153198Y480754D02*
X156098D01*
G02X156302Y480550I0J-204D01*
G01Y479649D01*
G02X156301Y479633I-200J4D01*
G01X156300Y479623D01*
Y479589D01*
X156278Y479555D01*
X156273Y479547D01*
G02X156269Y479539I-180J85D01*
G01X155459Y478305D01*
G03Y478085I167J-110D01*
G01X156269Y476846D01*
G02X156274Y476838I-167J-110D01*
G01X156277Y476833D01*
X156300Y476796D01*
Y476762D01*
X156301Y476752D01*
G02X156302Y476736I-199J-20D01*
G01Y475840D01*
G02X156098Y475636I-204J0D01*
G01X153198D01*
G02X152994Y475840I0J204D01*
G01Y476738D01*
G02X152995Y476754I200J-4D01*
G01X152996Y476764D01*
Y476796D01*
X153012Y476822D01*
X153016Y476829D01*
X153017Y476831D01*
G02X153026Y476846I176J-95D01*
G01X153837Y478089D01*
G03X153862Y478253I-167J109D01*
G01X153853Y478285D01*
X153027Y479544D01*
G02X153023Y479552I176J93D01*
G01X153018Y479560D01*
X152996Y479594D01*
Y479628D01*
X152995Y479638D01*
G02X152994Y479654I199J20D01*
G01Y480550D01*
G02X153198Y480754I204J0D01*
G37*
G36*
G01X610284D02*
X613184D01*
G02X613388Y480550I0J-204D01*
G01Y479649D01*
G02X613387Y479633I-200J4D01*
G01X613386Y479623D01*
Y479589D01*
X613364Y479555D01*
X613359Y479547D01*
G02X613355Y479539I-180J85D01*
G01X612545Y478305D01*
G03Y478085I167J-110D01*
G01X613355Y476846D01*
G02X613360Y476838I-167J-110D01*
G01X613363Y476833D01*
X613386Y476796D01*
Y476762D01*
X613387Y476752D01*
G02X613388Y476736I-199J-20D01*
G01Y475840D01*
G02X613184Y475636I-204J0D01*
G01X610284D01*
G02X610080Y475840I0J204D01*
G01Y476738D01*
G02X610081Y476754I200J-4D01*
G01X610082Y476764D01*
Y476796D01*
X610098Y476822D01*
X610102Y476829D01*
X610103Y476831D01*
G02X610112Y476846I176J-95D01*
G01X610891Y478039D01*
G03X610923Y478148I-168J109D01*
G01Y478249D01*
G03X610890Y478359I-200J0D01*
G01X610113Y479544D01*
G02X610109Y479552I176J93D01*
G01X610104Y479560D01*
X610082Y479594D01*
Y479628D01*
X610081Y479638D01*
G02X610080Y479654I199J20D01*
G01Y480550D01*
G02X610284Y480754I204J0D01*
G37*
G36*
G01X724988Y481228D02*
Y485190D01*
G02X725191Y485392I203J-1D01*
G01X729842D01*
G02X730044Y485190I0J-202D01*
G01Y481228D01*
G02X729841Y481026I-203J1D01*
G01X725190D01*
G02X724988Y481228I0J202D01*
G37*
G36*
G01Y488314D02*
Y492276D01*
G02X725191Y492478I203J-1D01*
G01X729842D01*
G02X730044Y492276I0J-202D01*
G01Y488314D01*
G02X729841Y488112I-203J1D01*
G01X725190D01*
G02X724988Y488314I0J202D01*
G37*
G36*
G01X653814Y469102D02*
Y473064D01*
G02X654016Y473266I202J0D01*
G01X658666D01*
G02X658868Y473064I0J-202D01*
G01Y469102D01*
G02X658666Y468900I-202J0D01*
G01X654016D01*
G02X653814Y469102I0J202D01*
G37*
G36*
G01X654016Y480354D02*
X658666D01*
G02X658868Y480151I-1J-203D01*
G01Y476188D01*
G02X658666Y475986I-202J0D01*
G01X654016D01*
G02X653814Y476189I1J203D01*
G01Y480152D01*
G02X654016Y480354I202J0D01*
G37*
G36*
G01X1115956Y473064D02*
Y469102D01*
G02X1115753Y468900I-203J1D01*
G01X1111102D01*
G02X1110900Y469102I0J202D01*
G01Y473064D01*
G02X1111103Y473266I203J-1D01*
G01X1115754D01*
G02X1115956Y473064I0J-202D01*
G37*
G36*
G01X1110900Y476189D02*
Y480151D01*
G02X1111103Y480354I203J0D01*
G01X1115753D01*
G02X1115956Y480151I0J-203D01*
G01Y476189D01*
G02X1115753Y475986I-203J0D01*
G01X1111103D01*
G02X1110900Y476189I0J203D01*
G37*
G36*
G01X1227760Y485734D02*
X1230660D01*
G02X1230864Y485530I0J-204D01*
G01Y484629D01*
G02X1230863Y484613I-200J4D01*
G01X1230862Y484603D01*
Y484569D01*
X1230840Y484535D01*
X1230835Y484527D01*
G02X1230831Y484519I-180J85D01*
G01X1230021Y483285D01*
G03Y483065I167J-110D01*
G01X1230831Y481826D01*
G02X1230836Y481818I-167J-110D01*
G01X1230839Y481813D01*
X1230862Y481776D01*
Y481742D01*
X1230863Y481732D01*
G02X1230864Y481716I-199J-20D01*
G01Y480820D01*
G02X1230660Y480616I-204J0D01*
G01X1227760D01*
G02X1227556Y480820I0J204D01*
G01Y481718D01*
G02X1227557Y481734I200J-4D01*
G01X1227558Y481744D01*
Y481776D01*
X1227574Y481802D01*
X1227578Y481809D01*
X1227579Y481811D01*
G02X1227588Y481826I176J-95D01*
G01X1228367Y483019D01*
G03X1228399Y483128I-168J109D01*
G01Y483229D01*
G03X1228366Y483339I-200J0D01*
G01X1227589Y484524D01*
G02X1227585Y484532I176J93D01*
G01X1227580Y484540D01*
X1227558Y484574D01*
Y484608D01*
X1227557Y484618D01*
G02X1227556Y484634I199J20D01*
G01Y485530D01*
G02X1227760Y485734I204J0D01*
G37*
G36*
G01X1187130Y485190D02*
Y481228D01*
G02X1186928Y481026I-202J0D01*
G01X1182278D01*
G02X1182076Y481228I0J202D01*
G01Y485190D01*
G02X1182278Y485392I202J0D01*
G01X1186928D01*
G02X1187130Y485190I0J-202D01*
G37*
G36*
G01Y492276D02*
Y488314D01*
G02X1186928Y488112I-202J0D01*
G01X1182278D01*
G02X1182076Y488314I0J202D01*
G01Y492276D01*
G02X1182278Y492478I202J0D01*
G01X1186928D01*
G02X1187130Y492276I0J-202D01*
G37*
G36*
G01X1639162Y481228D02*
Y485190D01*
G02X1639365Y485392I203J-1D01*
G01X1644016D01*
G02X1644218Y485190I0J-202D01*
G01Y481228D01*
G02X1644015Y481026I-203J1D01*
G01X1639364D01*
G02X1639162Y481228I0J202D01*
G37*
G36*
G01Y488314D02*
Y492276D01*
G02X1639365Y492478I203J-1D01*
G01X1644016D01*
G02X1644218Y492276I0J-202D01*
G01Y488314D01*
G02X1644015Y488112I-203J1D01*
G01X1639364D01*
G02X1639162Y488314I0J202D01*
G37*
G36*
G01X1567988Y469102D02*
Y473064D01*
G02X1568190Y473266I202J0D01*
G01X1572840D01*
G02X1573042Y473064I0J-202D01*
G01Y469102D01*
G02X1572840Y468900I-202J0D01*
G01X1568190D01*
G02X1567988Y469102I0J202D01*
G37*
G36*
G01X1568190Y480354D02*
X1572840D01*
G02X1573042Y480151I-1J-203D01*
G01Y476188D01*
G02X1572840Y475986I-202J0D01*
G01X1568190D01*
G02X1567988Y476189I1J203D01*
G01Y480152D01*
G02X1568190Y480354I202J0D01*
G37*
G36*
G01X1524458Y480754D02*
X1527358D01*
G02X1527562Y480550I0J-204D01*
G01Y479649D01*
G02X1527561Y479633I-200J4D01*
G01X1527560Y479623D01*
Y479589D01*
X1527538Y479555D01*
X1527533Y479547D01*
G02X1527529Y479539I-180J85D01*
G01X1526719Y478305D01*
G03Y478085I167J-110D01*
G01X1527529Y476846D01*
G02X1527534Y476838I-167J-110D01*
G01X1527537Y476833D01*
X1527560Y476796D01*
Y476762D01*
X1527561Y476752D01*
G02X1527562Y476736I-199J-20D01*
G01Y475840D01*
G02X1527358Y475636I-204J0D01*
G01X1524458D01*
G02X1524254Y475840I0J204D01*
G01Y476738D01*
G02X1524255Y476754I200J-4D01*
G01X1524256Y476764D01*
Y476796D01*
X1524272Y476822D01*
X1524276Y476829D01*
X1524277Y476831D01*
G02X1524286Y476846I176J-95D01*
G01X1525065Y478039D01*
G03X1525097Y478148I-168J109D01*
G01Y478249D01*
G03X1525064Y478359I-200J0D01*
G01X1524287Y479544D01*
G02X1524283Y479552I176J93D01*
G01X1524278Y479560D01*
X1524256Y479594D01*
Y479628D01*
X1524255Y479638D01*
G02X1524254Y479654I199J20D01*
G01Y480550D01*
G02X1524458Y480754I204J0D01*
G37*
G36*
G01X44538Y124892D02*
X39688D01*
G02X39486Y125095I1J203D01*
G01Y129158D01*
G02X39688Y129360I202J0D01*
G01X44538D01*
G02X44740Y129157I-1J-203D01*
G01Y125094D01*
G02X44538Y124892I-202J0D01*
G37*
G36*
G01X44740Y136244D02*
Y132182D01*
G02X44538Y131980I-202J0D01*
G01X39688D01*
G02X39486Y132182I0J202D01*
G01Y136244D01*
G02X39688Y136446I202J0D01*
G01X44538D01*
G02X44740Y136244I0J-202D01*
G37*
G36*
G01X44538Y117806D02*
X39688D01*
G02X39486Y118009I1J203D01*
G01Y122072D01*
G02X39688Y122274I202J0D01*
G01X44538D01*
G02X44740Y122071I-1J-203D01*
G01Y118008D01*
G02X44538Y117806I-202J0D01*
G37*
G36*
G01X44740Y114984D02*
Y110922D01*
G02X44538Y110720I-202J0D01*
G01X39688D01*
G02X39486Y110922I0J202D01*
G01Y114984D01*
G02X39688Y115186I202J0D01*
G01X44538D01*
G02X44740Y114984I0J-202D01*
G37*
G36*
G01X153198Y423602D02*
X156098D01*
G02X156302Y423398I0J-204D01*
G01Y422497D01*
G02X156301Y422481I-200J4D01*
G01X156300Y422471D01*
Y422437D01*
X156278Y422403D01*
X156273Y422395D01*
G02X156269Y422387I-180J85D01*
G01X155459Y421152D01*
G03X155431Y421000I167J-109D01*
G01X155439Y420963D01*
X156269Y419694D01*
G02X156274Y419686I-167J-110D01*
G01X156277Y419681D01*
X156300Y419644D01*
Y419610D01*
X156301Y419600D01*
G02X156302Y419584I-199J-20D01*
G01Y418688D01*
G02X156098Y418484I-204J0D01*
G01X153198D01*
G02X152994Y418688I0J204D01*
G01Y419586D01*
G02X152995Y419602I200J-4D01*
G01X152996Y419612D01*
Y419644D01*
X153012Y419670D01*
X153016Y419677D01*
X153017Y419679D01*
G02X153026Y419694I176J-95D01*
G01X153863Y420973D01*
X153875Y421063D01*
X153861Y421105D01*
X153853Y421132D01*
X153837Y421157D01*
X153027Y422392D01*
G02X153023Y422400I176J93D01*
G01X153018Y422408D01*
X152996Y422442D01*
Y422476D01*
X152995Y422486D01*
G02X152994Y422502I199J20D01*
G01Y423398D01*
G02X153198Y423602I204J0D01*
G37*
G36*
G01X142796Y416542D02*
X145696D01*
G02X145900Y416338I0J-204D01*
G01Y415437D01*
G02X145899Y415421I-200J4D01*
G01X145898Y415411D01*
Y415377D01*
X145876Y415343D01*
X145871Y415335D01*
G02X145867Y415327I-180J85D01*
G01X145057Y414092D01*
G03X145029Y413940I167J-109D01*
G01X145037Y413903D01*
X145867Y412634D01*
G02X145872Y412626I-167J-110D01*
G01X145875Y412621D01*
X145898Y412584D01*
Y412550D01*
X145899Y412540D01*
G02X145900Y412524I-199J-20D01*
G01Y411628D01*
G02X145696Y411424I-204J0D01*
G01X142796D01*
G02X142592Y411628I0J204D01*
G01Y412526D01*
G02X142593Y412542I200J-4D01*
G01X142594Y412552D01*
Y412584D01*
X142610Y412610D01*
X142614Y412617D01*
X142615Y412619D01*
G02X142624Y412634I176J-95D01*
G01X143461Y413913D01*
X143473Y414003D01*
X143459Y414045D01*
X143451Y414072D01*
X143435Y414097D01*
X142625Y415332D01*
G02X142621Y415340I176J93D01*
G01X142616Y415348D01*
X142594Y415382D01*
Y415416D01*
X142593Y415426D01*
G02X142592Y415442I199J20D01*
G01Y416338D01*
G02X142796Y416542I204J0D01*
G37*
G36*
G01X153198Y409428D02*
X156099D01*
G02X156302Y409225I0J-203D01*
G01Y408324D01*
G02X156301Y408308I-200J4D01*
G01X156300Y408298D01*
Y408264D01*
X156278Y408230D01*
X156273Y408222D01*
G02X156269Y408214I-180J85D01*
G01X155459Y406979D01*
G03X155431Y406827I167J-109D01*
G01X155439Y406790D01*
X156269Y405521D01*
G02X156274Y405513I-167J-110D01*
G01X156277Y405508D01*
X156300Y405471D01*
Y405437D01*
X156301Y405427D01*
G02X156302Y405411I-199J-20D01*
G01Y404515D01*
G02X156098Y404312I-204J1D01*
G01X153197D01*
G02X152994Y404515I0J203D01*
G01Y405413D01*
G02X152995Y405429I200J-4D01*
G01X152996Y405439D01*
Y405471D01*
X153012Y405497D01*
X153016Y405504D01*
X153017Y405506D01*
G02X153026Y405521I176J-95D01*
G01X153863Y406800D01*
X153875Y406890D01*
X153861Y406932D01*
X153853Y406959D01*
X153837Y406984D01*
X153027Y408219D01*
G02X153023Y408227I176J93D01*
G01X153018Y408235D01*
X152996Y408269D01*
Y408303D01*
X152995Y408313D01*
G02X152994Y408329I199J20D01*
G01Y409225D01*
G02X153198Y409428I204J-1D01*
G37*
G36*
G01X145196Y402368D02*
X148096D01*
G02X148300Y402164I0J-204D01*
G01Y401263D01*
G02X148299Y401247I-200J4D01*
G01X148298Y401237D01*
Y401203D01*
X148276Y401169D01*
X148271Y401161D01*
G02X148267Y401153I-180J85D01*
G01X147457Y399918D01*
G03X147429Y399766I167J-109D01*
G01X147437Y399729D01*
X148267Y398460D01*
G02X148272Y398452I-167J-110D01*
G01X148275Y398447D01*
X148298Y398410D01*
Y398376D01*
X148299Y398366D01*
G02X148300Y398350I-199J-20D01*
G01Y397454D01*
G02X148096Y397250I-204J0D01*
G01X145196D01*
G02X144992Y397454I0J204D01*
G01Y398352D01*
G02X144993Y398368I200J-4D01*
G01X144994Y398378D01*
Y398410D01*
X145010Y398436D01*
X145014Y398443D01*
X145015Y398445D01*
G02X145024Y398460I176J-95D01*
G01X145861Y399739D01*
X145873Y399829D01*
X145859Y399871D01*
X145851Y399898D01*
X145835Y399923D01*
X145025Y401158D01*
G02X145021Y401166I176J93D01*
G01X145016Y401174D01*
X144994Y401208D01*
Y401242D01*
X144993Y401252D01*
G02X144992Y401268I199J20D01*
G01Y402164D01*
G02X145196Y402368I204J0D01*
G37*
G36*
G01X153198Y395256D02*
X156098D01*
G02X156302Y395052I0J-204D01*
G01Y394151D01*
G02X156301Y394135I-200J4D01*
G01X156300Y394125D01*
Y394091D01*
X156278Y394057D01*
X156273Y394049D01*
G02X156269Y394041I-180J85D01*
G01X155459Y392806D01*
G03X155431Y392654I167J-109D01*
G01X155439Y392617D01*
X156269Y391348D01*
G02X156274Y391340I-167J-110D01*
G01X156277Y391335D01*
X156300Y391298D01*
Y391264D01*
X156301Y391254D01*
G02X156302Y391238I-199J-20D01*
G01Y390342D01*
G02X156098Y390138I-204J0D01*
G01X153198D01*
G02X152994Y390342I0J204D01*
G01Y391240D01*
G02X152995Y391256I200J-4D01*
G01X152996Y391266D01*
Y391298D01*
X153012Y391324D01*
X153016Y391331D01*
X153017Y391333D01*
G02X153026Y391348I176J-95D01*
G01X153863Y392627D01*
X153875Y392717D01*
X153861Y392759D01*
X153853Y392786D01*
X153837Y392811D01*
X153027Y394046D01*
G02X153023Y394054I176J93D01*
G01X153018Y394062D01*
X152996Y394096D01*
Y394130D01*
X152995Y394140D01*
G02X152994Y394156I199J20D01*
G01Y395052D01*
G02X153198Y395256I204J0D01*
G37*
G36*
G01X147102Y136244D02*
Y132182D01*
G02X146900Y131980I-202J0D01*
G01X142050D01*
G02X141848Y132182I0J202D01*
G01Y136244D01*
G02X142050Y136446I202J0D01*
G01X146900D01*
G02X147102Y136244I0J-202D01*
G37*
G36*
G01X146900Y124892D02*
X142050D01*
G02X141848Y125095I1J203D01*
G01Y129158D01*
G02X142050Y129360I202J0D01*
G01X146900D01*
G02X147102Y129157I-1J-203D01*
G01Y125094D01*
G02X146900Y124892I-202J0D01*
G37*
G36*
G01Y117806D02*
X142050D01*
G02X141848Y118009I1J203D01*
G01Y122072D01*
G02X142050Y122274I202J0D01*
G01X146900D01*
G02X147102Y122071I-1J-203D01*
G01Y118008D01*
G02X146900Y117806I-202J0D01*
G37*
G36*
G01X147102Y114984D02*
Y110922D01*
G02X146900Y110720I-202J0D01*
G01X142050D01*
G02X141848Y110922I0J202D01*
G01Y114984D01*
G02X142050Y115186I202J0D01*
G01X146900D01*
G02X147102Y114984I0J-202D01*
G37*
G36*
G01X142796Y444888D02*
X145696D01*
G02X145900Y444684I0J-204D01*
G01Y443783D01*
G02X145899Y443767I-200J4D01*
G01X145898Y443757D01*
Y443723D01*
X145876Y443689D01*
X145871Y443681D01*
G02X145867Y443673I-180J85D01*
G01X145057Y442439D01*
G03Y442219I167J-110D01*
G01X145867Y440980D01*
G02X145872Y440972I-167J-110D01*
G01X145875Y440967D01*
X145898Y440930D01*
Y440896D01*
X145899Y440886D01*
G02X145900Y440870I-199J-20D01*
G01Y439974D01*
G02X145696Y439770I-204J0D01*
G01X142796D01*
G02X142592Y439974I0J204D01*
G01Y440872D01*
G02X142593Y440888I200J-4D01*
G01X142594Y440898D01*
Y440930D01*
X142610Y440956D01*
X142614Y440963D01*
X142615Y440965D01*
G02X142624Y440980I176J-95D01*
G01X143435Y442223D01*
G03X143460Y442387I-167J109D01*
G01X143451Y442419D01*
X142625Y443678D01*
G02X142621Y443686I176J93D01*
G01X142616Y443694D01*
X142594Y443728D01*
Y443762D01*
X142593Y443772D01*
G02X142592Y443788I199J20D01*
G01Y444684D01*
G02X142796Y444888I204J0D01*
G37*
G36*
G01Y430714D02*
X145697D01*
G02X145900Y430511I0J-203D01*
G01Y429610D01*
G02X145899Y429594I-200J4D01*
G01X145898Y429584D01*
Y429550D01*
X145876Y429516D01*
X145871Y429508D01*
G02X145867Y429500I-180J85D01*
G01X145057Y428265D01*
G03X145029Y428113I167J-109D01*
G01X145037Y428076D01*
X145867Y426807D01*
G02X145872Y426799I-167J-110D01*
G01X145875Y426794D01*
X145898Y426757D01*
Y426723D01*
X145899Y426713D01*
G02X145900Y426697I-199J-20D01*
G01Y425801D01*
G02X145696Y425598I-204J1D01*
G01X142795D01*
G02X142592Y425801I0J203D01*
G01Y426699D01*
G02X142593Y426715I200J-4D01*
G01X142594Y426725D01*
Y426757D01*
X142610Y426783D01*
X142614Y426790D01*
X142615Y426792D01*
G02X142624Y426807I176J-95D01*
G01X143461Y428086D01*
X143473Y428176D01*
X143459Y428218D01*
X143451Y428245D01*
X143435Y428270D01*
X142625Y429505D01*
G02X142621Y429513I176J93D01*
G01X142616Y429521D01*
X142594Y429555D01*
Y429589D01*
X142593Y429599D01*
G02X142592Y429615I199J20D01*
G01Y430511D01*
G02X142796Y430714I204J-1D01*
G37*
G36*
G01X153198Y437776D02*
X156098D01*
G02X156302Y437572I0J-204D01*
G01Y436671D01*
G02X156301Y436655I-200J4D01*
G01X156300Y436645D01*
Y436611D01*
X156278Y436577D01*
X156273Y436569D01*
G02X156269Y436561I-180J85D01*
G01X155459Y435327D01*
G03Y435107I167J-110D01*
G01X156269Y433868D01*
G02X156274Y433860I-167J-110D01*
G01X156277Y433855D01*
X156300Y433818D01*
Y433784D01*
X156301Y433774D01*
G02X156302Y433758I-199J-20D01*
G01Y432862D01*
G02X156098Y432658I-204J0D01*
G01X153198D01*
G02X152994Y432862I0J204D01*
G01Y433760D01*
G02X152995Y433776I200J-4D01*
G01X152996Y433786D01*
Y433818D01*
X153012Y433844D01*
X153016Y433851D01*
X153017Y433853D01*
G02X153026Y433868I176J-95D01*
G01X153837Y435111D01*
G03X153862Y435275I-167J109D01*
G01X153853Y435307D01*
X153027Y436566D01*
G02X153023Y436574I176J93D01*
G01X153018Y436582D01*
X152996Y436616D01*
Y436650D01*
X152995Y436660D01*
G02X152994Y436676I199J20D01*
G01Y437572D01*
G02X153198Y437776I204J0D01*
G37*
G36*
G01X196728Y390716D02*
Y394678D01*
G02X196930Y394880I202J0D01*
G01X201580D01*
G02X201782Y394678I0J-202D01*
G01Y390716D01*
G02X201580Y390514I-202J0D01*
G01X196930D01*
G02X196728Y390716I0J202D01*
G37*
G36*
G01X196930Y401968D02*
X201580D01*
G02X201782Y401765I-1J-203D01*
G01Y397802D01*
G02X201580Y397600I-202J0D01*
G01X196930D01*
G02X196728Y397803I1J203D01*
G01Y401766D01*
G02X196930Y401968I202J0D01*
G37*
G36*
G01X196728Y440322D02*
Y444284D01*
G02X196930Y444486I202J0D01*
G01X201580D01*
G02X201782Y444284I0J-202D01*
G01Y440322D01*
G02X201580Y440120I-202J0D01*
G01X196930D01*
G02X196728Y440322I0J202D01*
G37*
G36*
G01Y433236D02*
Y437198D01*
G02X196930Y437400I202J0D01*
G01X201580D01*
G02X201782Y437198I0J-202D01*
G01Y433236D01*
G02X201580Y433034I-202J0D01*
G01X196930D01*
G02X196728Y433236I0J202D01*
G37*
G36*
G01X196930Y430314D02*
X201580D01*
G02X201782Y430111I-1J-203D01*
G01Y426148D01*
G02X201580Y425946I-202J0D01*
G01X196930D01*
G02X196728Y426149I1J203D01*
G01Y430112D01*
G02X196930Y430314I202J0D01*
G37*
G36*
G01X196728Y404890D02*
Y408852D01*
G02X196930Y409054I202J0D01*
G01X201580D01*
G02X201782Y408852I0J-202D01*
G01Y404890D01*
G02X201580Y404688I-202J0D01*
G01X196930D01*
G02X196728Y404890I0J202D01*
G37*
G36*
G01Y411976D02*
Y415938D01*
G02X196930Y416140I202J0D01*
G01X201580D01*
G02X201782Y415938I0J-202D01*
G01Y411976D01*
G02X201580Y411774I-202J0D01*
G01X196930D01*
G02X196728Y411976I0J202D01*
G37*
G36*
G01Y419062D02*
Y423024D01*
G02X196930Y423226I202J0D01*
G01X201580D01*
G02X201782Y423024I0J-202D01*
G01Y419062D01*
G02X201580Y418860I-202J0D01*
G01X196930D01*
G02X196728Y419062I0J202D01*
G37*
G36*
G01X249464Y136244D02*
Y132182D01*
G02X249262Y131980I-202J0D01*
G01X244412D01*
G02X244210Y132182I0J202D01*
G01Y136244D01*
G02X244412Y136446I202J0D01*
G01X249262D01*
G02X249464Y136244I0J-202D01*
G37*
G36*
G01X249262Y124892D02*
X244412D01*
G02X244210Y125095I1J203D01*
G01Y129158D01*
G02X244412Y129360I202J0D01*
G01X249262D01*
G02X249464Y129157I-1J-203D01*
G01Y125094D01*
G02X249262Y124892I-202J0D01*
G37*
G36*
G01X249464Y114984D02*
Y110922D01*
G02X249262Y110720I-202J0D01*
G01X244412D01*
G02X244210Y110922I0J202D01*
G01Y114984D01*
G02X244412Y115186I202J0D01*
G01X249262D01*
G02X249464Y114984I0J-202D01*
G37*
G36*
G01X249262Y117806D02*
X244412D01*
G02X244210Y118009I1J203D01*
G01Y122072D01*
G02X244412Y122274I202J0D01*
G01X249262D01*
G02X249464Y122071I-1J-203D01*
G01Y118008D01*
G02X249262Y117806I-202J0D01*
G37*
G36*
G01X272958Y478103D02*
Y474141D01*
G02X272755Y473938I-203J0D01*
G01X268105D01*
G02X267902Y474141I0J203D01*
G01Y478103D01*
G02X268105Y478306I203J0D01*
G01X272755D01*
G02X272958Y478103I0J-203D01*
G37*
G36*
G01X267902Y467054D02*
Y471016D01*
G02X268105Y471218I203J-1D01*
G01X272756D01*
G02X272958Y471016I0J-202D01*
G01Y467054D01*
G02X272755Y466852I-203J1D01*
G01X268104D01*
G02X267902Y467054I0J202D01*
G37*
G36*
G01X351826Y136244D02*
Y132182D01*
G02X351624Y131980I-202J0D01*
G01X346774D01*
G02X346572Y132182I0J202D01*
G01Y136244D01*
G02X346774Y136446I202J0D01*
G01X351624D01*
G02X351826Y136244I0J-202D01*
G37*
G36*
G01X351624Y124892D02*
X346774D01*
G02X346572Y125095I1J203D01*
G01Y129158D01*
G02X346774Y129360I202J0D01*
G01X351624D01*
G02X351826Y129157I-1J-203D01*
G01Y125094D01*
G02X351624Y124892I-202J0D01*
G37*
G36*
G01Y117806D02*
X346774D01*
G02X346572Y118009I1J203D01*
G01Y122072D01*
G02X346774Y122274I202J0D01*
G01X351624D01*
G02X351826Y122071I-1J-203D01*
G01Y118008D01*
G02X351624Y117806I-202J0D01*
G37*
G36*
G01X351826Y114984D02*
Y110922D01*
G02X351624Y110720I-202J0D01*
G01X346774D01*
G02X346572Y110922I0J202D01*
G01Y114984D01*
G02X346774Y115186I202J0D01*
G01X351624D01*
G02X351826Y114984I0J-202D01*
G37*
G36*
G01X496572Y132182D02*
Y136244D01*
G02X496775Y136446I203J-1D01*
G01X501626D01*
G02X501828Y136244I0J-202D01*
G01Y132182D01*
G02X501625Y131980I-203J1D01*
G01X496774D01*
G02X496572Y132182I0J202D01*
G37*
G36*
G01X501828Y129157D02*
Y125095D01*
G02X501625Y124892I-203J0D01*
G01X496775D01*
G02X496572Y125095I0J203D01*
G01Y129157D01*
G02X496775Y129360I203J0D01*
G01X501625D01*
G02X501828Y129157I0J-203D01*
G37*
G36*
G01X496572Y110922D02*
Y114984D01*
G02X496775Y115186I203J-1D01*
G01X501626D01*
G02X501828Y114984I0J-202D01*
G01Y110922D01*
G02X501625Y110720I-203J1D01*
G01X496774D01*
G02X496572Y110922I0J202D01*
G37*
G36*
G01X501828Y122071D02*
Y118009D01*
G02X501625Y117806I-203J0D01*
G01X496775D01*
G02X496572Y118009I0J203D01*
G01Y122071D01*
G02X496775Y122274I203J0D01*
G01X501625D01*
G02X501828Y122071I0J-203D01*
G37*
G36*
G01X525686Y129650D02*
X528587D01*
G02X528790Y129447I0J-203D01*
G01Y128546D01*
G02X528789Y128530I-200J4D01*
G01X528788Y128520D01*
Y128486D01*
X528766Y128452D01*
X528761Y128444D01*
G02X528757Y128436I-180J85D01*
G01X527947Y127202D01*
G03Y126982I167J-110D01*
G01X528757Y125743D01*
G02X528762Y125735I-167J-110D01*
G01X528765Y125730D01*
X528788Y125693D01*
Y125659D01*
X528789Y125649D01*
G02X528790Y125633I-199J-20D01*
G01Y124737D01*
G02X528586Y124534I-204J1D01*
G01X525685D01*
G02X525482Y124737I0J203D01*
G01Y125635D01*
G02X525483Y125651I200J-4D01*
G01X525484Y125661D01*
Y125693D01*
X525500Y125719D01*
X525504Y125726D01*
X525505Y125728D01*
G02X525514Y125743I176J-95D01*
G01X526293Y126936D01*
G03X526325Y127045I-168J109D01*
G01Y127146D01*
G03X526292Y127256I-200J0D01*
G01X525515Y128441D01*
G02X525511Y128449I176J93D01*
G01X525506Y128457D01*
X525484Y128491D01*
Y128525D01*
X525483Y128535D01*
G02X525482Y128551I199J20D01*
G01Y129447D01*
G02X525686Y129650I204J-1D01*
G37*
G36*
G01Y115478D02*
X528586D01*
G02X528790Y115274I0J-204D01*
G01Y114373D01*
G02X528789Y114357I-200J4D01*
G01X528788Y114347D01*
Y114313D01*
X528766Y114279D01*
X528761Y114271D01*
G02X528757Y114263I-180J85D01*
G01X527947Y113029D01*
G03Y112809I167J-110D01*
G01X528757Y111570D01*
G02X528762Y111562I-167J-110D01*
G01X528765Y111557D01*
X528788Y111520D01*
Y111486D01*
X528789Y111476D01*
G02X528790Y111460I-199J-20D01*
G01Y110564D01*
G02X528586Y110360I-204J0D01*
G01X525686D01*
G02X525482Y110564I0J204D01*
G01Y111462D01*
G02X525483Y111478I200J-4D01*
G01X525484Y111488D01*
Y111520D01*
X525500Y111546D01*
X525504Y111553D01*
X525505Y111555D01*
G02X525514Y111570I176J-95D01*
G01X526293Y112763D01*
G03X526325Y112872I-168J109D01*
G01Y112973D01*
G03X526292Y113083I-200J0D01*
G01X525515Y114268D01*
G02X525511Y114276I176J93D01*
G01X525506Y114284D01*
X525484Y114318D01*
Y114352D01*
X525483Y114362D01*
G02X525482Y114378I199J20D01*
G01Y115274D01*
G02X525686Y115478I204J0D01*
G37*
G36*
G01X598934Y132182D02*
Y136244D01*
G02X599137Y136446I203J-1D01*
G01X603988D01*
G02X604190Y136244I0J-202D01*
G01Y132182D01*
G02X603987Y131980I-203J1D01*
G01X599136D01*
G02X598934Y132182I0J202D01*
G37*
G36*
G01X604190Y129157D02*
Y125095D01*
G02X603987Y124892I-203J0D01*
G01X599137D01*
G02X598934Y125095I0J203D01*
G01Y129157D01*
G02X599137Y129360I203J0D01*
G01X603987D01*
G02X604190Y129157I0J-203D01*
G37*
G36*
G01Y122071D02*
Y118009D01*
G02X603987Y117806I-203J0D01*
G01X599137D01*
G02X598934Y118009I0J203D01*
G01Y122071D01*
G02X599137Y122274I203J0D01*
G01X603987D01*
G02X604190Y122071I0J-203D01*
G37*
G36*
G01X598934Y110922D02*
Y114984D01*
G02X599137Y115186I203J-1D01*
G01X603988D01*
G02X604190Y114984I0J-202D01*
G01Y110922D01*
G02X603987Y110720I-203J1D01*
G01X599136D01*
G02X598934Y110922I0J202D01*
G37*
G36*
G01X599882Y473642D02*
X602782D01*
G02X602986Y473438I0J-204D01*
G01Y472537D01*
G02X602985Y472521I-200J4D01*
G01X602984Y472511D01*
Y472477D01*
X602962Y472443D01*
X602957Y472435D01*
G02X602953Y472427I-180J85D01*
G01X602143Y471193D01*
G03Y470973I167J-110D01*
G01X602953Y469734D01*
G02X602958Y469726I-167J-110D01*
G01X602961Y469721D01*
X602984Y469684D01*
Y469650D01*
X602985Y469640D01*
G02X602986Y469624I-199J-20D01*
G01Y468728D01*
G02X602782Y468524I-204J0D01*
G01X599882D01*
G02X599678Y468728I0J204D01*
G01Y469626D01*
G02X599679Y469642I200J-4D01*
G01X599680Y469652D01*
Y469684D01*
X599696Y469710D01*
X599700Y469717D01*
X599701Y469719D01*
G02X599710Y469734I176J-95D01*
G01X600489Y470927D01*
G03X600521Y471036I-168J109D01*
G01Y471137D01*
G03X600488Y471247I-200J0D01*
G01X599711Y472432D01*
G02X599707Y472440I176J93D01*
G01X599702Y472448D01*
X599680Y472482D01*
Y472516D01*
X599679Y472526D01*
G02X599678Y472542I199J20D01*
G01Y473438D01*
G02X599882Y473642I204J0D01*
G37*
G36*
G01X628048Y129650D02*
X630949D01*
G02X631152Y129447I0J-203D01*
G01Y128546D01*
G02X631151Y128530I-200J4D01*
G01X631150Y128520D01*
Y128486D01*
X631128Y128452D01*
X631123Y128444D01*
G02X631119Y128436I-180J85D01*
G01X630309Y127202D01*
G03Y126982I167J-110D01*
G01X631119Y125743D01*
G02X631124Y125735I-167J-110D01*
G01X631127Y125730D01*
X631150Y125693D01*
Y125659D01*
X631151Y125649D01*
G02X631152Y125633I-199J-20D01*
G01Y124737D01*
G02X630948Y124534I-204J1D01*
G01X628047D01*
G02X627844Y124737I0J203D01*
G01Y125635D01*
G02X627845Y125651I200J-4D01*
G01X627846Y125661D01*
Y125693D01*
X627862Y125719D01*
X627866Y125726D01*
X627867Y125728D01*
G02X627876Y125743I176J-95D01*
G01X628655Y126936D01*
G03X628687Y127045I-168J109D01*
G01Y127146D01*
G03X628654Y127256I-200J0D01*
G01X627877Y128441D01*
G02X627873Y128449I176J93D01*
G01X627868Y128457D01*
X627846Y128491D01*
Y128525D01*
X627845Y128535D01*
G02X627844Y128551I199J20D01*
G01Y129447D01*
G02X628048Y129650I204J-1D01*
G37*
G36*
G01Y115478D02*
X630948D01*
G02X631152Y115274I0J-204D01*
G01Y114373D01*
G02X631151Y114357I-200J4D01*
G01X631150Y114347D01*
Y114313D01*
X631128Y114279D01*
X631123Y114271D01*
G02X631119Y114263I-180J85D01*
G01X630309Y113029D01*
G03Y112809I167J-110D01*
G01X631119Y111570D01*
G02X631124Y111562I-167J-110D01*
G01X631127Y111557D01*
X631150Y111520D01*
Y111486D01*
X631151Y111476D01*
G02X631152Y111460I-199J-20D01*
G01Y110564D01*
G02X630948Y110360I-204J0D01*
G01X628048D01*
G02X627844Y110564I0J204D01*
G01Y111462D01*
G02X627845Y111478I200J-4D01*
G01X627846Y111488D01*
Y111520D01*
X627862Y111546D01*
X627866Y111553D01*
X627867Y111555D01*
G02X627876Y111570I176J-95D01*
G01X628655Y112763D01*
G03X628687Y112872I-168J109D01*
G01Y112973D01*
G03X628654Y113083I-200J0D01*
G01X627877Y114268D01*
G02X627873Y114276I176J93D01*
G01X627868Y114284D01*
X627846Y114318D01*
Y114352D01*
X627845Y114362D01*
G02X627844Y114378I199J20D01*
G01Y115274D01*
G02X628048Y115478I204J0D01*
G37*
G36*
G01X610284Y437776D02*
X613184D01*
G02X613388Y437572I0J-204D01*
G01Y436671D01*
G02X613387Y436655I-200J4D01*
G01X613386Y436645D01*
Y436611D01*
X613364Y436577D01*
X613359Y436569D01*
G02X613355Y436561I-180J85D01*
G01X612545Y435327D01*
G03Y435107I167J-110D01*
G01X613355Y433868D01*
G02X613360Y433860I-167J-110D01*
G01X613363Y433855D01*
X613386Y433818D01*
Y433784D01*
X613387Y433774D01*
G02X613388Y433758I-199J-20D01*
G01Y432862D01*
G02X613184Y432658I-204J0D01*
G01X610284D01*
G02X610080Y432862I0J204D01*
G01Y433760D01*
G02X610081Y433776I200J-4D01*
G01X610082Y433786D01*
Y433818D01*
X610098Y433844D01*
X610102Y433851D01*
X610103Y433853D01*
G02X610112Y433868I176J-95D01*
G01X610891Y435061D01*
G03X610923Y435170I-168J109D01*
G01Y435271D01*
G03X610890Y435381I-200J0D01*
G01X610113Y436566D01*
G02X610109Y436574I176J93D01*
G01X610104Y436582D01*
X610082Y436616D01*
Y436650D01*
X610081Y436660D01*
G02X610080Y436676I199J20D01*
G01Y437572D01*
G02X610284Y437776I204J0D01*
G37*
G36*
G01Y423602D02*
X613184D01*
G02X613388Y423398I0J-204D01*
G01Y422497D01*
G02X613387Y422481I-200J4D01*
G01X613386Y422471D01*
Y422437D01*
X613364Y422403D01*
X613359Y422395D01*
G02X613355Y422387I-180J85D01*
G01X612545Y421153D01*
G03Y420933I167J-110D01*
G01X613355Y419694D01*
G02X613360Y419686I-167J-110D01*
G01X613363Y419681D01*
X613386Y419644D01*
Y419610D01*
X613387Y419600D01*
G02X613388Y419584I-199J-20D01*
G01Y418688D01*
G02X613184Y418484I-204J0D01*
G01X610284D01*
G02X610080Y418688I0J204D01*
G01Y419586D01*
G02X610081Y419602I200J-4D01*
G01X610082Y419612D01*
Y419644D01*
X610098Y419670D01*
X610102Y419677D01*
X610103Y419679D01*
G02X610112Y419694I176J-95D01*
G01X610891Y420887D01*
G03X610923Y420996I-168J109D01*
G01Y421097D01*
G03X610890Y421207I-200J0D01*
G01X610113Y422392D01*
G02X610109Y422400I176J93D01*
G01X610104Y422408D01*
X610082Y422442D01*
Y422476D01*
X610081Y422486D01*
G02X610080Y422502I199J20D01*
G01Y423398D01*
G02X610284Y423602I204J0D01*
G37*
G36*
G01X599882Y416542D02*
X602782D01*
G02X602986Y416338I0J-204D01*
G01Y415437D01*
G02X602985Y415421I-200J4D01*
G01X602984Y415411D01*
Y415377D01*
X602962Y415343D01*
X602957Y415335D01*
G02X602953Y415327I-180J85D01*
G01X602143Y414093D01*
G03Y413873I167J-110D01*
G01X602953Y412634D01*
G02X602958Y412626I-167J-110D01*
G01X602961Y412621D01*
X602984Y412584D01*
Y412550D01*
X602985Y412540D01*
G02X602986Y412524I-199J-20D01*
G01Y411628D01*
G02X602782Y411424I-204J0D01*
G01X599882D01*
G02X599678Y411628I0J204D01*
G01Y412526D01*
G02X599679Y412542I200J-4D01*
G01X599680Y412552D01*
Y412584D01*
X599696Y412610D01*
X599700Y412617D01*
X599701Y412619D01*
G02X599710Y412634I176J-95D01*
G01X600489Y413827D01*
G03X600521Y413936I-168J109D01*
G01Y414037D01*
G03X600488Y414147I-200J0D01*
G01X599711Y415332D01*
G02X599707Y415340I176J93D01*
G01X599702Y415348D01*
X599680Y415382D01*
Y415416D01*
X599679Y415426D01*
G02X599678Y415442I199J20D01*
G01Y416338D01*
G02X599882Y416542I204J0D01*
G37*
G36*
G01X602282Y402368D02*
X605182D01*
G02X605386Y402164I0J-204D01*
G01Y401263D01*
G02X605385Y401247I-200J4D01*
G01X605384Y401237D01*
Y401203D01*
X605362Y401169D01*
X605357Y401161D01*
G02X605353Y401153I-180J85D01*
G01X604543Y399919D01*
G03Y399699I167J-110D01*
G01X605353Y398460D01*
G02X605358Y398452I-167J-110D01*
G01X605361Y398447D01*
X605384Y398410D01*
Y398376D01*
X605385Y398366D01*
G02X605386Y398350I-199J-20D01*
G01Y397454D01*
G02X605182Y397250I-204J0D01*
G01X602282D01*
G02X602078Y397454I0J204D01*
G01Y398352D01*
G02X602079Y398368I200J-4D01*
G01X602080Y398378D01*
Y398410D01*
X602096Y398436D01*
X602100Y398443D01*
X602101Y398445D01*
G02X602110Y398460I176J-95D01*
G01X602889Y399653D01*
G03X602921Y399762I-168J109D01*
G01Y399863D01*
G03X602888Y399973I-200J0D01*
G01X602111Y401158D01*
G02X602107Y401166I176J93D01*
G01X602102Y401174D01*
X602080Y401208D01*
Y401242D01*
X602079Y401252D01*
G02X602078Y401268I199J20D01*
G01Y402164D01*
G02X602282Y402368I204J0D01*
G37*
G36*
G01X610284Y409428D02*
X613185D01*
G02X613388Y409225I0J-203D01*
G01Y408324D01*
G02X613387Y408308I-200J4D01*
G01X613386Y408298D01*
Y408264D01*
X613364Y408230D01*
X613359Y408222D01*
G02X613355Y408214I-180J85D01*
G01X612545Y406980D01*
G03Y406760I167J-110D01*
G01X613355Y405521D01*
G02X613360Y405513I-167J-110D01*
G01X613363Y405508D01*
X613386Y405471D01*
Y405437D01*
X613387Y405427D01*
G02X613388Y405411I-199J-20D01*
G01Y404515D01*
G02X613184Y404312I-204J1D01*
G01X610283D01*
G02X610080Y404515I0J203D01*
G01Y405413D01*
G02X610081Y405429I200J-4D01*
G01X610082Y405439D01*
Y405471D01*
X610098Y405497D01*
X610102Y405504D01*
X610103Y405506D01*
G02X610112Y405521I176J-95D01*
G01X610891Y406714D01*
G03X610923Y406823I-168J109D01*
G01Y406924D01*
G03X610890Y407034I-200J0D01*
G01X610113Y408219D01*
G02X610109Y408227I176J93D01*
G01X610104Y408235D01*
X610082Y408269D01*
Y408303D01*
X610081Y408313D01*
G02X610080Y408329I199J20D01*
G01Y409225D01*
G02X610284Y409428I204J-1D01*
G37*
G36*
G01Y395256D02*
X613184D01*
G02X613388Y395052I0J-204D01*
G01Y394151D01*
G02X613387Y394135I-200J4D01*
G01X613386Y394125D01*
Y394091D01*
X613364Y394057D01*
X613359Y394049D01*
G02X613355Y394041I-180J85D01*
G01X612545Y392807D01*
G03Y392587I167J-110D01*
G01X613355Y391348D01*
G02X613360Y391340I-167J-110D01*
G01X613363Y391335D01*
X613386Y391298D01*
Y391264D01*
X613387Y391254D01*
G02X613388Y391238I-199J-20D01*
G01Y390342D01*
G02X613184Y390138I-204J0D01*
G01X610284D01*
G02X610080Y390342I0J204D01*
G01Y391240D01*
G02X610081Y391256I200J-4D01*
G01X610082Y391266D01*
Y391298D01*
X610098Y391324D01*
X610102Y391331D01*
X610103Y391333D01*
G02X610112Y391348I176J-95D01*
G01X610891Y392541D01*
G03X610923Y392650I-168J109D01*
G01Y392751D01*
G03X610890Y392861I-200J0D01*
G01X610113Y394046D01*
G02X610109Y394054I176J93D01*
G01X610104Y394062D01*
X610082Y394096D01*
Y394130D01*
X610081Y394140D01*
G02X610080Y394156I199J20D01*
G01Y395052D01*
G02X610284Y395256I204J0D01*
G37*
G36*
G01X638450Y136764D02*
X641350D01*
G02X641554Y136560I0J-204D01*
G01Y135659D01*
G02X641553Y135643I-200J4D01*
G01X641552Y135633D01*
Y135599D01*
X641530Y135565D01*
X641525Y135557D01*
G02X641521Y135549I-180J85D01*
G01X640711Y134315D01*
G03Y134095I167J-110D01*
G01X641521Y132856D01*
G02X641526Y132848I-167J-110D01*
G01X641529Y132843D01*
X641552Y132806D01*
Y132772D01*
X641553Y132762D01*
G02X641554Y132746I-199J-20D01*
G01Y131850D01*
G02X641350Y131646I-204J0D01*
G01X638450D01*
G02X638246Y131850I0J204D01*
G01Y132748D01*
G02X638247Y132764I200J-4D01*
G01X638248Y132774D01*
Y132806D01*
X638264Y132832D01*
X638268Y132839D01*
X638269Y132841D01*
G02X638278Y132856I176J-95D01*
G01X639057Y134049D01*
G03X639089Y134158I-168J109D01*
G01Y134259D01*
G03X639056Y134369I-200J0D01*
G01X638279Y135554D01*
G02X638275Y135562I176J93D01*
G01X638270Y135570D01*
X638248Y135604D01*
Y135638D01*
X638247Y135648D01*
G02X638246Y135664I199J20D01*
G01Y136560D01*
G02X638450Y136764I204J0D01*
G37*
G36*
G01Y122590D02*
X641350D01*
G02X641554Y122386I0J-204D01*
G01Y121485D01*
G02X641553Y121469I-200J4D01*
G01X641552Y121459D01*
Y121425D01*
X641530Y121391D01*
X641525Y121383D01*
G02X641521Y121375I-180J85D01*
G01X640711Y120141D01*
G03Y119921I167J-110D01*
G01X641521Y118682D01*
G02X641526Y118674I-167J-110D01*
G01X641529Y118669D01*
X641552Y118632D01*
Y118598D01*
X641553Y118588D01*
G02X641554Y118572I-199J-20D01*
G01Y117676D01*
G02X641350Y117472I-204J0D01*
G01X638450D01*
G02X638246Y117676I0J204D01*
G01Y118574D01*
G02X638247Y118590I200J-4D01*
G01X638248Y118600D01*
Y118632D01*
X638264Y118658D01*
X638268Y118665D01*
X638269Y118667D01*
G02X638278Y118682I176J-95D01*
G01X639057Y119875D01*
G03X639089Y119984I-168J109D01*
G01Y120085D01*
G03X639056Y120195I-200J0D01*
G01X638279Y121380D01*
G02X638275Y121388I176J93D01*
G01X638270Y121396D01*
X638248Y121430D01*
Y121464D01*
X638247Y121474D01*
G02X638246Y121490I199J20D01*
G01Y122386D01*
G02X638450Y122590I204J0D01*
G37*
G36*
G01X653814Y433236D02*
Y437198D01*
G02X654016Y437400I202J0D01*
G01X658666D01*
G02X658868Y437198I0J-202D01*
G01Y433236D01*
G02X658666Y433034I-202J0D01*
G01X654016D01*
G02X653814Y433236I0J202D01*
G37*
G36*
G01Y440322D02*
Y444284D01*
G02X654016Y444486I202J0D01*
G01X658666D01*
G02X658868Y444284I0J-202D01*
G01Y440322D01*
G02X658666Y440120I-202J0D01*
G01X654016D01*
G02X653814Y440322I0J202D01*
G37*
G36*
G01X654016Y430314D02*
X658666D01*
G02X658868Y430111I-1J-203D01*
G01Y426148D01*
G02X658666Y425946I-202J0D01*
G01X654016D01*
G02X653814Y426149I1J203D01*
G01Y430112D01*
G02X654016Y430314I202J0D01*
G37*
G36*
G01X653814Y419062D02*
Y423024D01*
G02X654016Y423226I202J0D01*
G01X658666D01*
G02X658868Y423024I0J-202D01*
G01Y419062D01*
G02X658666Y418860I-202J0D01*
G01X654016D01*
G02X653814Y419062I0J202D01*
G37*
G36*
G01Y411976D02*
Y415938D01*
G02X654016Y416140I202J0D01*
G01X658666D01*
G02X658868Y415938I0J-202D01*
G01Y411976D01*
G02X658666Y411774I-202J0D01*
G01X654016D01*
G02X653814Y411976I0J202D01*
G37*
G36*
G01Y404890D02*
Y408852D01*
G02X654016Y409054I202J0D01*
G01X658666D01*
G02X658868Y408852I0J-202D01*
G01Y404890D01*
G02X658666Y404688I-202J0D01*
G01X654016D01*
G02X653814Y404890I0J202D01*
G37*
G36*
G01Y390716D02*
Y394678D01*
G02X654016Y394880I202J0D01*
G01X658666D01*
G02X658868Y394678I0J-202D01*
G01Y390716D01*
G02X658666Y390514I-202J0D01*
G01X654016D01*
G02X653814Y390716I0J202D01*
G37*
G36*
G01X654016Y401968D02*
X658666D01*
G02X658868Y401765I-1J-203D01*
G01Y397802D01*
G02X658666Y397600I-202J0D01*
G01X654016D01*
G02X653814Y397803I1J203D01*
G01Y401766D01*
G02X654016Y401968I202J0D01*
G37*
G36*
G01X701296Y132182D02*
Y136244D01*
G02X701499Y136446I203J-1D01*
G01X706350D01*
G02X706552Y136244I0J-202D01*
G01Y132182D01*
G02X706349Y131980I-203J1D01*
G01X701498D01*
G02X701296Y132182I0J202D01*
G37*
G36*
G01X706552Y129157D02*
Y125095D01*
G02X706349Y124892I-203J0D01*
G01X701499D01*
G02X701296Y125095I0J203D01*
G01Y129157D01*
G02X701499Y129360I203J0D01*
G01X706349D01*
G02X706552Y129157I0J-203D01*
G37*
G36*
G01X701296Y110922D02*
Y114984D01*
G02X701499Y115186I203J-1D01*
G01X706350D01*
G02X706552Y114984I0J-202D01*
G01Y110922D01*
G02X706349Y110720I-203J1D01*
G01X701498D01*
G02X701296Y110922I0J202D01*
G37*
G36*
G01X706552Y122071D02*
Y118009D01*
G02X706349Y117806I-203J0D01*
G01X701499D01*
G02X701296Y118009I0J203D01*
G01Y122071D01*
G02X701499Y122274I203J0D01*
G01X706349D01*
G02X706552Y122071I0J-203D01*
G37*
G36*
G01X730410Y129650D02*
X733311D01*
G02X733514Y129447I0J-203D01*
G01Y128546D01*
G02X733513Y128530I-200J4D01*
G01X733512Y128520D01*
Y128486D01*
X733490Y128452D01*
X733485Y128444D01*
G02X733481Y128436I-180J85D01*
G01X732671Y127202D01*
G03Y126982I167J-110D01*
G01X733481Y125743D01*
G02X733486Y125735I-167J-110D01*
G01X733489Y125730D01*
X733512Y125693D01*
Y125659D01*
X733513Y125649D01*
G02X733514Y125633I-199J-20D01*
G01Y124737D01*
G02X733310Y124534I-204J1D01*
G01X730409D01*
G02X730206Y124737I0J203D01*
G01Y125635D01*
G02X730207Y125651I200J-4D01*
G01X730208Y125661D01*
Y125693D01*
X730224Y125719D01*
X730228Y125726D01*
X730229Y125728D01*
G02X730238Y125743I176J-95D01*
G01X731017Y126936D01*
G03X731049Y127045I-168J109D01*
G01Y127146D01*
G03X731016Y127256I-200J0D01*
G01X730239Y128441D01*
G02X730235Y128449I176J93D01*
G01X730230Y128457D01*
X730208Y128491D01*
Y128525D01*
X730207Y128535D01*
G02X730206Y128551I199J20D01*
G01Y129447D01*
G02X730410Y129650I204J-1D01*
G37*
G36*
G01X740812Y136764D02*
X743712D01*
G02X743916Y136560I0J-204D01*
G01Y135659D01*
G02X743915Y135643I-200J4D01*
G01X743914Y135633D01*
Y135599D01*
X743892Y135565D01*
X743887Y135557D01*
G02X743883Y135549I-180J85D01*
G01X743073Y134315D01*
G03Y134095I167J-110D01*
G01X743883Y132856D01*
G02X743888Y132848I-167J-110D01*
G01X743891Y132843D01*
X743914Y132806D01*
Y132772D01*
X743915Y132762D01*
G02X743916Y132746I-199J-20D01*
G01Y131850D01*
G02X743712Y131646I-204J0D01*
G01X740812D01*
G02X740608Y131850I0J204D01*
G01Y132748D01*
G02X740609Y132764I200J-4D01*
G01X740610Y132774D01*
Y132806D01*
X740626Y132832D01*
X740630Y132839D01*
X740631Y132841D01*
G02X740640Y132856I176J-95D01*
G01X741419Y134049D01*
G03X741451Y134158I-168J109D01*
G01Y134259D01*
G03X741418Y134369I-200J0D01*
G01X740641Y135554D01*
G02X740637Y135562I176J93D01*
G01X740632Y135570D01*
X740610Y135604D01*
Y135638D01*
X740609Y135648D01*
G02X740608Y135664I199J20D01*
G01Y136560D01*
G02X740812Y136764I204J0D01*
G37*
G36*
G01X730410Y115478D02*
X733310D01*
G02X733514Y115274I0J-204D01*
G01Y114373D01*
G02X733513Y114357I-200J4D01*
G01X733512Y114347D01*
Y114313D01*
X733490Y114279D01*
X733485Y114271D01*
G02X733481Y114263I-180J85D01*
G01X732671Y113029D01*
G03Y112809I167J-110D01*
G01X733481Y111570D01*
G02X733486Y111562I-167J-110D01*
G01X733489Y111557D01*
X733512Y111520D01*
Y111486D01*
X733513Y111476D01*
G02X733514Y111460I-199J-20D01*
G01Y110564D01*
G02X733310Y110360I-204J0D01*
G01X730410D01*
G02X730206Y110564I0J204D01*
G01Y111462D01*
G02X730207Y111478I200J-4D01*
G01X730208Y111488D01*
Y111520D01*
X730224Y111546D01*
X730228Y111553D01*
X730229Y111555D01*
G02X730238Y111570I176J-95D01*
G01X731017Y112763D01*
G03X731049Y112872I-168J109D01*
G01Y112973D01*
G03X731016Y113083I-200J0D01*
G01X730239Y114268D01*
G02X730235Y114276I176J93D01*
G01X730230Y114284D01*
X730208Y114318D01*
Y114352D01*
X730207Y114362D01*
G02X730206Y114378I199J20D01*
G01Y115274D01*
G02X730410Y115478I204J0D01*
G37*
G36*
G01X724988Y467054D02*
Y471016D01*
G02X725191Y471218I203J-1D01*
G01X729842D01*
G02X730044Y471016I0J-202D01*
G01Y467054D01*
G02X729841Y466852I-203J1D01*
G01X725190D01*
G02X724988Y467054I0J202D01*
G37*
G36*
G01X730044Y478103D02*
Y474141D01*
G02X729841Y473938I-203J0D01*
G01X725191D01*
G02X724988Y474141I0J203D01*
G01Y478103D01*
G02X725191Y478306I203J0D01*
G01X729841D01*
G02X730044Y478103I0J-203D01*
G37*
G36*
G01X803658Y110922D02*
Y114984D01*
G02X803861Y115186I203J-1D01*
G01X808712D01*
G02X808914Y114984I0J-202D01*
G01Y110922D01*
G02X808711Y110720I-203J1D01*
G01X803860D01*
G02X803658Y110922I0J202D01*
G37*
G36*
G01X808914Y122071D02*
Y118009D01*
G02X808711Y117806I-203J0D01*
G01X803861D01*
G02X803658Y118009I0J203D01*
G01Y122071D01*
G02X803861Y122274I203J0D01*
G01X808711D01*
G02X808914Y122071I0J-203D01*
G37*
G36*
G01X803658Y132182D02*
Y136244D01*
G02X803861Y136446I203J-1D01*
G01X808712D01*
G02X808914Y136244I0J-202D01*
G01Y132182D01*
G02X808711Y131980I-203J1D01*
G01X803860D01*
G02X803658Y132182I0J202D01*
G37*
G36*
G01X808914Y129157D02*
Y125095D01*
G02X808711Y124892I-203J0D01*
G01X803861D01*
G02X803658Y125095I0J203D01*
G01Y129157D01*
G02X803861Y129360I203J0D01*
G01X808711D01*
G02X808914Y129157I0J-203D01*
G37*
G36*
G01X832772Y129650D02*
X835673D01*
G02X835876Y129447I0J-203D01*
G01Y128546D01*
G02X835875Y128530I-200J4D01*
G01X835874Y128520D01*
Y128486D01*
X835852Y128452D01*
X835847Y128444D01*
G02X835843Y128436I-180J85D01*
G01X835033Y127202D01*
G03Y126982I167J-110D01*
G01X835843Y125743D01*
G02X835848Y125735I-167J-110D01*
G01X835851Y125730D01*
X835874Y125693D01*
Y125659D01*
X835875Y125649D01*
G02X835876Y125633I-199J-20D01*
G01Y124737D01*
G02X835672Y124534I-204J1D01*
G01X832771D01*
G02X832568Y124737I0J203D01*
G01Y125635D01*
G02X832569Y125651I200J-4D01*
G01X832570Y125661D01*
Y125693D01*
X832586Y125719D01*
X832590Y125726D01*
X832591Y125728D01*
G02X832600Y125743I176J-95D01*
G01X833379Y126936D01*
G03X833411Y127045I-168J109D01*
G01Y127146D01*
G03X833378Y127256I-200J0D01*
G01X832601Y128441D01*
G02X832597Y128449I176J93D01*
G01X832592Y128457D01*
X832570Y128491D01*
Y128525D01*
X832569Y128535D01*
G02X832568Y128551I199J20D01*
G01Y129447D01*
G02X832772Y129650I204J-1D01*
G37*
G36*
G01X843174Y136764D02*
X846074D01*
G02X846278Y136560I0J-204D01*
G01Y135659D01*
G02X846277Y135643I-200J4D01*
G01X846276Y135633D01*
Y135599D01*
X846254Y135565D01*
X846249Y135557D01*
G02X846245Y135549I-180J85D01*
G01X845435Y134315D01*
G03Y134095I167J-110D01*
G01X846245Y132856D01*
G02X846250Y132848I-167J-110D01*
G01X846253Y132843D01*
X846276Y132806D01*
Y132772D01*
X846277Y132762D01*
G02X846278Y132746I-199J-20D01*
G01Y131850D01*
G02X846074Y131646I-204J0D01*
G01X843174D01*
G02X842970Y131850I0J204D01*
G01Y132748D01*
G02X842971Y132764I200J-4D01*
G01X842972Y132774D01*
Y132806D01*
X842988Y132832D01*
X842992Y132839D01*
X842993Y132841D01*
G02X843002Y132856I176J-95D01*
G01X843781Y134049D01*
G03X843813Y134158I-168J109D01*
G01Y134259D01*
G03X843780Y134369I-200J0D01*
G01X843003Y135554D01*
G02X842999Y135562I176J93D01*
G01X842994Y135570D01*
X842972Y135604D01*
Y135638D01*
X842971Y135648D01*
G02X842970Y135664I199J20D01*
G01Y136560D01*
G02X843174Y136764I204J0D01*
G37*
G36*
G01Y122590D02*
X846074D01*
G02X846278Y122386I0J-204D01*
G01Y121485D01*
G02X846277Y121469I-200J4D01*
G01X846276Y121459D01*
Y121425D01*
X846254Y121391D01*
X846249Y121383D01*
G02X846245Y121375I-180J85D01*
G01X845435Y120141D01*
G03Y119921I167J-110D01*
G01X846245Y118682D01*
G02X846250Y118674I-167J-110D01*
G01X846253Y118669D01*
X846276Y118632D01*
Y118598D01*
X846277Y118588D01*
G02X846278Y118572I-199J-20D01*
G01Y117676D01*
G02X846074Y117472I-204J0D01*
G01X843174D01*
G02X842970Y117676I0J204D01*
G01Y118574D01*
G02X842971Y118590I200J-4D01*
G01X842972Y118600D01*
Y118632D01*
X842988Y118658D01*
X842992Y118665D01*
X842993Y118667D01*
G02X843002Y118682I176J-95D01*
G01X843781Y119875D01*
G03X843813Y119984I-168J109D01*
G01Y120085D01*
G03X843780Y120195I-200J0D01*
G01X843003Y121380D01*
G02X842999Y121388I176J93D01*
G01X842994Y121396D01*
X842972Y121430D01*
Y121464D01*
X842971Y121474D01*
G02X842970Y121490I199J20D01*
G01Y122386D01*
G02X843174Y122590I204J0D01*
G37*
G36*
G01X953658Y110922D02*
Y114984D01*
G02X953861Y115186I203J-1D01*
G01X958712D01*
G02X958914Y114984I0J-202D01*
G01Y110922D01*
G02X958711Y110720I-203J1D01*
G01X953860D01*
G02X953658Y110922I0J202D01*
G37*
G36*
G01Y132182D02*
Y136244D01*
G02X953861Y136446I203J-1D01*
G01X958712D01*
G02X958914Y136244I0J-202D01*
G01Y132182D01*
G02X958711Y131980I-203J1D01*
G01X953860D01*
G02X953658Y132182I0J202D01*
G37*
G36*
G01X958914Y129157D02*
Y125095D01*
G02X958711Y124892I-203J0D01*
G01X953861D01*
G02X953658Y125095I0J203D01*
G01Y129157D01*
G02X953861Y129360I203J0D01*
G01X958711D01*
G02X958914Y129157I0J-203D01*
G37*
G36*
G01Y122071D02*
Y118009D01*
G02X958711Y117806I-203J0D01*
G01X953861D01*
G02X953658Y118009I0J203D01*
G01Y122071D01*
G02X953861Y122274I203J0D01*
G01X958711D01*
G02X958914Y122071I0J-203D01*
G37*
G36*
G01X982772Y129650D02*
X985673D01*
G02X985876Y129447I0J-203D01*
G01Y128546D01*
G02X985875Y128530I-200J4D01*
G01X985874Y128520D01*
Y128486D01*
X985852Y128452D01*
X985847Y128444D01*
G02X985843Y128436I-180J85D01*
G01X985033Y127202D01*
G03Y126982I167J-110D01*
G01X985843Y125743D01*
G02X985848Y125735I-167J-110D01*
G01X985851Y125730D01*
X985874Y125693D01*
Y125659D01*
X985875Y125649D01*
G02X985876Y125633I-199J-20D01*
G01Y124737D01*
G02X985672Y124534I-204J1D01*
G01X982771D01*
G02X982568Y124737I0J203D01*
G01Y125635D01*
G02X982569Y125651I200J-4D01*
G01X982570Y125661D01*
Y125693D01*
X982586Y125719D01*
X982590Y125726D01*
X982591Y125728D01*
G02X982600Y125743I176J-95D01*
G01X983379Y126936D01*
G03X983411Y127045I-168J109D01*
G01Y127146D01*
G03X983378Y127256I-200J0D01*
G01X982601Y128441D01*
G02X982597Y128449I176J93D01*
G01X982592Y128457D01*
X982570Y128491D01*
Y128525D01*
X982569Y128535D01*
G02X982568Y128551I199J20D01*
G01Y129447D01*
G02X982772Y129650I204J-1D01*
G37*
G36*
G01Y115478D02*
X985672D01*
G02X985876Y115274I0J-204D01*
G01Y114373D01*
G02X985875Y114357I-200J4D01*
G01X985874Y114347D01*
Y114313D01*
X985852Y114279D01*
X985847Y114271D01*
G02X985843Y114263I-180J85D01*
G01X985033Y113029D01*
G03Y112809I167J-110D01*
G01X985843Y111570D01*
G02X985848Y111562I-167J-110D01*
G01X985851Y111557D01*
X985874Y111520D01*
Y111486D01*
X985875Y111476D01*
G02X985876Y111460I-199J-20D01*
G01Y110564D01*
G02X985672Y110360I-204J0D01*
G01X982772D01*
G02X982568Y110564I0J204D01*
G01Y111462D01*
G02X982569Y111478I200J-4D01*
G01X982570Y111488D01*
Y111520D01*
X982586Y111546D01*
X982590Y111553D01*
X982591Y111555D01*
G02X982600Y111570I176J-95D01*
G01X983379Y112763D01*
G03X983411Y112872I-168J109D01*
G01Y112973D01*
G03X983378Y113083I-200J0D01*
G01X982601Y114268D01*
G02X982597Y114276I176J93D01*
G01X982592Y114284D01*
X982570Y114318D01*
Y114352D01*
X982569Y114362D01*
G02X982568Y114378I199J20D01*
G01Y115274D01*
G02X982772Y115478I204J0D01*
G37*
G36*
G01X993174Y136764D02*
X996074D01*
G02X996278Y136560I0J-204D01*
G01Y135659D01*
G02X996277Y135643I-200J4D01*
G01X996276Y135633D01*
Y135599D01*
X996254Y135565D01*
X996249Y135557D01*
G02X996245Y135549I-180J85D01*
G01X995435Y134315D01*
G03Y134095I167J-110D01*
G01X996245Y132856D01*
G02X996250Y132848I-167J-110D01*
G01X996253Y132843D01*
X996276Y132806D01*
Y132772D01*
X996277Y132762D01*
G02X996278Y132746I-199J-20D01*
G01Y131850D01*
G02X996074Y131646I-204J0D01*
G01X993174D01*
G02X992970Y131850I0J204D01*
G01Y132748D01*
G02X992971Y132764I200J-4D01*
G01X992972Y132774D01*
Y132806D01*
X992988Y132832D01*
X992992Y132839D01*
X992993Y132841D01*
G02X993002Y132856I176J-95D01*
G01X993781Y134049D01*
G03X993813Y134158I-168J109D01*
G01Y134259D01*
G03X993780Y134369I-200J0D01*
G01X993003Y135554D01*
G02X992999Y135562I176J93D01*
G01X992994Y135570D01*
X992972Y135604D01*
Y135638D01*
X992971Y135648D01*
G02X992970Y135664I199J20D01*
G01Y136560D01*
G02X993174Y136764I204J0D01*
G37*
G36*
G01Y122590D02*
X996074D01*
G02X996278Y122386I0J-204D01*
G01Y121485D01*
G02X996277Y121469I-200J4D01*
G01X996276Y121459D01*
Y121425D01*
X996254Y121391D01*
X996249Y121383D01*
G02X996245Y121375I-180J85D01*
G01X995435Y120141D01*
G03Y119921I167J-110D01*
G01X996245Y118682D01*
G02X996250Y118674I-167J-110D01*
G01X996253Y118669D01*
X996276Y118632D01*
Y118598D01*
X996277Y118588D01*
G02X996278Y118572I-199J-20D01*
G01Y117676D01*
G02X996074Y117472I-204J0D01*
G01X993174D01*
G02X992970Y117676I0J204D01*
G01Y118574D01*
G02X992971Y118590I200J-4D01*
G01X992972Y118600D01*
Y118632D01*
X992988Y118658D01*
X992992Y118665D01*
X992993Y118667D01*
G02X993002Y118682I176J-95D01*
G01X993781Y119875D01*
G03X993813Y119984I-168J109D01*
G01Y120085D01*
G03X993780Y120195I-200J0D01*
G01X993003Y121380D01*
G02X992999Y121388I176J93D01*
G01X992994Y121396D01*
X992972Y121430D01*
Y121464D01*
X992971Y121474D01*
G02X992970Y121490I199J20D01*
G01Y122386D01*
G02X993174Y122590I204J0D01*
G37*
G36*
G01X1056020Y132182D02*
Y136244D01*
G02X1056223Y136446I203J-1D01*
G01X1061074D01*
G02X1061276Y136244I0J-202D01*
G01Y132182D01*
G02X1061073Y131980I-203J1D01*
G01X1056222D01*
G02X1056020Y132182I0J202D01*
G37*
G36*
G01X1061276Y129157D02*
Y125095D01*
G02X1061073Y124892I-203J0D01*
G01X1056223D01*
G02X1056020Y125095I0J203D01*
G01Y129157D01*
G02X1056223Y129360I203J0D01*
G01X1061073D01*
G02X1061276Y129157I0J-203D01*
G37*
G36*
G01Y122071D02*
Y118009D01*
G02X1061073Y117806I-203J0D01*
G01X1056223D01*
G02X1056020Y118009I0J203D01*
G01Y122071D01*
G02X1056223Y122274I203J0D01*
G01X1061073D01*
G02X1061276Y122071I0J-203D01*
G37*
G36*
G01X1056020Y110922D02*
Y114984D01*
G02X1056223Y115186I203J-1D01*
G01X1061074D01*
G02X1061276Y114984I0J-202D01*
G01Y110922D01*
G02X1061073Y110720I-203J1D01*
G01X1056222D01*
G02X1056020Y110922I0J202D01*
G37*
G36*
G01X1085134Y129650D02*
X1088035D01*
G02X1088238Y129447I0J-203D01*
G01Y128546D01*
G02X1088237Y128530I-200J4D01*
G01X1088236Y128520D01*
Y128486D01*
X1088214Y128452D01*
X1088209Y128444D01*
G02X1088205Y128436I-180J85D01*
G01X1087395Y127202D01*
G03Y126982I167J-110D01*
G01X1088205Y125743D01*
G02X1088210Y125735I-167J-110D01*
G01X1088213Y125730D01*
X1088236Y125693D01*
Y125659D01*
X1088237Y125649D01*
G02X1088238Y125633I-199J-20D01*
G01Y124737D01*
G02X1088034Y124534I-204J1D01*
G01X1085133D01*
G02X1084930Y124737I0J203D01*
G01Y125635D01*
G02X1084931Y125651I200J-4D01*
G01X1084932Y125661D01*
Y125693D01*
X1084948Y125719D01*
X1084952Y125726D01*
X1084953Y125728D01*
G02X1084962Y125743I176J-95D01*
G01X1085741Y126936D01*
G03X1085773Y127045I-168J109D01*
G01Y127146D01*
G03X1085740Y127256I-200J0D01*
G01X1084963Y128441D01*
G02X1084959Y128449I176J93D01*
G01X1084954Y128457D01*
X1084932Y128491D01*
Y128525D01*
X1084931Y128535D01*
G02X1084930Y128551I199J20D01*
G01Y129447D01*
G02X1085134Y129650I204J-1D01*
G37*
G36*
G01Y115478D02*
X1088034D01*
G02X1088238Y115274I0J-204D01*
G01Y114373D01*
G02X1088237Y114357I-200J4D01*
G01X1088236Y114347D01*
Y114313D01*
X1088214Y114279D01*
X1088209Y114271D01*
G02X1088205Y114263I-180J85D01*
G01X1087395Y113029D01*
G03Y112809I167J-110D01*
G01X1088205Y111570D01*
G02X1088210Y111562I-167J-110D01*
G01X1088213Y111557D01*
X1088236Y111520D01*
Y111486D01*
X1088237Y111476D01*
G02X1088238Y111460I-199J-20D01*
G01Y110564D01*
G02X1088034Y110360I-204J0D01*
G01X1085134D01*
G02X1084930Y110564I0J204D01*
G01Y111462D01*
G02X1084931Y111478I200J-4D01*
G01X1084932Y111488D01*
Y111520D01*
X1084948Y111546D01*
X1084952Y111553D01*
X1084953Y111555D01*
G02X1084962Y111570I176J-95D01*
G01X1085741Y112763D01*
G03X1085773Y112872I-168J109D01*
G01Y112973D01*
G03X1085740Y113083I-200J0D01*
G01X1084963Y114268D01*
G02X1084959Y114276I176J93D01*
G01X1084954Y114284D01*
X1084932Y114318D01*
Y114352D01*
X1084931Y114362D01*
G02X1084930Y114378I199J20D01*
G01Y115274D01*
G02X1085134Y115478I204J0D01*
G37*
G36*
G01X1095536Y122590D02*
X1098436D01*
G02X1098640Y122386I0J-204D01*
G01Y121485D01*
G02X1098639Y121469I-200J4D01*
G01X1098638Y121459D01*
Y121425D01*
X1098616Y121391D01*
X1098611Y121383D01*
G02X1098607Y121375I-180J85D01*
G01X1097797Y120141D01*
G03Y119921I167J-110D01*
G01X1098607Y118682D01*
G02X1098612Y118674I-167J-110D01*
G01X1098615Y118669D01*
X1098638Y118632D01*
Y118598D01*
X1098639Y118588D01*
G02X1098640Y118572I-199J-20D01*
G01Y117676D01*
G02X1098436Y117472I-204J0D01*
G01X1095536D01*
G02X1095332Y117676I0J204D01*
G01Y118574D01*
G02X1095333Y118590I200J-4D01*
G01X1095334Y118600D01*
Y118632D01*
X1095350Y118658D01*
X1095354Y118665D01*
X1095355Y118667D01*
G02X1095364Y118682I176J-95D01*
G01X1096143Y119875D01*
G03X1096175Y119984I-168J109D01*
G01Y120085D01*
G03X1096142Y120195I-200J0D01*
G01X1095365Y121380D01*
G02X1095361Y121388I176J93D01*
G01X1095356Y121396D01*
X1095334Y121430D01*
Y121464D01*
X1095333Y121474D01*
G02X1095332Y121490I199J20D01*
G01Y122386D01*
G02X1095536Y122590I204J0D01*
G37*
G36*
G01X1115956Y394678D02*
Y390716D01*
G02X1115753Y390514I-203J1D01*
G01X1111102D01*
G02X1110900Y390716I0J202D01*
G01Y394678D01*
G02X1111103Y394880I203J-1D01*
G01X1115754D01*
G02X1115956Y394678I0J-202D01*
G37*
G36*
G01X1110900Y397803D02*
Y401765D01*
G02X1111103Y401968I203J0D01*
G01X1115753D01*
G02X1115956Y401765I0J-203D01*
G01Y397803D01*
G02X1115753Y397600I-203J0D01*
G01X1111103D01*
G02X1110900Y397803I0J203D01*
G37*
G36*
G01X1115956Y437198D02*
Y433236D01*
G02X1115753Y433034I-203J1D01*
G01X1111102D01*
G02X1110900Y433236I0J202D01*
G01Y437198D01*
G02X1111103Y437400I203J-1D01*
G01X1115754D01*
G02X1115956Y437198I0J-202D01*
G37*
G36*
G01Y444284D02*
Y440322D01*
G02X1115753Y440120I-203J1D01*
G01X1111102D01*
G02X1110900Y440322I0J202D01*
G01Y444284D01*
G02X1111103Y444486I203J-1D01*
G01X1115754D01*
G02X1115956Y444284I0J-202D01*
G37*
G36*
G01Y423024D02*
Y419062D01*
G02X1115753Y418860I-203J1D01*
G01X1111102D01*
G02X1110900Y419062I0J202D01*
G01Y423024D01*
G02X1111103Y423226I203J-1D01*
G01X1115754D01*
G02X1115956Y423024I0J-202D01*
G37*
G36*
G01X1110900Y426149D02*
Y430111D01*
G02X1111103Y430314I203J0D01*
G01X1115753D01*
G02X1115956Y430111I0J-203D01*
G01Y426149D01*
G02X1115753Y425946I-203J0D01*
G01X1111103D01*
G02X1110900Y426149I0J203D01*
G37*
G36*
G01X1115956Y408852D02*
Y404890D01*
G02X1115753Y404688I-203J1D01*
G01X1111102D01*
G02X1110900Y404890I0J202D01*
G01Y408852D01*
G02X1111103Y409054I203J-1D01*
G01X1115754D01*
G02X1115956Y408852I0J-202D01*
G37*
G36*
G01Y415938D02*
Y411976D01*
G02X1115753Y411774I-203J1D01*
G01X1111102D01*
G02X1110900Y411976I0J202D01*
G01Y415938D01*
G02X1111103Y416140I203J-1D01*
G01X1115754D01*
G02X1115956Y415938I0J-202D01*
G37*
G36*
G01X1158382Y110922D02*
Y114984D01*
G02X1158585Y115186I203J-1D01*
G01X1163436D01*
G02X1163638Y114984I0J-202D01*
G01Y110922D01*
G02X1163435Y110720I-203J1D01*
G01X1158584D01*
G02X1158382Y110922I0J202D01*
G37*
G36*
G01Y132182D02*
Y136244D01*
G02X1158585Y136446I203J-1D01*
G01X1163436D01*
G02X1163638Y136244I0J-202D01*
G01Y132182D01*
G02X1163435Y131980I-203J1D01*
G01X1158584D01*
G02X1158382Y132182I0J202D01*
G37*
G36*
G01X1163638Y129157D02*
Y125095D01*
G02X1163435Y124892I-203J0D01*
G01X1158585D01*
G02X1158382Y125095I0J203D01*
G01Y129157D01*
G02X1158585Y129360I203J0D01*
G01X1163435D01*
G02X1163638Y129157I0J-203D01*
G37*
G36*
G01Y122071D02*
Y118009D01*
G02X1163435Y117806I-203J0D01*
G01X1158585D01*
G02X1158382Y118009I0J203D01*
G01Y122071D01*
G02X1158585Y122274I203J0D01*
G01X1163435D01*
G02X1163638Y122071I0J-203D01*
G37*
G36*
G01X1187130Y471016D02*
Y467054D01*
G02X1186928Y466852I-202J0D01*
G01X1182278D01*
G02X1182076Y467054I0J202D01*
G01Y471016D01*
G02X1182278Y471218I202J0D01*
G01X1186928D01*
G02X1187130Y471016I0J-202D01*
G37*
G36*
G01X1186928Y473938D02*
X1182278D01*
G02X1182076Y474141I1J203D01*
G01Y478104D01*
G02X1182278Y478306I202J0D01*
G01X1186928D01*
G02X1187130Y478103I-1J-203D01*
G01Y474140D01*
G02X1186928Y473938I-202J0D01*
G37*
G36*
G01X1187496Y129650D02*
X1190397D01*
G02X1190600Y129447I0J-203D01*
G01Y128546D01*
G02X1190599Y128530I-200J4D01*
G01X1190598Y128520D01*
Y128486D01*
X1190576Y128452D01*
X1190571Y128444D01*
G02X1190567Y128436I-180J85D01*
G01X1189757Y127202D01*
G03Y126982I167J-110D01*
G01X1190567Y125743D01*
G02X1190572Y125735I-167J-110D01*
G01X1190575Y125730D01*
X1190598Y125693D01*
Y125659D01*
X1190599Y125649D01*
G02X1190600Y125633I-199J-20D01*
G01Y124737D01*
G02X1190396Y124534I-204J1D01*
G01X1187495D01*
G02X1187292Y124737I0J203D01*
G01Y125635D01*
G02X1187293Y125651I200J-4D01*
G01X1187294Y125661D01*
Y125693D01*
X1187310Y125719D01*
X1187314Y125726D01*
X1187315Y125728D01*
G02X1187324Y125743I176J-95D01*
G01X1188103Y126936D01*
G03X1188135Y127045I-168J109D01*
G01Y127146D01*
G03X1188102Y127256I-200J0D01*
G01X1187325Y128441D01*
G02X1187321Y128449I176J93D01*
G01X1187316Y128457D01*
X1187294Y128491D01*
Y128525D01*
X1187293Y128535D01*
G02X1187292Y128551I199J20D01*
G01Y129447D01*
G02X1187496Y129650I204J-1D01*
G37*
G36*
G01X1197898Y136764D02*
X1200798D01*
G02X1201002Y136560I0J-204D01*
G01Y135659D01*
G02X1201001Y135643I-200J4D01*
G01X1201000Y135633D01*
Y135599D01*
X1200978Y135565D01*
X1200973Y135557D01*
G02X1200969Y135549I-180J85D01*
G01X1200159Y134315D01*
G03Y134095I167J-110D01*
G01X1200969Y132856D01*
G02X1200974Y132848I-167J-110D01*
G01X1200977Y132843D01*
X1201000Y132806D01*
Y132772D01*
X1201001Y132762D01*
G02X1201002Y132746I-199J-20D01*
G01Y131850D01*
G02X1200798Y131646I-204J0D01*
G01X1197898D01*
G02X1197694Y131850I0J204D01*
G01Y132748D01*
G02X1197695Y132764I200J-4D01*
G01X1197696Y132774D01*
Y132806D01*
X1197712Y132832D01*
X1197716Y132839D01*
X1197717Y132841D01*
G02X1197726Y132856I176J-95D01*
G01X1198505Y134049D01*
G03X1198537Y134158I-168J109D01*
G01Y134259D01*
G03X1198504Y134369I-200J0D01*
G01X1197727Y135554D01*
G02X1197723Y135562I176J93D01*
G01X1197718Y135570D01*
X1197696Y135604D01*
Y135638D01*
X1197695Y135648D01*
G02X1197694Y135664I199J20D01*
G01Y136560D01*
G02X1197898Y136764I204J0D01*
G37*
G36*
G01Y122590D02*
X1200798D01*
G02X1201002Y122386I0J-204D01*
G01Y121485D01*
G02X1201001Y121469I-200J4D01*
G01X1201000Y121459D01*
Y121425D01*
X1200978Y121391D01*
X1200973Y121383D01*
G02X1200969Y121375I-180J85D01*
G01X1200159Y120141D01*
G03Y119921I167J-110D01*
G01X1200969Y118682D01*
G02X1200974Y118674I-167J-110D01*
G01X1200977Y118669D01*
X1201000Y118632D01*
Y118598D01*
X1201001Y118588D01*
G02X1201002Y118572I-199J-20D01*
G01Y117676D01*
G02X1200798Y117472I-204J0D01*
G01X1197898D01*
G02X1197694Y117676I0J204D01*
G01Y118574D01*
G02X1197695Y118590I200J-4D01*
G01X1197696Y118600D01*
Y118632D01*
X1197712Y118658D01*
X1197716Y118665D01*
X1197717Y118667D01*
G02X1197726Y118682I176J-95D01*
G01X1198505Y119875D01*
G03X1198537Y119984I-168J109D01*
G01Y120085D01*
G03X1198504Y120195I-200J0D01*
G01X1197727Y121380D01*
G02X1197723Y121388I176J93D01*
G01X1197718Y121396D01*
X1197696Y121430D01*
Y121464D01*
X1197695Y121474D01*
G02X1197694Y121490I199J20D01*
G01Y122386D01*
G02X1197898Y122590I204J0D01*
G37*
G36*
G01X1227760Y471560D02*
X1230661D01*
G02X1230864Y471357I0J-203D01*
G01Y470456D01*
G02X1230863Y470440I-200J4D01*
G01X1230862Y470430D01*
Y470396D01*
X1230840Y470362D01*
X1230835Y470354D01*
G02X1230831Y470346I-180J85D01*
G01X1230021Y469112D01*
G03Y468892I167J-110D01*
G01X1230831Y467653D01*
G02X1230836Y467645I-167J-110D01*
G01X1230839Y467640D01*
X1230862Y467603D01*
Y467569D01*
X1230863Y467559D01*
G02X1230864Y467543I-199J-20D01*
G01Y466647D01*
G02X1230660Y466444I-204J1D01*
G01X1227759D01*
G02X1227556Y466647I0J203D01*
G01Y467545D01*
G02X1227557Y467561I200J-4D01*
G01X1227558Y467571D01*
Y467603D01*
X1227574Y467629D01*
X1227578Y467636D01*
X1227579Y467638D01*
G02X1227588Y467653I176J-95D01*
G01X1228367Y468846D01*
G03X1228399Y468955I-168J109D01*
G01Y469056D01*
G03X1228366Y469166I-200J0D01*
G01X1227589Y470351D01*
G02X1227585Y470359I176J93D01*
G01X1227580Y470367D01*
X1227558Y470401D01*
Y470435D01*
X1227557Y470445D01*
G02X1227556Y470461I199J20D01*
G01Y471357D01*
G02X1227760Y471560I204J-1D01*
G37*
G36*
G01X1238162Y478672D02*
X1241063D01*
G02X1241266Y478469I0J-203D01*
G01Y477568D01*
G02X1241265Y477552I-200J4D01*
G01X1241264Y477542D01*
Y477508D01*
X1241242Y477474D01*
X1241237Y477466D01*
G02X1241233Y477458I-180J85D01*
G01X1240423Y476224D01*
G03Y476004I167J-110D01*
G01X1241233Y474765D01*
G02X1241238Y474757I-167J-110D01*
G01X1241241Y474752D01*
X1241264Y474715D01*
Y474681D01*
X1241265Y474671D01*
G02X1241266Y474655I-199J-20D01*
G01Y473759D01*
G02X1241062Y473556I-204J1D01*
G01X1238161D01*
G02X1237958Y473759I0J203D01*
G01Y474657D01*
G02X1237959Y474673I200J-4D01*
G01X1237960Y474683D01*
Y474715D01*
X1237976Y474741D01*
X1237980Y474748D01*
X1237981Y474750D01*
G02X1237990Y474765I176J-95D01*
G01X1238769Y475958D01*
G03X1238801Y476067I-168J109D01*
G01Y476168D01*
G03X1238768Y476278I-200J0D01*
G01X1237991Y477463D01*
G02X1237987Y477471I176J93D01*
G01X1237982Y477479D01*
X1237960Y477513D01*
Y477547D01*
X1237959Y477557D01*
G02X1237958Y477573I199J20D01*
G01Y478469D01*
G02X1238162Y478672I204J-1D01*
G37*
G36*
G01X1260744Y132182D02*
Y136244D01*
G02X1260947Y136446I203J-1D01*
G01X1265798D01*
G02X1266000Y136244I0J-202D01*
G01Y132182D01*
G02X1265797Y131980I-203J1D01*
G01X1260946D01*
G02X1260744Y132182I0J202D01*
G37*
G36*
G01X1266000Y129157D02*
Y125095D01*
G02X1265797Y124892I-203J0D01*
G01X1260947D01*
G02X1260744Y125095I0J203D01*
G01Y129157D01*
G02X1260947Y129360I203J0D01*
G01X1265797D01*
G02X1266000Y129157I0J-203D01*
G37*
G36*
G01X1260744Y110922D02*
Y114984D01*
G02X1260947Y115186I203J-1D01*
G01X1265798D01*
G02X1266000Y114984I0J-202D01*
G01Y110922D01*
G02X1265797Y110720I-203J1D01*
G01X1260946D01*
G02X1260744Y110922I0J202D01*
G37*
G36*
G01X1266000Y122071D02*
Y118009D01*
G02X1265797Y117806I-203J0D01*
G01X1260947D01*
G02X1260744Y118009I0J203D01*
G01Y122071D01*
G02X1260947Y122274I203J0D01*
G01X1265797D01*
G02X1266000Y122071I0J-203D01*
G37*
G36*
G01X1289858Y129650D02*
X1292759D01*
G02X1292962Y129447I0J-203D01*
G01Y128546D01*
G02X1292961Y128530I-200J4D01*
G01X1292960Y128520D01*
Y128486D01*
X1292938Y128452D01*
X1292933Y128444D01*
G02X1292929Y128436I-180J85D01*
G01X1292119Y127202D01*
G03Y126982I167J-110D01*
G01X1292929Y125743D01*
G02X1292934Y125735I-167J-110D01*
G01X1292937Y125730D01*
X1292960Y125693D01*
Y125659D01*
X1292961Y125649D01*
G02X1292962Y125633I-199J-20D01*
G01Y124737D01*
G02X1292758Y124534I-204J1D01*
G01X1289857D01*
G02X1289654Y124737I0J203D01*
G01Y125635D01*
G02X1289655Y125651I200J-4D01*
G01X1289656Y125661D01*
Y125693D01*
X1289672Y125719D01*
X1289676Y125726D01*
X1289677Y125728D01*
G02X1289686Y125743I176J-95D01*
G01X1290465Y126936D01*
G03X1290497Y127045I-168J109D01*
G01Y127146D01*
G03X1290464Y127256I-200J0D01*
G01X1289687Y128441D01*
G02X1289683Y128449I176J93D01*
G01X1289678Y128457D01*
X1289656Y128491D01*
Y128525D01*
X1289655Y128535D01*
G02X1289654Y128551I199J20D01*
G01Y129447D01*
G02X1289858Y129650I204J-1D01*
G37*
G36*
G01X1300260Y136764D02*
X1303160D01*
G02X1303364Y136560I0J-204D01*
G01Y135659D01*
G02X1303363Y135643I-200J4D01*
G01X1303362Y135633D01*
Y135599D01*
X1303340Y135565D01*
X1303335Y135557D01*
G02X1303331Y135549I-180J85D01*
G01X1302521Y134315D01*
G03Y134095I167J-110D01*
G01X1303331Y132856D01*
G02X1303336Y132848I-167J-110D01*
G01X1303339Y132843D01*
X1303362Y132806D01*
Y132772D01*
X1303363Y132762D01*
G02X1303364Y132746I-199J-20D01*
G01Y131850D01*
G02X1303160Y131646I-204J0D01*
G01X1300260D01*
G02X1300056Y131850I0J204D01*
G01Y132748D01*
G02X1300057Y132764I200J-4D01*
G01X1300058Y132774D01*
Y132806D01*
X1300074Y132832D01*
X1300078Y132839D01*
X1300079Y132841D01*
G02X1300088Y132856I176J-95D01*
G01X1300867Y134049D01*
G03X1300899Y134158I-168J109D01*
G01Y134259D01*
G03X1300866Y134369I-200J0D01*
G01X1300089Y135554D01*
G02X1300085Y135562I176J93D01*
G01X1300080Y135570D01*
X1300058Y135604D01*
Y135638D01*
X1300057Y135648D01*
G02X1300056Y135664I199J20D01*
G01Y136560D01*
G02X1300260Y136764I204J0D01*
G37*
G36*
G01Y122590D02*
X1303160D01*
G02X1303364Y122386I0J-204D01*
G01Y121485D01*
G02X1303363Y121469I-200J4D01*
G01X1303362Y121459D01*
Y121425D01*
X1303340Y121391D01*
X1303335Y121383D01*
G02X1303331Y121375I-180J85D01*
G01X1302521Y120141D01*
G03Y119921I167J-110D01*
G01X1303331Y118682D01*
G02X1303336Y118674I-167J-110D01*
G01X1303339Y118669D01*
X1303362Y118632D01*
Y118598D01*
X1303363Y118588D01*
G02X1303364Y118572I-199J-20D01*
G01Y117676D01*
G02X1303160Y117472I-204J0D01*
G01X1300260D01*
G02X1300056Y117676I0J204D01*
G01Y118574D01*
G02X1300057Y118590I200J-4D01*
G01X1300058Y118600D01*
Y118632D01*
X1300074Y118658D01*
X1300078Y118665D01*
X1300079Y118667D01*
G02X1300088Y118682I176J-95D01*
G01X1300867Y119875D01*
G03X1300899Y119984I-168J109D01*
G01Y120085D01*
G03X1300866Y120195I-200J0D01*
G01X1300089Y121380D01*
G02X1300085Y121388I176J93D01*
G01X1300080Y121396D01*
X1300058Y121430D01*
Y121464D01*
X1300057Y121474D01*
G02X1300056Y121490I199J20D01*
G01Y122386D01*
G02X1300260Y122590I204J0D01*
G37*
G36*
G01X1416000Y136244D02*
Y132182D01*
G02X1415798Y131980I-202J0D01*
G01X1410948D01*
G02X1410746Y132182I0J202D01*
G01Y136244D01*
G02X1410948Y136446I202J0D01*
G01X1415798D01*
G02X1416000Y136244I0J-202D01*
G37*
G36*
G01X1415798Y124892D02*
X1410948D01*
G02X1410746Y125095I1J203D01*
G01Y129158D01*
G02X1410948Y129360I202J0D01*
G01X1415798D01*
G02X1416000Y129157I-1J-203D01*
G01Y125094D01*
G02X1415798Y124892I-202J0D01*
G37*
G36*
G01Y117806D02*
X1410948D01*
G02X1410746Y118009I1J203D01*
G01Y122072D01*
G02X1410948Y122274I202J0D01*
G01X1415798D01*
G02X1416000Y122071I-1J-203D01*
G01Y118008D01*
G02X1415798Y117806I-202J0D01*
G37*
G36*
G01X1416000Y114984D02*
Y110922D01*
G02X1415798Y110720I-202J0D01*
G01X1410948D01*
G02X1410746Y110922I0J202D01*
G01Y114984D01*
G02X1410948Y115186I202J0D01*
G01X1415798D01*
G02X1416000Y114984I0J-202D01*
G37*
G36*
G01X1518362D02*
Y110922D01*
G02X1518160Y110720I-202J0D01*
G01X1513310D01*
G02X1513108Y110922I0J202D01*
G01Y114984D01*
G02X1513310Y115186I202J0D01*
G01X1518160D01*
G02X1518362Y114984I0J-202D01*
G37*
G36*
G01Y136244D02*
Y132182D01*
G02X1518160Y131980I-202J0D01*
G01X1513310D01*
G02X1513108Y132182I0J202D01*
G01Y136244D01*
G02X1513310Y136446I202J0D01*
G01X1518160D01*
G02X1518362Y136244I0J-202D01*
G37*
G36*
G01X1518160Y124892D02*
X1513310D01*
G02X1513108Y125095I1J203D01*
G01Y129158D01*
G02X1513310Y129360I202J0D01*
G01X1518160D01*
G02X1518362Y129157I-1J-203D01*
G01Y125094D01*
G02X1518160Y124892I-202J0D01*
G37*
G36*
G01Y117806D02*
X1513310D01*
G02X1513108Y118009I1J203D01*
G01Y122072D01*
G02X1513310Y122274I202J0D01*
G01X1518160D01*
G02X1518362Y122071I-1J-203D01*
G01Y118008D01*
G02X1518160Y117806I-202J0D01*
G37*
G36*
G01X1524458Y423602D02*
X1527358D01*
G02X1527562Y423398I0J-204D01*
G01Y422497D01*
G02X1527561Y422481I-200J4D01*
G01X1527560Y422471D01*
Y422437D01*
X1527538Y422403D01*
X1527533Y422395D01*
G02X1527529Y422387I-180J85D01*
G01X1526719Y421153D01*
G03Y420933I167J-110D01*
G01X1527529Y419694D01*
G02X1527534Y419686I-167J-110D01*
G01X1527537Y419681D01*
X1527560Y419644D01*
Y419610D01*
X1527561Y419600D01*
G02X1527562Y419584I-199J-20D01*
G01Y418688D01*
G02X1527358Y418484I-204J0D01*
G01X1524458D01*
G02X1524254Y418688I0J204D01*
G01Y419586D01*
G02X1524255Y419602I200J-4D01*
G01X1524256Y419612D01*
Y419644D01*
X1524272Y419670D01*
X1524276Y419677D01*
X1524277Y419679D01*
G02X1524286Y419694I176J-95D01*
G01X1525065Y420887D01*
G03X1525097Y420996I-168J109D01*
G01Y421097D01*
G03X1525064Y421207I-200J0D01*
G01X1524287Y422392D01*
G02X1524283Y422400I176J93D01*
G01X1524278Y422408D01*
X1524256Y422442D01*
Y422476D01*
X1524255Y422486D01*
G02X1524254Y422502I199J20D01*
G01Y423398D01*
G02X1524458Y423602I204J0D01*
G37*
G36*
G01Y409428D02*
X1527359D01*
G02X1527562Y409225I0J-203D01*
G01Y408324D01*
G02X1527561Y408308I-200J4D01*
G01X1527560Y408298D01*
Y408264D01*
X1527538Y408230D01*
X1527533Y408222D01*
G02X1527529Y408214I-180J85D01*
G01X1526719Y406980D01*
G03Y406760I167J-110D01*
G01X1527529Y405521D01*
G02X1527534Y405513I-167J-110D01*
G01X1527537Y405508D01*
X1527560Y405471D01*
Y405437D01*
X1527561Y405427D01*
G02X1527562Y405411I-199J-20D01*
G01Y404515D01*
G02X1527358Y404312I-204J1D01*
G01X1524457D01*
G02X1524254Y404515I0J203D01*
G01Y405413D01*
G02X1524255Y405429I200J-4D01*
G01X1524256Y405439D01*
Y405471D01*
X1524272Y405497D01*
X1524276Y405504D01*
X1524277Y405506D01*
G02X1524286Y405521I176J-95D01*
G01X1525065Y406714D01*
G03X1525097Y406823I-168J109D01*
G01Y406924D01*
G03X1525064Y407034I-200J0D01*
G01X1524287Y408219D01*
G02X1524283Y408227I176J93D01*
G01X1524278Y408235D01*
X1524256Y408269D01*
Y408303D01*
X1524255Y408313D01*
G02X1524254Y408329I199J20D01*
G01Y409225D01*
G02X1524458Y409428I204J-1D01*
G37*
G36*
G01X1514056Y416542D02*
X1516956D01*
G02X1517160Y416338I0J-204D01*
G01Y415437D01*
G02X1517159Y415421I-200J4D01*
G01X1517158Y415411D01*
Y415377D01*
X1517136Y415343D01*
X1517131Y415335D01*
G02X1517127Y415327I-180J85D01*
G01X1516317Y414093D01*
G03Y413873I167J-110D01*
G01X1517127Y412634D01*
G02X1517132Y412626I-167J-110D01*
G01X1517135Y412621D01*
X1517158Y412584D01*
Y412550D01*
X1517159Y412540D01*
G02X1517160Y412524I-199J-20D01*
G01Y411628D01*
G02X1516956Y411424I-204J0D01*
G01X1514056D01*
G02X1513852Y411628I0J204D01*
G01Y412526D01*
G02X1513853Y412542I200J-4D01*
G01X1513854Y412552D01*
Y412584D01*
X1513870Y412610D01*
X1513874Y412617D01*
X1513875Y412619D01*
G02X1513884Y412634I176J-95D01*
G01X1514663Y413827D01*
G03X1514695Y413936I-168J109D01*
G01Y414037D01*
G03X1514662Y414147I-200J0D01*
G01X1513885Y415332D01*
G02X1513881Y415340I176J93D01*
G01X1513876Y415348D01*
X1513854Y415382D01*
Y415416D01*
X1513853Y415426D01*
G02X1513852Y415442I199J20D01*
G01Y416338D01*
G02X1514056Y416542I204J0D01*
G37*
G36*
G01X1516456Y402368D02*
X1519356D01*
G02X1519560Y402164I0J-204D01*
G01Y401263D01*
G02X1519559Y401247I-200J4D01*
G01X1519558Y401237D01*
Y401203D01*
X1519536Y401169D01*
X1519531Y401161D01*
G02X1519527Y401153I-180J85D01*
G01X1518717Y399919D01*
G03Y399699I167J-110D01*
G01X1519527Y398460D01*
G02X1519532Y398452I-167J-110D01*
G01X1519535Y398447D01*
X1519558Y398410D01*
Y398376D01*
X1519559Y398366D01*
G02X1519560Y398350I-199J-20D01*
G01Y397454D01*
G02X1519356Y397250I-204J0D01*
G01X1516456D01*
G02X1516252Y397454I0J204D01*
G01Y398352D01*
G02X1516253Y398368I200J-4D01*
G01X1516254Y398378D01*
Y398410D01*
X1516270Y398436D01*
X1516274Y398443D01*
X1516275Y398445D01*
G02X1516284Y398460I176J-95D01*
G01X1517063Y399653D01*
G03X1517095Y399762I-168J109D01*
G01Y399863D01*
G03X1517062Y399973I-200J0D01*
G01X1516285Y401158D01*
G02X1516281Y401166I176J93D01*
G01X1516276Y401174D01*
X1516254Y401208D01*
Y401242D01*
X1516253Y401252D01*
G02X1516252Y401268I199J20D01*
G01Y402164D01*
G02X1516456Y402368I204J0D01*
G37*
G36*
G01X1524458Y395256D02*
X1527358D01*
G02X1527562Y395052I0J-204D01*
G01Y394151D01*
G02X1527561Y394135I-200J4D01*
G01X1527560Y394125D01*
Y394091D01*
X1527538Y394057D01*
X1527533Y394049D01*
G02X1527529Y394041I-180J85D01*
G01X1526719Y392807D01*
G03Y392587I167J-110D01*
G01X1527529Y391348D01*
G02X1527534Y391340I-167J-110D01*
G01X1527537Y391335D01*
X1527560Y391298D01*
Y391264D01*
X1527561Y391254D01*
G02X1527562Y391238I-199J-20D01*
G01Y390342D01*
G02X1527358Y390138I-204J0D01*
G01X1524458D01*
G02X1524254Y390342I0J204D01*
G01Y391240D01*
G02X1524255Y391256I200J-4D01*
G01X1524256Y391266D01*
Y391298D01*
X1524272Y391324D01*
X1524276Y391331D01*
X1524277Y391333D01*
G02X1524286Y391348I176J-95D01*
G01X1525065Y392541D01*
G03X1525097Y392650I-168J109D01*
G01Y392751D01*
G03X1525064Y392861I-200J0D01*
G01X1524287Y394046D01*
G02X1524283Y394054I176J93D01*
G01X1524278Y394062D01*
X1524256Y394096D01*
Y394130D01*
X1524255Y394140D01*
G02X1524254Y394156I199J20D01*
G01Y395052D01*
G02X1524458Y395256I204J0D01*
G37*
G36*
G01X1514056Y444888D02*
X1516956D01*
G02X1517160Y444684I0J-204D01*
G01Y443783D01*
G02X1517159Y443767I-200J4D01*
G01X1517158Y443757D01*
Y443723D01*
X1517136Y443689D01*
X1517131Y443681D01*
G02X1517127Y443673I-180J85D01*
G01X1516317Y442439D01*
G03Y442219I167J-110D01*
G01X1517127Y440980D01*
G02X1517132Y440972I-167J-110D01*
G01X1517135Y440967D01*
X1517158Y440930D01*
Y440896D01*
X1517159Y440886D01*
G02X1517160Y440870I-199J-20D01*
G01Y439974D01*
G02X1516956Y439770I-204J0D01*
G01X1514056D01*
G02X1513852Y439974I0J204D01*
G01Y440872D01*
G02X1513853Y440888I200J-4D01*
G01X1513854Y440898D01*
Y440930D01*
X1513870Y440956D01*
X1513874Y440963D01*
X1513875Y440965D01*
G02X1513884Y440980I176J-95D01*
G01X1514663Y442173D01*
G03X1514695Y442282I-168J109D01*
G01Y442383D01*
G03X1514662Y442493I-200J0D01*
G01X1513885Y443678D01*
G02X1513881Y443686I176J93D01*
G01X1513876Y443694D01*
X1513854Y443728D01*
Y443762D01*
X1513853Y443772D01*
G02X1513852Y443788I199J20D01*
G01Y444684D01*
G02X1514056Y444888I204J0D01*
G37*
G36*
G01X1524458Y437776D02*
X1527358D01*
G02X1527562Y437572I0J-204D01*
G01Y436671D01*
G02X1527561Y436655I-200J4D01*
G01X1527560Y436645D01*
Y436611D01*
X1527538Y436577D01*
X1527533Y436569D01*
G02X1527529Y436561I-180J85D01*
G01X1526719Y435327D01*
G03Y435107I167J-110D01*
G01X1527529Y433868D01*
G02X1527534Y433860I-167J-110D01*
G01X1527537Y433855D01*
X1527560Y433818D01*
Y433784D01*
X1527561Y433774D01*
G02X1527562Y433758I-199J-20D01*
G01Y432862D01*
G02X1527358Y432658I-204J0D01*
G01X1524458D01*
G02X1524254Y432862I0J204D01*
G01Y433760D01*
G02X1524255Y433776I200J-4D01*
G01X1524256Y433786D01*
Y433818D01*
X1524272Y433844D01*
X1524276Y433851D01*
X1524277Y433853D01*
G02X1524286Y433868I176J-95D01*
G01X1525065Y435061D01*
G03X1525097Y435170I-168J109D01*
G01Y435271D01*
G03X1525064Y435381I-200J0D01*
G01X1524287Y436566D01*
G02X1524283Y436574I176J93D01*
G01X1524278Y436582D01*
X1524256Y436616D01*
Y436650D01*
X1524255Y436660D01*
G02X1524254Y436676I199J20D01*
G01Y437572D01*
G02X1524458Y437776I204J0D01*
G37*
G36*
G01X1567988Y433236D02*
Y437198D01*
G02X1568190Y437400I202J0D01*
G01X1572840D01*
G02X1573042Y437198I0J-202D01*
G01Y433236D01*
G02X1572840Y433034I-202J0D01*
G01X1568190D01*
G02X1567988Y433236I0J202D01*
G37*
G36*
G01Y440322D02*
Y444284D01*
G02X1568190Y444486I202J0D01*
G01X1572840D01*
G02X1573042Y444284I0J-202D01*
G01Y440322D01*
G02X1572840Y440120I-202J0D01*
G01X1568190D01*
G02X1567988Y440322I0J202D01*
G37*
G36*
G01X1568190Y430314D02*
X1572840D01*
G02X1573042Y430111I-1J-203D01*
G01Y426148D01*
G02X1572840Y425946I-202J0D01*
G01X1568190D01*
G02X1567988Y426149I1J203D01*
G01Y430112D01*
G02X1568190Y430314I202J0D01*
G37*
G36*
G01X1567988Y419062D02*
Y423024D01*
G02X1568190Y423226I202J0D01*
G01X1572840D01*
G02X1573042Y423024I0J-202D01*
G01Y419062D01*
G02X1572840Y418860I-202J0D01*
G01X1568190D01*
G02X1567988Y419062I0J202D01*
G37*
G36*
G01Y411976D02*
Y415938D01*
G02X1568190Y416140I202J0D01*
G01X1572840D01*
G02X1573042Y415938I0J-202D01*
G01Y411976D01*
G02X1572840Y411774I-202J0D01*
G01X1568190D01*
G02X1567988Y411976I0J202D01*
G37*
G36*
G01Y404890D02*
Y408852D01*
G02X1568190Y409054I202J0D01*
G01X1572840D01*
G02X1573042Y408852I0J-202D01*
G01Y404890D01*
G02X1572840Y404688I-202J0D01*
G01X1568190D01*
G02X1567988Y404890I0J202D01*
G37*
G36*
G01Y390716D02*
Y394678D01*
G02X1568190Y394880I202J0D01*
G01X1572840D01*
G02X1573042Y394678I0J-202D01*
G01Y390716D01*
G02X1572840Y390514I-202J0D01*
G01X1568190D01*
G02X1567988Y390716I0J202D01*
G37*
G36*
G01X1568190Y401968D02*
X1572840D01*
G02X1573042Y401765I-1J-203D01*
G01Y397802D01*
G02X1572840Y397600I-202J0D01*
G01X1568190D01*
G02X1567988Y397803I1J203D01*
G01Y401766D01*
G02X1568190Y401968I202J0D01*
G37*
G36*
G01X1620724Y136244D02*
Y132182D01*
G02X1620522Y131980I-202J0D01*
G01X1615672D01*
G02X1615470Y132182I0J202D01*
G01Y136244D01*
G02X1615672Y136446I202J0D01*
G01X1620522D01*
G02X1620724Y136244I0J-202D01*
G37*
G36*
G01X1620522Y124892D02*
X1615672D01*
G02X1615470Y125095I1J203D01*
G01Y129158D01*
G02X1615672Y129360I202J0D01*
G01X1620522D01*
G02X1620724Y129157I-1J-203D01*
G01Y125094D01*
G02X1620522Y124892I-202J0D01*
G37*
G36*
G01Y117806D02*
X1615672D01*
G02X1615470Y118009I1J203D01*
G01Y122072D01*
G02X1615672Y122274I202J0D01*
G01X1620522D01*
G02X1620724Y122071I-1J-203D01*
G01Y118008D01*
G02X1620522Y117806I-202J0D01*
G37*
G36*
G01X1620724Y114984D02*
Y110922D01*
G02X1620522Y110720I-202J0D01*
G01X1615672D01*
G02X1615470Y110922I0J202D01*
G01Y114984D01*
G02X1615672Y115186I202J0D01*
G01X1620522D01*
G02X1620724Y114984I0J-202D01*
G37*
G36*
G01X1639162Y467054D02*
Y471016D01*
G02X1639365Y471218I203J-1D01*
G01X1644016D01*
G02X1644218Y471016I0J-202D01*
G01Y467054D01*
G02X1644015Y466852I-203J1D01*
G01X1639364D01*
G02X1639162Y467054I0J202D01*
G37*
G36*
G01X1644218Y478103D02*
Y474141D01*
G02X1644015Y473938I-203J0D01*
G01X1639365D01*
G02X1639162Y474141I0J203D01*
G01Y478103D01*
G02X1639365Y478306I203J0D01*
G01X1644015D01*
G02X1644218Y478103I0J-203D01*
G37*
G36*
G01X1723086Y136244D02*
Y132182D01*
G02X1722884Y131980I-202J0D01*
G01X1718034D01*
G02X1717832Y132182I0J202D01*
G01Y136244D01*
G02X1718034Y136446I202J0D01*
G01X1722884D01*
G02X1723086Y136244I0J-202D01*
G37*
G36*
G01X1722884Y124892D02*
X1718034D01*
G02X1717832Y125095I1J203D01*
G01Y129158D01*
G02X1718034Y129360I202J0D01*
G01X1722884D01*
G02X1723086Y129157I-1J-203D01*
G01Y125094D01*
G02X1722884Y124892I-202J0D01*
G37*
G36*
G01Y117806D02*
X1718034D01*
G02X1717832Y118009I1J203D01*
G01Y122072D01*
G02X1718034Y122274I202J0D01*
G01X1722884D01*
G02X1723086Y122071I-1J-203D01*
G01Y118008D01*
G02X1722884Y117806I-202J0D01*
G37*
G36*
G01X1723086Y114984D02*
Y110922D01*
G02X1722884Y110720I-202J0D01*
G01X1718034D01*
G02X1717832Y110922I0J202D01*
G01Y114984D01*
G02X1718034Y115186I202J0D01*
G01X1722884D01*
G02X1723086Y114984I0J-202D01*
G37*
G36*
G01X153198Y539060D02*
X156099D01*
G02X156302Y538857I0J-203D01*
G01Y537956D01*
G02X156301Y537940I-200J4D01*
G01X156300Y537930D01*
Y537896D01*
X156278Y537862D01*
X156273Y537854D01*
G02X156269Y537846I-180J85D01*
G01X155459Y536612D01*
G03Y536392I167J-110D01*
G01X156269Y535153D01*
G02X156274Y535145I-167J-110D01*
G01X156277Y535140D01*
X156300Y535103D01*
Y535069D01*
X156301Y535059D01*
G02X156302Y535043I-199J-20D01*
G01Y534147D01*
G02X156098Y533944I-204J1D01*
G01X153197D01*
G02X152994Y534147I0J203D01*
G01Y535045D01*
G02X152995Y535061I200J-4D01*
G01X152996Y535071D01*
Y535103D01*
X153012Y535129D01*
X153016Y535136D01*
X153017Y535138D01*
G02X153026Y535153I176J-95D01*
G01X153805Y536346D01*
G03X153837Y536455I-168J109D01*
G01Y536556D01*
G03X153804Y536666I-200J0D01*
G01X153027Y537851D01*
G02X153023Y537859I176J93D01*
G01X153018Y537867D01*
X152996Y537901D01*
Y537935D01*
X152995Y537945D01*
G02X152994Y537961I199J20D01*
G01Y538857D01*
G02X153198Y539060I204J-1D01*
G37*
G36*
G01Y524888D02*
X156098D01*
G02X156302Y524684I0J-204D01*
G01Y523783D01*
G02X156301Y523767I-200J4D01*
G01X156300Y523757D01*
Y523723D01*
X156278Y523689D01*
X156273Y523681D01*
G02X156269Y523673I-180J85D01*
G01X155459Y522439D01*
G03Y522219I167J-110D01*
G01X156269Y520980D01*
G02X156274Y520972I-167J-110D01*
G01X156277Y520967D01*
X156300Y520930D01*
Y520896D01*
X156301Y520886D01*
G02X156302Y520870I-199J-20D01*
G01Y519974D01*
G02X156098Y519770I-204J0D01*
G01X153198D01*
G02X152994Y519974I0J204D01*
G01Y520872D01*
G02X152995Y520888I200J-4D01*
G01X152996Y520898D01*
Y520930D01*
X153012Y520956D01*
X153016Y520963D01*
X153017Y520965D01*
G02X153026Y520980I176J-95D01*
G01X153805Y522173D01*
G03X153837Y522282I-168J109D01*
G01Y522383D01*
G03X153804Y522493I-200J0D01*
G01X153027Y523678D01*
G02X153023Y523686I176J93D01*
G01X153018Y523694D01*
X152996Y523728D01*
Y523762D01*
X152995Y523772D01*
G02X152994Y523788I199J20D01*
G01Y524684D01*
G02X153198Y524888I204J0D01*
G37*
G36*
G01X142796Y517776D02*
X145696D01*
G02X145900Y517572I0J-204D01*
G01Y516671D01*
G02X145899Y516655I-200J4D01*
G01X145898Y516645D01*
Y516611D01*
X145876Y516577D01*
X145871Y516569D01*
G02X145867Y516561I-180J85D01*
G01X145057Y515327D01*
G03Y515107I167J-110D01*
G01X145867Y513868D01*
G02X145872Y513860I-167J-110D01*
G01X145875Y513855D01*
X145898Y513818D01*
Y513784D01*
X145899Y513774D01*
G02X145900Y513758I-199J-20D01*
G01Y512862D01*
G02X145696Y512658I-204J0D01*
G01X142796D01*
G02X142592Y512862I0J204D01*
G01Y513760D01*
G02X142593Y513776I200J-4D01*
G01X142594Y513786D01*
Y513818D01*
X142610Y513844D01*
X142614Y513851D01*
X142615Y513853D01*
G02X142624Y513868I176J-95D01*
G01X143403Y515061D01*
G03X143435Y515170I-168J109D01*
G01Y515271D01*
G03X143402Y515381I-200J0D01*
G01X142625Y516566D01*
G02X142621Y516574I176J93D01*
G01X142616Y516582D01*
X142594Y516616D01*
Y516650D01*
X142593Y516660D01*
G02X142592Y516676I199J20D01*
G01Y517572D01*
G02X142796Y517776I204J0D01*
G37*
G36*
G01Y487814D02*
X145697D01*
G02X145900Y487611I0J-203D01*
G01Y486710D01*
G02X145899Y486694I-200J4D01*
G01X145898Y486684D01*
Y486650D01*
X145876Y486616D01*
X145871Y486608D01*
G02X145867Y486600I-180J85D01*
G01X145057Y485366D01*
G03Y485146I167J-110D01*
G01X145867Y483907D01*
G02X145872Y483899I-167J-110D01*
G01X145875Y483894D01*
X145898Y483857D01*
Y483823D01*
X145899Y483813D01*
G02X145900Y483797I-199J-20D01*
G01Y482901D01*
G02X145696Y482698I-204J1D01*
G01X142795D01*
G02X142592Y482901I0J203D01*
G01Y483799D01*
G02X142593Y483815I200J-4D01*
G01X142594Y483825D01*
Y483857D01*
X142610Y483883D01*
X142614Y483890D01*
X142615Y483892D01*
G02X142624Y483907I176J-95D01*
G01X143435Y485150D01*
G03X143460Y485314I-167J109D01*
G01X143451Y485346D01*
X142625Y486605D01*
G02X142621Y486613I176J93D01*
G01X142616Y486621D01*
X142594Y486655D01*
Y486689D01*
X142593Y486699D01*
G02X142592Y486715I199J20D01*
G01Y487611D01*
G02X142796Y487814I204J-1D01*
G37*
G36*
G01X153198Y494928D02*
X156098D01*
G02X156302Y494724I0J-204D01*
G01Y493823D01*
G02X156301Y493807I-200J4D01*
G01X156300Y493797D01*
Y493763D01*
X156278Y493729D01*
X156273Y493721D01*
G02X156269Y493713I-180J85D01*
G01X155459Y492479D01*
G03Y492259I167J-110D01*
G01X156269Y491020D01*
G02X156274Y491012I-167J-110D01*
G01X156277Y491007D01*
X156300Y490970D01*
Y490936D01*
X156301Y490926D01*
G02X156302Y490910I-199J-20D01*
G01Y490014D01*
G02X156098Y489810I-204J0D01*
G01X153198D01*
G02X152994Y490014I0J204D01*
G01Y490912D01*
G02X152995Y490928I200J-4D01*
G01X152996Y490938D01*
Y490970D01*
X153012Y490996D01*
X153016Y491003D01*
X153017Y491005D01*
G02X153026Y491020I176J-95D01*
G01X153805Y492213D01*
G03X153837Y492322I-168J109D01*
G01Y492423D01*
G03X153804Y492533I-200J0D01*
G01X153027Y493718D01*
G02X153023Y493726I176J93D01*
G01X153018Y493734D01*
X152996Y493768D01*
Y493802D01*
X152995Y493812D01*
G02X152994Y493828I199J20D01*
G01Y494724D01*
G02X153198Y494928I204J0D01*
G37*
G36*
G01X142796Y531948D02*
X145697D01*
G02X145900Y531745I0J-203D01*
G01Y530844D01*
G02X145899Y530828I-200J4D01*
G01X145898Y530818D01*
Y530784D01*
X145876Y530750D01*
X145871Y530742D01*
G02X145867Y530734I-180J85D01*
G01X145057Y529500D01*
G03Y529280I167J-110D01*
G01X145867Y528041D01*
G02X145872Y528033I-167J-110D01*
G01X145875Y528028D01*
X145898Y527991D01*
Y527957D01*
X145899Y527947D01*
G02X145900Y527931I-199J-20D01*
G01Y527035D01*
G02X145696Y526832I-204J1D01*
G01X142795D01*
G02X142592Y527035I0J203D01*
G01Y527933D01*
G02X142593Y527949I200J-4D01*
G01X142594Y527959D01*
Y527991D01*
X142610Y528017D01*
X142614Y528024D01*
X142615Y528026D01*
G02X142624Y528041I176J-95D01*
G01X143403Y529234D01*
G03X143435Y529343I-168J109D01*
G01Y529444D01*
G03X143402Y529554I-200J0D01*
G01X142625Y530739D01*
G02X142621Y530747I176J93D01*
G01X142616Y530755D01*
X142594Y530789D01*
Y530823D01*
X142593Y530833D01*
G02X142592Y530849I199J20D01*
G01Y531745D01*
G02X142796Y531948I204J-1D01*
G37*
G36*
G01X196728Y483276D02*
Y487238D01*
G02X196930Y487440I202J0D01*
G01X201580D01*
G02X201782Y487238I0J-202D01*
G01Y483276D01*
G02X201580Y483074I-202J0D01*
G01X196930D01*
G02X196728Y483276I0J202D01*
G37*
G36*
G01Y490362D02*
Y494324D01*
G02X196930Y494526I202J0D01*
G01X201580D01*
G02X201782Y494324I0J-202D01*
G01Y490362D01*
G02X201580Y490160I-202J0D01*
G01X196930D01*
G02X196728Y490362I0J202D01*
G37*
G36*
G01Y534496D02*
Y538458D01*
G02X196930Y538660I202J0D01*
G01X201580D01*
G02X201782Y538458I0J-202D01*
G01Y534496D01*
G02X201580Y534294I-202J0D01*
G01X196930D01*
G02X196728Y534496I0J202D01*
G37*
G36*
G01Y527410D02*
Y531372D01*
G02X196930Y531574I202J0D01*
G01X201580D01*
G02X201782Y531372I0J-202D01*
G01Y527410D01*
G02X201580Y527208I-202J0D01*
G01X196930D01*
G02X196728Y527410I0J202D01*
G37*
G36*
G01X196930Y524488D02*
X201580D01*
G02X201782Y524285I-1J-203D01*
G01Y520322D01*
G02X201580Y520120I-202J0D01*
G01X196930D01*
G02X196728Y520323I1J203D01*
G01Y524286D01*
G02X196930Y524488I202J0D01*
G37*
G36*
G01X196728Y513236D02*
Y517198D01*
G02X196930Y517400I202J0D01*
G01X201580D01*
G02X201782Y517198I0J-202D01*
G01Y513236D01*
G02X201580Y513034I-202J0D01*
G01X196930D01*
G02X196728Y513236I0J202D01*
G37*
G36*
G01X267902Y511188D02*
Y515150D01*
G02X268105Y515352I203J-1D01*
G01X272756D01*
G02X272958Y515150I0J-202D01*
G01Y511188D01*
G02X272755Y510986I-203J1D01*
G01X268104D01*
G02X267902Y511188I0J202D01*
G37*
G36*
G01Y610834D02*
Y614796D01*
G02X268105Y614998I203J-1D01*
G01X272756D01*
G02X272958Y614796I0J-202D01*
G01Y610834D01*
G02X272755Y610632I-203J1D01*
G01X268104D01*
G02X267902Y610834I0J202D01*
G37*
G36*
G01Y589574D02*
Y593536D01*
G02X268105Y593738I203J-1D01*
G01X272756D01*
G02X272958Y593536I0J-202D01*
G01Y589574D01*
G02X272755Y589372I-203J1D01*
G01X268104D01*
G02X267902Y589574I0J202D01*
G37*
G36*
G01X272958Y600623D02*
Y596661D01*
G02X272755Y596458I-203J0D01*
G01X268105D01*
G02X267902Y596661I0J203D01*
G01Y600623D01*
G02X268105Y600826I203J0D01*
G01X272755D01*
G02X272958Y600623I0J-203D01*
G37*
G36*
G01X267902Y603748D02*
Y607710D01*
G02X268105Y607912I203J-1D01*
G01X272756D01*
G02X272958Y607710I0J-202D01*
G01Y603748D01*
G02X272755Y603546I-203J1D01*
G01X268104D01*
G02X267902Y603748I0J202D01*
G37*
G36*
G01X272958Y579363D02*
Y575401D01*
G02X272755Y575198I-203J0D01*
G01X268105D01*
G02X267902Y575401I0J203D01*
G01Y579363D01*
G02X268105Y579566I203J0D01*
G01X272755D01*
G02X272958Y579363I0J-203D01*
G37*
G36*
G01X267902Y582488D02*
Y586450D01*
G02X268105Y586652I203J-1D01*
G01X272756D01*
G02X272958Y586450I0J-202D01*
G01Y582488D01*
G02X272755Y582286I-203J1D01*
G01X268104D01*
G02X267902Y582488I0J202D01*
G37*
G36*
G01Y561228D02*
Y565190D01*
G02X268105Y565392I203J-1D01*
G01X272756D01*
G02X272958Y565190I0J-202D01*
G01Y561228D01*
G02X272755Y561026I-203J1D01*
G01X268104D01*
G02X267902Y561228I0J202D01*
G37*
G36*
G01Y568314D02*
Y572276D01*
G02X268105Y572478I203J-1D01*
G01X272756D01*
G02X272958Y572276I0J-202D01*
G01Y568314D01*
G02X272755Y568112I-203J1D01*
G01X268104D01*
G02X267902Y568314I0J202D01*
G37*
G36*
G01X272958Y522237D02*
Y518275D01*
G02X272755Y518072I-203J0D01*
G01X268105D01*
G02X267902Y518275I0J203D01*
G01Y522237D01*
G02X268105Y522440I203J0D01*
G01X272755D01*
G02X272958Y522237I0J-203D01*
G37*
G36*
G01X267902Y525362D02*
Y529324D01*
G02X268105Y529526I203J-1D01*
G01X272756D01*
G02X272958Y529324I0J-202D01*
G01Y525362D01*
G02X272755Y525160I-203J1D01*
G01X268104D01*
G02X267902Y525362I0J202D01*
G37*
G36*
G01Y532448D02*
Y536410D01*
G02X268105Y536612I203J-1D01*
G01X272756D01*
G02X272958Y536410I0J-202D01*
G01Y532448D01*
G02X272755Y532246I-203J1D01*
G01X268104D01*
G02X267902Y532448I0J202D01*
G37*
G36*
G01X610284Y539060D02*
X613185D01*
G02X613388Y538857I0J-203D01*
G01Y537956D01*
G02X613387Y537940I-200J4D01*
G01X613386Y537930D01*
Y537896D01*
X613364Y537862D01*
X613359Y537854D01*
G02X613355Y537846I-180J85D01*
G01X612545Y536612D01*
G03Y536392I167J-110D01*
G01X613355Y535153D01*
G02X613360Y535145I-167J-110D01*
G01X613363Y535140D01*
X613386Y535103D01*
Y535069D01*
X613387Y535059D01*
G02X613388Y535043I-199J-20D01*
G01Y534147D01*
G02X613184Y533944I-204J1D01*
G01X610283D01*
G02X610080Y534147I0J203D01*
G01Y535045D01*
G02X610081Y535061I200J-4D01*
G01X610082Y535071D01*
Y535103D01*
X610098Y535129D01*
X610102Y535136D01*
X610103Y535138D01*
G02X610112Y535153I176J-95D01*
G01X610891Y536346D01*
G03X610923Y536455I-168J109D01*
G01Y536556D01*
G03X610890Y536666I-200J0D01*
G01X610113Y537851D01*
G02X610109Y537859I176J93D01*
G01X610104Y537867D01*
X610082Y537901D01*
Y537935D01*
X610081Y537945D01*
G02X610080Y537961I199J20D01*
G01Y538857D01*
G02X610284Y539060I204J-1D01*
G37*
G36*
G01X599882Y531948D02*
X602783D01*
G02X602986Y531745I0J-203D01*
G01Y530844D01*
G02X602985Y530828I-200J4D01*
G01X602984Y530818D01*
Y530784D01*
X602962Y530750D01*
X602957Y530742D01*
G02X602953Y530734I-180J85D01*
G01X602143Y529500D01*
G03Y529280I167J-110D01*
G01X602953Y528041D01*
G02X602958Y528033I-167J-110D01*
G01X602961Y528028D01*
X602984Y527991D01*
Y527957D01*
X602985Y527947D01*
G02X602986Y527931I-199J-20D01*
G01Y527035D01*
G02X602782Y526832I-204J1D01*
G01X599881D01*
G02X599678Y527035I0J203D01*
G01Y527933D01*
G02X599679Y527949I200J-4D01*
G01X599680Y527959D01*
Y527991D01*
X599696Y528017D01*
X599700Y528024D01*
X599701Y528026D01*
G02X599710Y528041I176J-95D01*
G01X600489Y529234D01*
G03X600521Y529343I-168J109D01*
G01Y529444D01*
G03X600488Y529554I-200J0D01*
G01X599711Y530739D01*
G02X599707Y530747I176J93D01*
G01X599702Y530755D01*
X599680Y530789D01*
Y530823D01*
X599679Y530833D01*
G02X599678Y530849I199J20D01*
G01Y531745D01*
G02X599882Y531948I204J-1D01*
G37*
G36*
G01Y517776D02*
X602782D01*
G02X602986Y517572I0J-204D01*
G01Y516671D01*
G02X602985Y516655I-200J4D01*
G01X602984Y516645D01*
Y516611D01*
X602962Y516577D01*
X602957Y516569D01*
G02X602953Y516561I-180J85D01*
G01X602143Y515327D01*
G03Y515107I167J-110D01*
G01X602953Y513868D01*
G02X602958Y513860I-167J-110D01*
G01X602961Y513855D01*
X602984Y513818D01*
Y513784D01*
X602985Y513774D01*
G02X602986Y513758I-199J-20D01*
G01Y512862D01*
G02X602782Y512658I-204J0D01*
G01X599882D01*
G02X599678Y512862I0J204D01*
G01Y513760D01*
G02X599679Y513776I200J-4D01*
G01X599680Y513786D01*
Y513818D01*
X599696Y513844D01*
X599700Y513851D01*
X599701Y513853D01*
G02X599710Y513868I176J-95D01*
G01X600489Y515061D01*
G03X600521Y515170I-168J109D01*
G01Y515271D01*
G03X600488Y515381I-200J0D01*
G01X599711Y516566D01*
G02X599707Y516574I176J93D01*
G01X599702Y516582D01*
X599680Y516616D01*
Y516650D01*
X599679Y516660D01*
G02X599678Y516676I199J20D01*
G01Y517572D01*
G02X599882Y517776I204J0D01*
G37*
G36*
G01X610284Y524888D02*
X613184D01*
G02X613388Y524684I0J-204D01*
G01Y523783D01*
G02X613387Y523767I-200J4D01*
G01X613386Y523757D01*
Y523723D01*
X613364Y523689D01*
X613359Y523681D01*
G02X613355Y523673I-180J85D01*
G01X612545Y522439D01*
G03Y522219I167J-110D01*
G01X613355Y520980D01*
G02X613360Y520972I-167J-110D01*
G01X613363Y520967D01*
X613386Y520930D01*
Y520896D01*
X613387Y520886D01*
G02X613388Y520870I-199J-20D01*
G01Y519974D01*
G02X613184Y519770I-204J0D01*
G01X610284D01*
G02X610080Y519974I0J204D01*
G01Y520872D01*
G02X610081Y520888I200J-4D01*
G01X610082Y520898D01*
Y520930D01*
X610098Y520956D01*
X610102Y520963D01*
X610103Y520965D01*
G02X610112Y520980I176J-95D01*
G01X610891Y522173D01*
G03X610923Y522282I-168J109D01*
G01Y522383D01*
G03X610890Y522493I-200J0D01*
G01X610113Y523678D01*
G02X610109Y523686I176J93D01*
G01X610104Y523694D01*
X610082Y523728D01*
Y523762D01*
X610081Y523772D01*
G02X610080Y523788I199J20D01*
G01Y524684D01*
G02X610284Y524888I204J0D01*
G37*
G36*
G01X599882Y487814D02*
X602783D01*
G02X602986Y487611I0J-203D01*
G01Y486710D01*
G02X602985Y486694I-200J4D01*
G01X602984Y486684D01*
Y486650D01*
X602962Y486616D01*
X602957Y486608D01*
G02X602953Y486600I-180J85D01*
G01X602143Y485366D01*
G03Y485146I167J-110D01*
G01X602953Y483907D01*
G02X602958Y483899I-167J-110D01*
G01X602961Y483894D01*
X602984Y483857D01*
Y483823D01*
X602985Y483813D01*
G02X602986Y483797I-199J-20D01*
G01Y482901D01*
G02X602782Y482698I-204J1D01*
G01X599881D01*
G02X599678Y482901I0J203D01*
G01Y483799D01*
G02X599679Y483815I200J-4D01*
G01X599680Y483825D01*
Y483857D01*
X599696Y483883D01*
X599700Y483890D01*
X599701Y483892D01*
G02X599710Y483907I176J-95D01*
G01X600489Y485100D01*
G03X600521Y485209I-168J109D01*
G01Y485310D01*
G03X600488Y485420I-200J0D01*
G01X599711Y486605D01*
G02X599707Y486613I176J93D01*
G01X599702Y486621D01*
X599680Y486655D01*
Y486689D01*
X599679Y486699D01*
G02X599678Y486715I199J20D01*
G01Y487611D01*
G02X599882Y487814I204J-1D01*
G37*
G36*
G01X653814Y534496D02*
Y538458D01*
G02X654016Y538660I202J0D01*
G01X658666D01*
G02X658868Y538458I0J-202D01*
G01Y534496D01*
G02X658666Y534294I-202J0D01*
G01X654016D01*
G02X653814Y534496I0J202D01*
G37*
G36*
G01Y513236D02*
Y517198D01*
G02X654016Y517400I202J0D01*
G01X658666D01*
G02X658868Y517198I0J-202D01*
G01Y513236D01*
G02X658666Y513034I-202J0D01*
G01X654016D01*
G02X653814Y513236I0J202D01*
G37*
G36*
G01X654016Y524488D02*
X658666D01*
G02X658868Y524285I-1J-203D01*
G01Y520322D01*
G02X658666Y520120I-202J0D01*
G01X654016D01*
G02X653814Y520323I1J203D01*
G01Y524286D01*
G02X654016Y524488I202J0D01*
G37*
G36*
G01X653814Y527410D02*
Y531372D01*
G02X654016Y531574I202J0D01*
G01X658666D01*
G02X658868Y531372I0J-202D01*
G01Y527410D01*
G02X658666Y527208I-202J0D01*
G01X654016D01*
G02X653814Y527410I0J202D01*
G37*
G36*
G01Y483276D02*
Y487238D01*
G02X654016Y487440I202J0D01*
G01X658666D01*
G02X658868Y487238I0J-202D01*
G01Y483276D01*
G02X658666Y483074I-202J0D01*
G01X654016D01*
G02X653814Y483276I0J202D01*
G37*
G36*
G01Y490362D02*
Y494324D01*
G02X654016Y494526I202J0D01*
G01X658666D01*
G02X658868Y494324I0J-202D01*
G01Y490362D01*
G02X658666Y490160I-202J0D01*
G01X654016D01*
G02X653814Y490362I0J202D01*
G37*
G36*
G01X730044Y600623D02*
Y596661D01*
G02X729841Y596458I-203J0D01*
G01X725191D01*
G02X724988Y596661I0J203D01*
G01Y600623D01*
G02X725191Y600826I203J0D01*
G01X729841D01*
G02X730044Y600623I0J-203D01*
G37*
G36*
G01X724988Y589574D02*
Y593536D01*
G02X725191Y593738I203J-1D01*
G01X729842D01*
G02X730044Y593536I0J-202D01*
G01Y589574D01*
G02X729841Y589372I-203J1D01*
G01X725190D01*
G02X724988Y589574I0J202D01*
G37*
G36*
G01Y582488D02*
Y586450D01*
G02X725191Y586652I203J-1D01*
G01X729842D01*
G02X730044Y586450I0J-202D01*
G01Y582488D01*
G02X729841Y582286I-203J1D01*
G01X725190D01*
G02X724988Y582488I0J202D01*
G37*
G36*
G01X730044Y579363D02*
Y575401D01*
G02X729841Y575198I-203J0D01*
G01X725191D01*
G02X724988Y575401I0J203D01*
G01Y579363D01*
G02X725191Y579566I203J0D01*
G01X729841D01*
G02X730044Y579363I0J-203D01*
G37*
G36*
G01X724988Y568314D02*
Y572276D01*
G02X725191Y572478I203J-1D01*
G01X729842D01*
G02X730044Y572276I0J-202D01*
G01Y568314D01*
G02X729841Y568112I-203J1D01*
G01X725190D01*
G02X724988Y568314I0J202D01*
G37*
G36*
G01Y561228D02*
Y565190D01*
G02X725191Y565392I203J-1D01*
G01X729842D01*
G02X730044Y565190I0J-202D01*
G01Y561228D01*
G02X729841Y561026I-203J1D01*
G01X725190D01*
G02X724988Y561228I0J202D01*
G37*
G36*
G01Y532448D02*
Y536410D01*
G02X725191Y536612I203J-1D01*
G01X729842D01*
G02X730044Y536410I0J-202D01*
G01Y532448D01*
G02X729841Y532246I-203J1D01*
G01X725190D01*
G02X724988Y532448I0J202D01*
G37*
G36*
G01Y525362D02*
Y529324D01*
G02X725191Y529526I203J-1D01*
G01X729842D01*
G02X730044Y529324I0J-202D01*
G01Y525362D01*
G02X729841Y525160I-203J1D01*
G01X725190D01*
G02X724988Y525362I0J202D01*
G37*
G36*
G01X730044Y522237D02*
Y518275D01*
G02X729841Y518072I-203J0D01*
G01X725191D01*
G02X724988Y518275I0J203D01*
G01Y522237D01*
G02X725191Y522440I203J0D01*
G01X729841D01*
G02X730044Y522237I0J-203D01*
G37*
G36*
G01X724988Y511188D02*
Y515150D01*
G02X725191Y515352I203J-1D01*
G01X729842D01*
G02X730044Y515150I0J-202D01*
G01Y511188D01*
G02X729841Y510986I-203J1D01*
G01X725190D01*
G02X724988Y511188I0J202D01*
G37*
G36*
G01Y603748D02*
Y607710D01*
G02X725191Y607912I203J-1D01*
G01X729842D01*
G02X730044Y607710I0J-202D01*
G01Y603748D01*
G02X729841Y603546I-203J1D01*
G01X725190D01*
G02X724988Y603748I0J202D01*
G37*
G36*
G01Y610834D02*
Y614796D01*
G02X725191Y614998I203J-1D01*
G01X729842D01*
G02X730044Y614796I0J-202D01*
G01Y610834D01*
G02X729841Y610632I-203J1D01*
G01X725190D01*
G02X724988Y610834I0J202D01*
G37*
G36*
G01X1115956Y538458D02*
Y534496D01*
G02X1115753Y534294I-203J1D01*
G01X1111102D01*
G02X1110900Y534496I0J202D01*
G01Y538458D01*
G02X1111103Y538660I203J-1D01*
G01X1115754D01*
G02X1115956Y538458I0J-202D01*
G37*
G36*
G01Y531372D02*
Y527410D01*
G02X1115753Y527208I-203J1D01*
G01X1111102D01*
G02X1110900Y527410I0J202D01*
G01Y531372D01*
G02X1111103Y531574I203J-1D01*
G01X1115754D01*
G02X1115956Y531372I0J-202D01*
G37*
G36*
G01Y517198D02*
Y513236D01*
G02X1115753Y513034I-203J1D01*
G01X1111102D01*
G02X1110900Y513236I0J202D01*
G01Y517198D01*
G02X1111103Y517400I203J-1D01*
G01X1115754D01*
G02X1115956Y517198I0J-202D01*
G37*
G36*
G01X1110900Y520323D02*
Y524285D01*
G02X1111103Y524488I203J0D01*
G01X1115753D01*
G02X1115956Y524285I0J-203D01*
G01Y520323D01*
G02X1115753Y520120I-203J0D01*
G01X1111103D01*
G02X1110900Y520323I0J203D01*
G37*
G36*
G01X1115956Y487238D02*
Y483276D01*
G02X1115753Y483074I-203J1D01*
G01X1111102D01*
G02X1110900Y483276I0J202D01*
G01Y487238D01*
G02X1111103Y487440I203J-1D01*
G01X1115754D01*
G02X1115956Y487238I0J-202D01*
G37*
G36*
G01Y494324D02*
Y490362D01*
G02X1115753Y490160I-203J1D01*
G01X1111102D01*
G02X1110900Y490362I0J202D01*
G01Y494324D01*
G02X1111103Y494526I203J-1D01*
G01X1115754D01*
G02X1115956Y494324I0J-202D01*
G37*
G36*
G01X1187130Y572276D02*
Y568314D01*
G02X1186928Y568112I-202J0D01*
G01X1182278D01*
G02X1182076Y568314I0J202D01*
G01Y572276D01*
G02X1182278Y572478I202J0D01*
G01X1186928D01*
G02X1187130Y572276I0J-202D01*
G37*
G36*
G01Y565190D02*
Y561228D01*
G02X1186928Y561026I-202J0D01*
G01X1182278D01*
G02X1182076Y561228I0J202D01*
G01Y565190D01*
G02X1182278Y565392I202J0D01*
G01X1186928D01*
G02X1187130Y565190I0J-202D01*
G37*
G36*
G01Y536410D02*
Y532448D01*
G02X1186928Y532246I-202J0D01*
G01X1182278D01*
G02X1182076Y532448I0J202D01*
G01Y536410D01*
G02X1182278Y536612I202J0D01*
G01X1186928D01*
G02X1187130Y536410I0J-202D01*
G37*
G36*
G01Y529324D02*
Y525362D01*
G02X1186928Y525160I-202J0D01*
G01X1182278D01*
G02X1182076Y525362I0J202D01*
G01Y529324D01*
G02X1182278Y529526I202J0D01*
G01X1186928D01*
G02X1187130Y529324I0J-202D01*
G37*
G36*
G01X1186928Y518072D02*
X1182278D01*
G02X1182076Y518275I1J203D01*
G01Y522238D01*
G02X1182278Y522440I202J0D01*
G01X1186928D01*
G02X1187130Y522237I-1J-203D01*
G01Y518274D01*
G02X1186928Y518072I-202J0D01*
G37*
G36*
G01X1187130Y515150D02*
Y511188D01*
G02X1186928Y510986I-202J0D01*
G01X1182278D01*
G02X1182076Y511188I0J202D01*
G01Y515150D01*
G02X1182278Y515352I202J0D01*
G01X1186928D01*
G02X1187130Y515150I0J-202D01*
G37*
G36*
G01Y614796D02*
Y610834D01*
G02X1186928Y610632I-202J0D01*
G01X1182278D01*
G02X1182076Y610834I0J202D01*
G01Y614796D01*
G02X1182278Y614998I202J0D01*
G01X1186928D01*
G02X1187130Y614796I0J-202D01*
G37*
G36*
G01Y607710D02*
Y603748D01*
G02X1186928Y603546I-202J0D01*
G01X1182278D01*
G02X1182076Y603748I0J202D01*
G01Y607710D01*
G02X1182278Y607912I202J0D01*
G01X1186928D01*
G02X1187130Y607710I0J-202D01*
G37*
G36*
G01X1186928Y596458D02*
X1182278D01*
G02X1182076Y596661I1J203D01*
G01Y600624D01*
G02X1182278Y600826I202J0D01*
G01X1186928D01*
G02X1187130Y600623I-1J-203D01*
G01Y596660D01*
G02X1186928Y596458I-202J0D01*
G37*
G36*
G01X1187130Y593536D02*
Y589574D01*
G02X1186928Y589372I-202J0D01*
G01X1182278D01*
G02X1182076Y589574I0J202D01*
G01Y593536D01*
G02X1182278Y593738I202J0D01*
G01X1186928D01*
G02X1187130Y593536I0J-202D01*
G37*
G36*
G01Y586450D02*
Y582488D01*
G02X1186928Y582286I-202J0D01*
G01X1182278D01*
G02X1182076Y582488I0J202D01*
G01Y586450D01*
G02X1182278Y586652I202J0D01*
G01X1186928D01*
G02X1187130Y586450I0J-202D01*
G37*
G36*
G01X1186928Y575198D02*
X1182278D01*
G02X1182076Y575401I1J203D01*
G01Y579364D01*
G02X1182278Y579566I202J0D01*
G01X1186928D01*
G02X1187130Y579363I-1J-203D01*
G01Y575400D01*
G02X1186928Y575198I-202J0D01*
G37*
G36*
G01X1227760Y529868D02*
X1230660D01*
G02X1230864Y529664I0J-204D01*
G01Y528763D01*
G02X1230863Y528747I-200J4D01*
G01X1230862Y528737D01*
Y528703D01*
X1230840Y528669D01*
X1230835Y528661D01*
G02X1230831Y528653I-180J85D01*
G01X1230021Y527419D01*
G03Y527199I167J-110D01*
G01X1230831Y525960D01*
G02X1230836Y525952I-167J-110D01*
G01X1230839Y525947D01*
X1230862Y525910D01*
Y525876D01*
X1230863Y525866D01*
G02X1230864Y525850I-199J-20D01*
G01Y524954D01*
G02X1230660Y524750I-204J0D01*
G01X1227760D01*
G02X1227556Y524954I0J204D01*
G01Y525852D01*
G02X1227557Y525868I200J-4D01*
G01X1227558Y525878D01*
Y525910D01*
X1227574Y525936D01*
X1227578Y525943D01*
X1227579Y525945D01*
G02X1227588Y525960I176J-95D01*
G01X1228367Y527153D01*
G03X1228399Y527262I-168J109D01*
G01Y527363D01*
G03X1228366Y527473I-200J0D01*
G01X1227589Y528658D01*
G02X1227585Y528666I176J93D01*
G01X1227580Y528674D01*
X1227558Y528708D01*
Y528742D01*
X1227557Y528752D01*
G02X1227556Y528768I199J20D01*
G01Y529664D01*
G02X1227760Y529868I204J0D01*
G37*
G36*
G01Y515694D02*
X1230660D01*
G02X1230864Y515490I0J-204D01*
G01Y514589D01*
G02X1230863Y514573I-200J4D01*
G01X1230862Y514563D01*
Y514529D01*
X1230840Y514495D01*
X1230835Y514487D01*
G02X1230831Y514479I-180J85D01*
G01X1230021Y513245D01*
G03Y513025I167J-110D01*
G01X1230831Y511786D01*
G02X1230836Y511778I-167J-110D01*
G01X1230839Y511773D01*
X1230862Y511736D01*
Y511702D01*
X1230863Y511692D01*
G02X1230864Y511676I-199J-20D01*
G01Y510780D01*
G02X1230660Y510576I-204J0D01*
G01X1227760D01*
G02X1227556Y510780I0J204D01*
G01Y511678D01*
G02X1227557Y511694I200J-4D01*
G01X1227558Y511704D01*
Y511736D01*
X1227574Y511762D01*
X1227578Y511769D01*
X1227579Y511771D01*
G02X1227588Y511786I176J-95D01*
G01X1228367Y512979D01*
G03X1228399Y513088I-168J109D01*
G01Y513189D01*
G03X1228366Y513299I-200J0D01*
G01X1227589Y514484D01*
G02X1227585Y514492I176J93D01*
G01X1227580Y514500D01*
X1227558Y514534D01*
Y514568D01*
X1227557Y514578D01*
G02X1227556Y514594I199J20D01*
G01Y515490D01*
G02X1227760Y515694I204J0D01*
G37*
G36*
G01Y608254D02*
X1230660D01*
G02X1230864Y608050I0J-204D01*
G01Y607149D01*
G02X1230863Y607133I-200J4D01*
G01X1230862Y607123D01*
Y607089D01*
X1230840Y607055D01*
X1230835Y607047D01*
G02X1230831Y607039I-180J85D01*
G01X1230021Y605805D01*
G03Y605585I167J-110D01*
G01X1230831Y604346D01*
G02X1230836Y604338I-167J-110D01*
G01X1230839Y604333D01*
X1230862Y604296D01*
Y604262D01*
X1230863Y604252D01*
G02X1230864Y604236I-199J-20D01*
G01Y603340D01*
G02X1230660Y603136I-204J0D01*
G01X1227760D01*
G02X1227556Y603340I0J204D01*
G01Y604238D01*
G02X1227557Y604254I200J-4D01*
G01X1227558Y604264D01*
Y604296D01*
X1227574Y604322D01*
X1227578Y604329D01*
X1227579Y604331D01*
G02X1227588Y604346I176J-95D01*
G01X1228367Y605539D01*
G03X1228399Y605648I-168J109D01*
G01Y605749D01*
G03X1228366Y605859I-200J0D01*
G01X1227589Y607044D01*
G02X1227585Y607052I176J93D01*
G01X1227580Y607060D01*
X1227558Y607094D01*
Y607128D01*
X1227557Y607138D01*
G02X1227556Y607154I199J20D01*
G01Y608050D01*
G02X1227760Y608254I204J0D01*
G37*
G36*
G01Y594080D02*
X1230660D01*
G02X1230864Y593876I0J-204D01*
G01Y592975D01*
G02X1230863Y592959I-200J4D01*
G01X1230862Y592949D01*
Y592915D01*
X1230840Y592881D01*
X1230835Y592873D01*
G02X1230831Y592865I-180J85D01*
G01X1230021Y591631D01*
G03Y591411I167J-110D01*
G01X1230831Y590172D01*
G02X1230836Y590164I-167J-110D01*
G01X1230839Y590159D01*
X1230862Y590122D01*
Y590088D01*
X1230863Y590078D01*
G02X1230864Y590062I-199J-20D01*
G01Y589166D01*
G02X1230660Y588962I-204J0D01*
G01X1227760D01*
G02X1227556Y589166I0J204D01*
G01Y590064D01*
G02X1227557Y590080I200J-4D01*
G01X1227558Y590090D01*
Y590122D01*
X1227574Y590148D01*
X1227578Y590155D01*
X1227579Y590157D01*
G02X1227588Y590172I176J-95D01*
G01X1228367Y591365D01*
G03X1228399Y591474I-168J109D01*
G01Y591575D01*
G03X1228366Y591685I-200J0D01*
G01X1227589Y592870D01*
G02X1227585Y592878I176J93D01*
G01X1227580Y592886D01*
X1227558Y592920D01*
Y592954D01*
X1227557Y592964D01*
G02X1227556Y592980I199J20D01*
G01Y593876D01*
G02X1227760Y594080I204J0D01*
G37*
G36*
G01Y579906D02*
X1230661D01*
G02X1230864Y579703I0J-203D01*
G01Y578802D01*
G02X1230863Y578786I-200J4D01*
G01X1230862Y578776D01*
Y578742D01*
X1230840Y578708D01*
X1230835Y578700D01*
G02X1230831Y578692I-180J85D01*
G01X1230021Y577458D01*
G03Y577238I167J-110D01*
G01X1230831Y575999D01*
G02X1230836Y575991I-167J-110D01*
G01X1230839Y575986D01*
X1230862Y575949D01*
Y575915D01*
X1230863Y575905D01*
G02X1230864Y575889I-199J-20D01*
G01Y574993D01*
G02X1230660Y574790I-204J1D01*
G01X1227759D01*
G02X1227556Y574993I0J203D01*
G01Y575891D01*
G02X1227557Y575907I200J-4D01*
G01X1227558Y575917D01*
Y575949D01*
X1227574Y575975D01*
X1227578Y575982D01*
X1227579Y575984D01*
G02X1227588Y575999I176J-95D01*
G01X1228367Y577192D01*
G03X1228399Y577301I-168J109D01*
G01Y577402D01*
G03X1228366Y577512I-200J0D01*
G01X1227589Y578697D01*
G02X1227585Y578705I176J93D01*
G01X1227580Y578713D01*
X1227558Y578747D01*
Y578781D01*
X1227557Y578791D01*
G02X1227556Y578807I199J20D01*
G01Y579703D01*
G02X1227760Y579906I204J-1D01*
G37*
G36*
G01Y565734D02*
X1230660D01*
G02X1230864Y565530I0J-204D01*
G01Y564629D01*
G02X1230863Y564613I-200J4D01*
G01X1230862Y564603D01*
Y564569D01*
X1230840Y564535D01*
X1230835Y564527D01*
G02X1230831Y564519I-180J85D01*
G01X1230021Y563285D01*
G03Y563065I167J-110D01*
G01X1230831Y561826D01*
G02X1230836Y561818I-167J-110D01*
G01X1230839Y561813D01*
X1230862Y561776D01*
Y561742D01*
X1230863Y561732D01*
G02X1230864Y561716I-199J-20D01*
G01Y560820D01*
G02X1230660Y560616I-204J0D01*
G01X1227760D01*
G02X1227556Y560820I0J204D01*
G01Y561718D01*
G02X1227557Y561734I200J-4D01*
G01X1227558Y561744D01*
Y561776D01*
X1227574Y561802D01*
X1227578Y561809D01*
X1227579Y561811D01*
G02X1227588Y561826I176J-95D01*
G01X1228367Y563019D01*
G03X1228399Y563128I-168J109D01*
G01Y563229D01*
G03X1228366Y563339I-200J0D01*
G01X1227589Y564524D01*
G02X1227585Y564532I176J93D01*
G01X1227580Y564540D01*
X1227558Y564574D01*
Y564608D01*
X1227557Y564618D01*
G02X1227556Y564634I199J20D01*
G01Y565530D01*
G02X1227760Y565734I204J0D01*
G37*
G36*
G01X1238162Y522806D02*
X1241063D01*
G02X1241266Y522603I0J-203D01*
G01Y521702D01*
G02X1241265Y521686I-200J4D01*
G01X1241264Y521676D01*
Y521642D01*
X1241242Y521608D01*
X1241237Y521600D01*
G02X1241233Y521592I-180J85D01*
G01X1240423Y520358D01*
G03Y520138I167J-110D01*
G01X1241233Y518899D01*
G02X1241238Y518891I-167J-110D01*
G01X1241241Y518886D01*
X1241264Y518849D01*
Y518815D01*
X1241265Y518805D01*
G02X1241266Y518789I-199J-20D01*
G01Y517893D01*
G02X1241062Y517690I-204J1D01*
G01X1238161D01*
G02X1237958Y517893I0J203D01*
G01Y518791D01*
G02X1237959Y518807I200J-4D01*
G01X1237960Y518817D01*
Y518849D01*
X1237976Y518875D01*
X1237980Y518882D01*
X1237981Y518884D01*
G02X1237990Y518899I176J-95D01*
G01X1238769Y520092D01*
G03X1238801Y520201I-168J109D01*
G01Y520302D01*
G03X1238768Y520412I-200J0D01*
G01X1237991Y521597D01*
G02X1237987Y521605I176J93D01*
G01X1237982Y521613D01*
X1237960Y521647D01*
Y521681D01*
X1237959Y521691D01*
G02X1237958Y521707I199J20D01*
G01Y522603D01*
G02X1238162Y522806I204J-1D01*
G37*
G36*
G01Y492846D02*
X1241062D01*
G02X1241266Y492642I0J-204D01*
G01Y491741D01*
G02X1241265Y491725I-200J4D01*
G01X1241264Y491715D01*
Y491681D01*
X1241242Y491647D01*
X1241237Y491639D01*
G02X1241233Y491631I-180J85D01*
G01X1240423Y490397D01*
G03Y490177I167J-110D01*
G01X1241233Y488938D01*
G02X1241238Y488930I-167J-110D01*
G01X1241241Y488925D01*
X1241264Y488888D01*
Y488854D01*
X1241265Y488844D01*
G02X1241266Y488828I-199J-20D01*
G01Y487932D01*
G02X1241062Y487728I-204J0D01*
G01X1238162D01*
G02X1237958Y487932I0J204D01*
G01Y488830D01*
G02X1237959Y488846I200J-4D01*
G01X1237960Y488856D01*
Y488888D01*
X1237976Y488914D01*
X1237980Y488921D01*
X1237981Y488923D01*
G02X1237990Y488938I176J-95D01*
G01X1238769Y490131D01*
G03X1238801Y490240I-168J109D01*
G01Y490341D01*
G03X1238768Y490451I-200J0D01*
G01X1237991Y491636D01*
G02X1237987Y491644I176J93D01*
G01X1237982Y491652D01*
X1237960Y491686D01*
Y491720D01*
X1237959Y491730D01*
G02X1237958Y491746I199J20D01*
G01Y492642D01*
G02X1238162Y492846I204J0D01*
G37*
G36*
G01Y615366D02*
X1241062D01*
G02X1241266Y615162I0J-204D01*
G01Y614261D01*
G02X1241265Y614245I-200J4D01*
G01X1241264Y614235D01*
Y614201D01*
X1241242Y614167D01*
X1241237Y614159D01*
G02X1241233Y614151I-180J85D01*
G01X1240423Y612917D01*
G03Y612697I167J-110D01*
G01X1241233Y611458D01*
G02X1241238Y611450I-167J-110D01*
G01X1241241Y611445D01*
X1241264Y611408D01*
Y611374D01*
X1241265Y611364D01*
G02X1241266Y611348I-199J-20D01*
G01Y610452D01*
G02X1241062Y610248I-204J0D01*
G01X1238162D01*
G02X1237958Y610452I0J204D01*
G01Y611350D01*
G02X1237959Y611366I200J-4D01*
G01X1237960Y611376D01*
Y611408D01*
X1237976Y611434D01*
X1237980Y611441D01*
X1237981Y611443D01*
G02X1237990Y611458I176J-95D01*
G01X1238769Y612651D01*
G03X1238801Y612760I-168J109D01*
G01Y612861D01*
G03X1238768Y612971I-200J0D01*
G01X1237991Y614156D01*
G02X1237987Y614164I176J93D01*
G01X1237982Y614172D01*
X1237960Y614206D01*
Y614240D01*
X1237959Y614250D01*
G02X1237958Y614266I199J20D01*
G01Y615162D01*
G02X1238162Y615366I204J0D01*
G37*
G36*
G01Y601192D02*
X1241063D01*
G02X1241266Y600989I0J-203D01*
G01Y600088D01*
G02X1241265Y600072I-200J4D01*
G01X1241264Y600062D01*
Y600028D01*
X1241242Y599994D01*
X1241237Y599986D01*
G02X1241233Y599978I-180J85D01*
G01X1240423Y598744D01*
G03Y598524I167J-110D01*
G01X1241233Y597285D01*
G02X1241238Y597277I-167J-110D01*
G01X1241241Y597272D01*
X1241264Y597235D01*
Y597201D01*
X1241265Y597191D01*
G02X1241266Y597175I-199J-20D01*
G01Y596279D01*
G02X1241062Y596076I-204J1D01*
G01X1238161D01*
G02X1237958Y596279I0J203D01*
G01Y597177D01*
G02X1237959Y597193I200J-4D01*
G01X1237960Y597203D01*
Y597235D01*
X1237976Y597261D01*
X1237980Y597268D01*
X1237981Y597270D01*
G02X1237990Y597285I176J-95D01*
G01X1238769Y598478D01*
G03X1238801Y598587I-168J109D01*
G01Y598688D01*
G03X1238768Y598798I-200J0D01*
G01X1237991Y599983D01*
G02X1237987Y599991I176J93D01*
G01X1237982Y599999D01*
X1237960Y600033D01*
Y600067D01*
X1237959Y600077D01*
G02X1237958Y600093I199J20D01*
G01Y600989D01*
G02X1238162Y601192I204J-1D01*
G37*
G36*
G01Y587020D02*
X1241062D01*
G02X1241266Y586816I0J-204D01*
G01Y585915D01*
G02X1241265Y585899I-200J4D01*
G01X1241264Y585889D01*
Y585855D01*
X1241242Y585821D01*
X1241237Y585813D01*
G02X1241233Y585805I-180J85D01*
G01X1240423Y584571D01*
G03Y584351I167J-110D01*
G01X1241233Y583112D01*
G02X1241238Y583104I-167J-110D01*
G01X1241241Y583099D01*
X1241264Y583062D01*
Y583028D01*
X1241265Y583018D01*
G02X1241266Y583002I-199J-20D01*
G01Y582106D01*
G02X1241062Y581902I-204J0D01*
G01X1238162D01*
G02X1237958Y582106I0J204D01*
G01Y583004D01*
G02X1237959Y583020I200J-4D01*
G01X1237960Y583030D01*
Y583062D01*
X1237976Y583088D01*
X1237980Y583095D01*
X1237981Y583097D01*
G02X1237990Y583112I176J-95D01*
G01X1238769Y584305D01*
G03X1238801Y584414I-168J109D01*
G01Y584515D01*
G03X1238768Y584625I-200J0D01*
G01X1237991Y585810D01*
G02X1237987Y585818I176J93D01*
G01X1237982Y585826D01*
X1237960Y585860D01*
Y585894D01*
X1237959Y585904D01*
G02X1237958Y585920I199J20D01*
G01Y586816D01*
G02X1238162Y587020I204J0D01*
G37*
G36*
G01X1524458Y539060D02*
X1527359D01*
G02X1527562Y538857I0J-203D01*
G01Y537956D01*
G02X1527561Y537940I-200J4D01*
G01X1527560Y537930D01*
Y537896D01*
X1527538Y537862D01*
X1527533Y537854D01*
G02X1527529Y537846I-180J85D01*
G01X1526719Y536612D01*
G03Y536392I167J-110D01*
G01X1527529Y535153D01*
G02X1527534Y535145I-167J-110D01*
G01X1527537Y535140D01*
X1527560Y535103D01*
Y535069D01*
X1527561Y535059D01*
G02X1527562Y535043I-199J-20D01*
G01Y534147D01*
G02X1527358Y533944I-204J1D01*
G01X1524457D01*
G02X1524254Y534147I0J203D01*
G01Y535045D01*
G02X1524255Y535061I200J-4D01*
G01X1524256Y535071D01*
Y535103D01*
X1524272Y535129D01*
X1524276Y535136D01*
X1524277Y535138D01*
G02X1524286Y535153I176J-95D01*
G01X1525065Y536346D01*
G03X1525097Y536455I-168J109D01*
G01Y536556D01*
G03X1525064Y536666I-200J0D01*
G01X1524287Y537851D01*
G02X1524283Y537859I176J93D01*
G01X1524278Y537867D01*
X1524256Y537901D01*
Y537935D01*
X1524255Y537945D01*
G02X1524254Y537961I199J20D01*
G01Y538857D01*
G02X1524458Y539060I204J-1D01*
G37*
G36*
G01X1514056Y531948D02*
X1516957D01*
G02X1517160Y531745I0J-203D01*
G01Y530844D01*
G02X1517159Y530828I-200J4D01*
G01X1517158Y530818D01*
Y530784D01*
X1517136Y530750D01*
X1517131Y530742D01*
G02X1517127Y530734I-180J85D01*
G01X1516317Y529500D01*
G03Y529280I167J-110D01*
G01X1517127Y528041D01*
G02X1517132Y528033I-167J-110D01*
G01X1517135Y528028D01*
X1517158Y527991D01*
Y527957D01*
X1517159Y527947D01*
G02X1517160Y527931I-199J-20D01*
G01Y527035D01*
G02X1516956Y526832I-204J1D01*
G01X1514055D01*
G02X1513852Y527035I0J203D01*
G01Y527933D01*
G02X1513853Y527949I200J-4D01*
G01X1513854Y527959D01*
Y527991D01*
X1513870Y528017D01*
X1513874Y528024D01*
X1513875Y528026D01*
G02X1513884Y528041I176J-95D01*
G01X1514663Y529234D01*
G03X1514695Y529343I-168J109D01*
G01Y529444D01*
G03X1514662Y529554I-200J0D01*
G01X1513885Y530739D01*
G02X1513881Y530747I176J93D01*
G01X1513876Y530755D01*
X1513854Y530789D01*
Y530823D01*
X1513853Y530833D01*
G02X1513852Y530849I199J20D01*
G01Y531745D01*
G02X1514056Y531948I204J-1D01*
G37*
G36*
G01Y517776D02*
X1516956D01*
G02X1517160Y517572I0J-204D01*
G01Y516671D01*
G02X1517159Y516655I-200J4D01*
G01X1517158Y516645D01*
Y516611D01*
X1517136Y516577D01*
X1517131Y516569D01*
G02X1517127Y516561I-180J85D01*
G01X1516317Y515327D01*
G03Y515107I167J-110D01*
G01X1517127Y513868D01*
G02X1517132Y513860I-167J-110D01*
G01X1517135Y513855D01*
X1517158Y513818D01*
Y513784D01*
X1517159Y513774D01*
G02X1517160Y513758I-199J-20D01*
G01Y512862D01*
G02X1516956Y512658I-204J0D01*
G01X1514056D01*
G02X1513852Y512862I0J204D01*
G01Y513760D01*
G02X1513853Y513776I200J-4D01*
G01X1513854Y513786D01*
Y513818D01*
X1513870Y513844D01*
X1513874Y513851D01*
X1513875Y513853D01*
G02X1513884Y513868I176J-95D01*
G01X1514663Y515061D01*
G03X1514695Y515170I-168J109D01*
G01Y515271D01*
G03X1514662Y515381I-200J0D01*
G01X1513885Y516566D01*
G02X1513881Y516574I176J93D01*
G01X1513876Y516582D01*
X1513854Y516616D01*
Y516650D01*
X1513853Y516660D01*
G02X1513852Y516676I199J20D01*
G01Y517572D01*
G02X1514056Y517776I204J0D01*
G37*
G36*
G01X1524458Y524888D02*
X1527358D01*
G02X1527562Y524684I0J-204D01*
G01Y523783D01*
G02X1527561Y523767I-200J4D01*
G01X1527560Y523757D01*
Y523723D01*
X1527538Y523689D01*
X1527533Y523681D01*
G02X1527529Y523673I-180J85D01*
G01X1526719Y522439D01*
G03Y522219I167J-110D01*
G01X1527529Y520980D01*
G02X1527534Y520972I-167J-110D01*
G01X1527537Y520967D01*
X1527560Y520930D01*
Y520896D01*
X1527561Y520886D01*
G02X1527562Y520870I-199J-20D01*
G01Y519974D01*
G02X1527358Y519770I-204J0D01*
G01X1524458D01*
G02X1524254Y519974I0J204D01*
G01Y520872D01*
G02X1524255Y520888I200J-4D01*
G01X1524256Y520898D01*
Y520930D01*
X1524272Y520956D01*
X1524276Y520963D01*
X1524277Y520965D01*
G02X1524286Y520980I176J-95D01*
G01X1525065Y522173D01*
G03X1525097Y522282I-168J109D01*
G01Y522383D01*
G03X1525064Y522493I-200J0D01*
G01X1524287Y523678D01*
G02X1524283Y523686I176J93D01*
G01X1524278Y523694D01*
X1524256Y523728D01*
Y523762D01*
X1524255Y523772D01*
G02X1524254Y523788I199J20D01*
G01Y524684D01*
G02X1524458Y524888I204J0D01*
G37*
G36*
G01Y494928D02*
X1527358D01*
G02X1527562Y494724I0J-204D01*
G01Y493823D01*
G02X1527561Y493807I-200J4D01*
G01X1527560Y493797D01*
Y493763D01*
X1527538Y493729D01*
X1527533Y493721D01*
G02X1527529Y493713I-180J85D01*
G01X1526719Y492479D01*
G03Y492259I167J-110D01*
G01X1527529Y491020D01*
G02X1527534Y491012I-167J-110D01*
G01X1527537Y491007D01*
X1527560Y490970D01*
Y490936D01*
X1527561Y490926D01*
G02X1527562Y490910I-199J-20D01*
G01Y490014D01*
G02X1527358Y489810I-204J0D01*
G01X1524458D01*
G02X1524254Y490014I0J204D01*
G01Y490912D01*
G02X1524255Y490928I200J-4D01*
G01X1524256Y490938D01*
Y490970D01*
X1524272Y490996D01*
X1524276Y491003D01*
X1524277Y491005D01*
G02X1524286Y491020I176J-95D01*
G01X1525065Y492213D01*
G03X1525097Y492322I-168J109D01*
G01Y492423D01*
G03X1525064Y492533I-200J0D01*
G01X1524287Y493718D01*
G02X1524283Y493726I176J93D01*
G01X1524278Y493734D01*
X1524256Y493768D01*
Y493802D01*
X1524255Y493812D01*
G02X1524254Y493828I199J20D01*
G01Y494724D01*
G02X1524458Y494928I204J0D01*
G37*
G36*
G01X1567988Y534496D02*
Y538458D01*
G02X1568190Y538660I202J0D01*
G01X1572840D01*
G02X1573042Y538458I0J-202D01*
G01Y534496D01*
G02X1572840Y534294I-202J0D01*
G01X1568190D01*
G02X1567988Y534496I0J202D01*
G37*
G36*
G01Y513236D02*
Y517198D01*
G02X1568190Y517400I202J0D01*
G01X1572840D01*
G02X1573042Y517198I0J-202D01*
G01Y513236D01*
G02X1572840Y513034I-202J0D01*
G01X1568190D01*
G02X1567988Y513236I0J202D01*
G37*
G36*
G01X1568190Y524488D02*
X1572840D01*
G02X1573042Y524285I-1J-203D01*
G01Y520322D01*
G02X1572840Y520120I-202J0D01*
G01X1568190D01*
G02X1567988Y520323I1J203D01*
G01Y524286D01*
G02X1568190Y524488I202J0D01*
G37*
G36*
G01X1567988Y527410D02*
Y531372D01*
G02X1568190Y531574I202J0D01*
G01X1572840D01*
G02X1573042Y531372I0J-202D01*
G01Y527410D01*
G02X1572840Y527208I-202J0D01*
G01X1568190D01*
G02X1567988Y527410I0J202D01*
G37*
G36*
G01Y483276D02*
Y487238D01*
G02X1568190Y487440I202J0D01*
G01X1572840D01*
G02X1573042Y487238I0J-202D01*
G01Y483276D01*
G02X1572840Y483074I-202J0D01*
G01X1568190D01*
G02X1567988Y483276I0J202D01*
G37*
G36*
G01Y490362D02*
Y494324D01*
G02X1568190Y494526I202J0D01*
G01X1572840D01*
G02X1573042Y494324I0J-202D01*
G01Y490362D01*
G02X1572840Y490160I-202J0D01*
G01X1568190D01*
G02X1567988Y490362I0J202D01*
G37*
G36*
G01X1639162Y532448D02*
Y536410D01*
G02X1639365Y536612I203J-1D01*
G01X1644016D01*
G02X1644218Y536410I0J-202D01*
G01Y532448D01*
G02X1644015Y532246I-203J1D01*
G01X1639364D01*
G02X1639162Y532448I0J202D01*
G37*
G36*
G01Y525362D02*
Y529324D01*
G02X1639365Y529526I203J-1D01*
G01X1644016D01*
G02X1644218Y529324I0J-202D01*
G01Y525362D01*
G02X1644015Y525160I-203J1D01*
G01X1639364D01*
G02X1639162Y525362I0J202D01*
G37*
G36*
G01X1644218Y522237D02*
Y518275D01*
G02X1644015Y518072I-203J0D01*
G01X1639365D01*
G02X1639162Y518275I0J203D01*
G01Y522237D01*
G02X1639365Y522440I203J0D01*
G01X1644015D01*
G02X1644218Y522237I0J-203D01*
G37*
G36*
G01X1639162Y511188D02*
Y515150D01*
G02X1639365Y515352I203J-1D01*
G01X1644016D01*
G02X1644218Y515150I0J-202D01*
G01Y511188D01*
G02X1644015Y510986I-203J1D01*
G01X1639364D01*
G02X1639162Y511188I0J202D01*
G37*
G36*
G01Y610834D02*
Y614796D01*
G02X1639365Y614998I203J-1D01*
G01X1644016D01*
G02X1644218Y614796I0J-202D01*
G01Y610834D01*
G02X1644015Y610632I-203J1D01*
G01X1639364D01*
G02X1639162Y610834I0J202D01*
G37*
G36*
G01Y603748D02*
Y607710D01*
G02X1639365Y607912I203J-1D01*
G01X1644016D01*
G02X1644218Y607710I0J-202D01*
G01Y603748D01*
G02X1644015Y603546I-203J1D01*
G01X1639364D01*
G02X1639162Y603748I0J202D01*
G37*
G36*
G01X1644218Y600623D02*
Y596661D01*
G02X1644015Y596458I-203J0D01*
G01X1639365D01*
G02X1639162Y596661I0J203D01*
G01Y600623D01*
G02X1639365Y600826I203J0D01*
G01X1644015D01*
G02X1644218Y600623I0J-203D01*
G37*
G36*
G01X1639162Y589574D02*
Y593536D01*
G02X1639365Y593738I203J-1D01*
G01X1644016D01*
G02X1644218Y593536I0J-202D01*
G01Y589574D01*
G02X1644015Y589372I-203J1D01*
G01X1639364D01*
G02X1639162Y589574I0J202D01*
G37*
G36*
G01Y582488D02*
Y586450D01*
G02X1639365Y586652I203J-1D01*
G01X1644016D01*
G02X1644218Y586450I0J-202D01*
G01Y582488D01*
G02X1644015Y582286I-203J1D01*
G01X1639364D01*
G02X1639162Y582488I0J202D01*
G37*
G36*
G01X1644218Y579363D02*
Y575401D01*
G02X1644015Y575198I-203J0D01*
G01X1639365D01*
G02X1639162Y575401I0J203D01*
G01Y579363D01*
G02X1639365Y579566I203J0D01*
G01X1644015D01*
G02X1644218Y579363I0J-203D01*
G37*
G36*
G01X1639162Y568314D02*
Y572276D01*
G02X1639365Y572478I203J-1D01*
G01X1644016D01*
G02X1644218Y572276I0J-202D01*
G01Y568314D01*
G02X1644015Y568112I-203J1D01*
G01X1639364D01*
G02X1639162Y568314I0J202D01*
G37*
G36*
G01Y561228D02*
Y565190D01*
G02X1639365Y565392I203J-1D01*
G01X1644016D01*
G02X1644218Y565190I0J-202D01*
G01Y561228D01*
G02X1644015Y561026I-203J1D01*
G01X1639364D01*
G02X1639162Y561228I0J202D01*
G37*
G36*
G01X12562Y1524246D02*
X10978D01*
G02X10776Y1524449I1J203D01*
G01Y1526050D01*
G02X10978Y1526252I202J0D01*
G01X12562D01*
G02X12764Y1526050I0J-202D01*
G01Y1524448D01*
G02X12562Y1524246I-202J0D01*
G37*
G36*
G01X10784Y1528610D02*
Y1530211D01*
G02X10987Y1530414I203J0D01*
G01X12571D01*
G02X12774Y1530211I0J-203D01*
G01Y1528610D01*
G02X12571Y1528408I-203J1D01*
G01X10986D01*
G02X10784Y1528610I0J202D01*
G37*
G36*
G01X1522570Y1409998D02*
X1525970D01*
G02Y1406992I0J-1503D01*
G01X1522570D01*
G02Y1409998I0J1503D01*
G37*
G36*
G01X1559290Y1349690D02*
X1562690D01*
G02Y1346684I0J-1503D01*
G01X1559290D01*
G02Y1349690I0J1503D01*
G37*
G36*
G01X1522570Y1385800D02*
X1525970D01*
G02Y1382794I0J-1503D01*
G01X1522570D01*
G02Y1385800I0J1503D01*
G37*
G36*
G01Y1373888D02*
X1525970D01*
G02Y1370882I0J-1503D01*
G01X1522570D01*
G02Y1373888I0J1503D01*
G37*
G36*
G01Y1398086D02*
X1525970D01*
G02Y1395080I0J-1503D01*
G01X1522570D01*
G02Y1398086I0J1503D01*
G37*
G36*
G01X1510330Y1373888D02*
X1513730D01*
G02Y1370882I0J-1503D01*
G01X1510330D01*
G02Y1373888I0J1503D01*
G37*
G36*
G01X1547050Y1361602D02*
X1550450D01*
G02Y1358596I0J-1503D01*
G01X1547050D01*
G02Y1361602I0J1503D01*
G37*
G36*
G01X1534810D02*
X1538210D01*
G02Y1358596I0J-1503D01*
G01X1534810D01*
G02Y1361602I0J1503D01*
G37*
G36*
G01X1547050Y1349690D02*
X1550450D01*
G02Y1346684I0J-1503D01*
G01X1547050D01*
G02Y1349690I0J1503D01*
G37*
G36*
G01X1534810D02*
X1538210D01*
G02Y1346684I0J-1503D01*
G01X1534810D01*
G02Y1349690I0J1503D01*
G37*
G36*
G01X241623Y1373888D02*
X245023D01*
G02Y1370882I0J-1503D01*
G01X241623D01*
G02Y1373888I0J1503D01*
G37*
G36*
G01Y1361602D02*
X245023D01*
G02Y1358596I0J-1503D01*
G01X241623D01*
G02Y1361602I0J1503D01*
G37*
G36*
G01X1485850Y1409998D02*
X1489250D01*
G02Y1406992I0J-1503D01*
G01X1485850D01*
G02Y1409998I0J1503D01*
G37*
G36*
G01X1510330Y1349690D02*
X1513730D01*
G02Y1346684I0J-1503D01*
G01X1510330D01*
G02Y1349690I0J1503D01*
G37*
G36*
G01X364023Y1398086D02*
X367423D01*
G02Y1395080I0J-1503D01*
G01X364023D01*
G02Y1398086I0J1503D01*
G37*
G36*
G01X1485850Y1385800D02*
X1489250D01*
G02Y1382794I0J-1503D01*
G01X1485850D01*
G02Y1385800I0J1503D01*
G37*
G36*
G01X1473610D02*
X1477010D01*
G02Y1382794I0J-1503D01*
G01X1473610D01*
G02Y1385800I0J1503D01*
G37*
G36*
G01Y1361602D02*
X1477010D01*
G02Y1358596I0J-1503D01*
G01X1473610D01*
G02Y1361602I0J1503D01*
G37*
G36*
G01Y1349690D02*
X1477010D01*
G02Y1346684I0J-1503D01*
G01X1473610D01*
G02Y1349690I0J1503D01*
G37*
G36*
G01X1461370Y1385800D02*
X1464770D01*
G02Y1382794I0J-1503D01*
G01X1461370D01*
G02Y1385800I0J1503D01*
G37*
G36*
G01Y1373888D02*
X1464770D01*
G02Y1370882I0J-1503D01*
G01X1461370D01*
G02Y1373888I0J1503D01*
G37*
G36*
G01Y1361602D02*
X1464770D01*
G02Y1358596I0J-1503D01*
G01X1461370D01*
G02Y1361602I0J1503D01*
G37*
G36*
G01Y1349690D02*
X1464770D01*
G02Y1346684I0J-1503D01*
G01X1461370D01*
G02Y1349690I0J1503D01*
G37*
G36*
G01X1485850Y1373888D02*
X1489250D01*
G02Y1370882I0J-1503D01*
G01X1485850D01*
G02Y1373888I0J1503D01*
G37*
G36*
G01X1498090Y1361602D02*
X1501490D01*
G02Y1358596I0J-1503D01*
G01X1498090D01*
G02Y1361602I0J1503D01*
G37*
G36*
G01X1485850D02*
X1489250D01*
G02Y1358596I0J-1503D01*
G01X1485850D01*
G02Y1361602I0J1503D01*
G37*
G36*
G01X253863Y1409998D02*
X257263D01*
G02Y1406992I0J-1503D01*
G01X253863D01*
G02Y1409998I0J1503D01*
G37*
G36*
G01X266103Y1373888D02*
X269503D01*
G02Y1370882I0J-1503D01*
G01X266103D01*
G02Y1373888I0J1503D01*
G37*
G36*
G01X290583Y1361602D02*
X293983D01*
G02Y1358596I0J-1503D01*
G01X290583D01*
G02Y1361602I0J1503D01*
G37*
G36*
G01X327303Y1349690D02*
X330703D01*
G02Y1346684I0J-1503D01*
G01X327303D01*
G02Y1349690I0J1503D01*
G37*
G36*
G01X290583Y1385800D02*
X293983D01*
G02Y1382794I0J-1503D01*
G01X290583D01*
G02Y1385800I0J1503D01*
G37*
G36*
G01Y1409998D02*
X293983D01*
G02Y1406992I0J-1503D01*
G01X290583D01*
G02Y1409998I0J1503D01*
G37*
G36*
G01X253863Y1398086D02*
X257263D01*
G02Y1395080I0J-1503D01*
G01X253863D01*
G02Y1398086I0J1503D01*
G37*
G36*
G01X364023Y1361602D02*
X367423D01*
G02Y1358596I0J-1503D01*
G01X364023D01*
G02Y1361602I0J1503D01*
G37*
G36*
G01X339543Y1349690D02*
X342943D01*
G02Y1346684I0J-1503D01*
G01X339543D01*
G02Y1349690I0J1503D01*
G37*
G36*
G01X241623D02*
X245023D01*
G02Y1346684I0J-1503D01*
G01X241623D01*
G02Y1349690I0J1503D01*
G37*
G36*
G01X339543Y1361602D02*
X342943D01*
G02Y1358596I0J-1503D01*
G01X339543D01*
G02Y1361602I0J1503D01*
G37*
G36*
G01X302823Y1409998D02*
X306223D01*
G02Y1406992I0J-1503D01*
G01X302823D01*
G02Y1409998I0J1503D01*
G37*
G36*
G01X364023Y1385800D02*
X367423D01*
G02Y1382794I0J-1503D01*
G01X364023D01*
G02Y1385800I0J1503D01*
G37*
G36*
G01X290583Y1398086D02*
X293983D01*
G02Y1395080I0J-1503D01*
G01X290583D01*
G02Y1398086I0J1503D01*
G37*
G36*
G01X112832D02*
X116232D01*
G02Y1395080I0J-1503D01*
G01X112832D01*
G02Y1398086I0J1503D01*
G37*
G36*
G01X364023Y1373888D02*
X367423D01*
G02Y1370882I0J-1503D01*
G01X364023D01*
G02Y1373888I0J1503D01*
G37*
G36*
G01X302823Y1361602D02*
X306223D01*
G02Y1358596I0J-1503D01*
G01X302823D01*
G02Y1361602I0J1503D01*
G37*
G36*
G01X1534810Y1409998D02*
X1538210D01*
G02Y1406992I0J-1503D01*
G01X1534810D01*
G02Y1409998I0J1503D01*
G37*
G36*
G01X1510330Y1385800D02*
X1513730D01*
G02Y1382794I0J-1503D01*
G01X1510330D01*
G02Y1385800I0J1503D01*
G37*
G36*
G01X1534810Y1398086D02*
X1538210D01*
G02Y1395080I0J-1503D01*
G01X1534810D01*
G02Y1398086I0J1503D01*
G37*
G36*
G01X302823Y1349690D02*
X306223D01*
G02Y1346684I0J-1503D01*
G01X302823D01*
G02Y1349690I0J1503D01*
G37*
G36*
G01X88352Y1373888D02*
X91752D01*
G02Y1370882I0J-1503D01*
G01X88352D01*
G02Y1373888I0J1503D01*
G37*
G36*
G01X339543Y1385800D02*
X342943D01*
G02Y1382794I0J-1503D01*
G01X339543D01*
G02Y1385800I0J1503D01*
G37*
G36*
G01X327303Y1373888D02*
X330703D01*
G02Y1370882I0J-1503D01*
G01X327303D01*
G02Y1373888I0J1503D01*
G37*
G36*
G01Y1409998D02*
X330703D01*
G02Y1406992I0J-1503D01*
G01X327303D01*
G02Y1409998I0J1503D01*
G37*
G36*
G01X278343Y1398086D02*
X281743D01*
G02Y1395080I0J-1503D01*
G01X278343D01*
G02Y1398086I0J1503D01*
G37*
G36*
G01X351783Y1349690D02*
X355183D01*
G02Y1346684I0J-1503D01*
G01X351783D01*
G02Y1349690I0J1503D01*
G37*
G36*
G01X186272Y1385800D02*
X189672D01*
G02Y1382794I0J-1503D01*
G01X186272D01*
G02Y1385800I0J1503D01*
G37*
G36*
G01Y1373888D02*
X189672D01*
G02Y1370882I0J-1503D01*
G01X186272D01*
G02Y1373888I0J1503D01*
G37*
G36*
G01X315063Y1361602D02*
X318463D01*
G02Y1358596I0J-1503D01*
G01X315063D01*
G02Y1361602I0J1503D01*
G37*
G36*
G01X327303D02*
X330703D01*
G02Y1358596I0J-1503D01*
G01X327303D01*
G02Y1361602I0J1503D01*
G37*
G36*
G01X315063Y1349690D02*
X318463D01*
G02Y1346684I0J-1503D01*
G01X315063D01*
G02Y1349690I0J1503D01*
G37*
G36*
G01X174032Y1398086D02*
X177432D01*
G02Y1395080I0J-1503D01*
G01X174032D01*
G02Y1398086I0J1503D01*
G37*
G36*
G01X266103Y1349690D02*
X269503D01*
G02Y1346684I0J-1503D01*
G01X266103D01*
G02Y1349690I0J1503D01*
G37*
G36*
G01X1054713Y1361602D02*
X1058113D01*
G02Y1358596I0J-1503D01*
G01X1054713D01*
G02Y1361602I0J1503D01*
G37*
G36*
G01Y1349690D02*
X1058113D01*
G02Y1346684I0J-1503D01*
G01X1054713D01*
G02Y1349690I0J1503D01*
G37*
G36*
G01Y1385800D02*
X1058113D01*
G02Y1382794I0J-1503D01*
G01X1054713D01*
G02Y1385800I0J1503D01*
G37*
G36*
G01Y1373888D02*
X1058113D01*
G02Y1370882I0J-1503D01*
G01X1054713D01*
G02Y1373888I0J1503D01*
G37*
G36*
G01X1177113Y1409998D02*
X1180513D01*
G02Y1406992I0J-1503D01*
G01X1177113D01*
G02Y1409998I0J1503D01*
G37*
G36*
G01Y1398086D02*
X1180513D01*
G02Y1395080I0J-1503D01*
G01X1177113D01*
G02Y1398086I0J1503D01*
G37*
G36*
G01Y1373888D02*
X1180513D01*
G02Y1370882I0J-1503D01*
G01X1177113D01*
G02Y1373888I0J1503D01*
G37*
G36*
G01Y1385800D02*
X1180513D01*
G02Y1382794I0J-1503D01*
G01X1177113D01*
G02Y1385800I0J1503D01*
G37*
G36*
G01Y1361602D02*
X1180513D01*
G02Y1358596I0J-1503D01*
G01X1177113D01*
G02Y1361602I0J1503D01*
G37*
G36*
G01Y1349690D02*
X1180513D01*
G02Y1346684I0J-1503D01*
G01X1177113D01*
G02Y1349690I0J1503D01*
G37*
G36*
G01X1164873Y1409998D02*
X1168273D01*
G02Y1406992I0J-1503D01*
G01X1164873D01*
G02Y1409998I0J1503D01*
G37*
G36*
G01Y1398086D02*
X1168273D01*
G02Y1395080I0J-1503D01*
G01X1164873D01*
G02Y1398086I0J1503D01*
G37*
G36*
G01Y1385800D02*
X1168273D01*
G02Y1382794I0J-1503D01*
G01X1164873D01*
G02Y1385800I0J1503D01*
G37*
G36*
G01Y1373888D02*
X1168273D01*
G02Y1370882I0J-1503D01*
G01X1164873D01*
G02Y1373888I0J1503D01*
G37*
G36*
G01Y1361602D02*
X1168273D01*
G02Y1358596I0J-1503D01*
G01X1164873D01*
G02Y1361602I0J1503D01*
G37*
G36*
G01Y1349690D02*
X1168273D01*
G02Y1346684I0J-1503D01*
G01X1164873D01*
G02Y1349690I0J1503D01*
G37*
G36*
G01X1152633Y1409998D02*
X1156033D01*
G02Y1406992I0J-1503D01*
G01X1152633D01*
G02Y1409998I0J1503D01*
G37*
G36*
G01Y1398086D02*
X1156033D01*
G02Y1395080I0J-1503D01*
G01X1152633D01*
G02Y1398086I0J1503D01*
G37*
G36*
G01Y1373888D02*
X1156033D01*
G02Y1370882I0J-1503D01*
G01X1152633D01*
G02Y1373888I0J1503D01*
G37*
G36*
G01Y1385800D02*
X1156033D01*
G02Y1382794I0J-1503D01*
G01X1152633D01*
G02Y1385800I0J1503D01*
G37*
G36*
G01Y1361602D02*
X1156033D01*
G02Y1358596I0J-1503D01*
G01X1152633D01*
G02Y1361602I0J1503D01*
G37*
G36*
G01Y1349690D02*
X1156033D01*
G02Y1346684I0J-1503D01*
G01X1152633D01*
G02Y1349690I0J1503D01*
G37*
G36*
G01X1128153Y1409998D02*
X1131553D01*
G02Y1406992I0J-1503D01*
G01X1128153D01*
G02Y1409998I0J1503D01*
G37*
G36*
G01X1140393D02*
X1143793D01*
G02Y1406992I0J-1503D01*
G01X1140393D01*
G02Y1409998I0J1503D01*
G37*
G36*
G01X1128153Y1398086D02*
X1131553D01*
G02Y1395080I0J-1503D01*
G01X1128153D01*
G02Y1398086I0J1503D01*
G37*
G36*
G01X1140393D02*
X1143793D01*
G02Y1395080I0J-1503D01*
G01X1140393D01*
G02Y1398086I0J1503D01*
G37*
G36*
G01X1128153Y1373888D02*
X1131553D01*
G02Y1370882I0J-1503D01*
G01X1128153D01*
G02Y1373888I0J1503D01*
G37*
G36*
G01Y1385800D02*
X1131553D01*
G02Y1382794I0J-1503D01*
G01X1128153D01*
G02Y1385800I0J1503D01*
G37*
G36*
G01X1140393D02*
X1143793D01*
G02Y1382794I0J-1503D01*
G01X1140393D01*
G02Y1385800I0J1503D01*
G37*
G36*
G01Y1373888D02*
X1143793D01*
G02Y1370882I0J-1503D01*
G01X1140393D01*
G02Y1373888I0J1503D01*
G37*
G36*
G01X1128153Y1361602D02*
X1131553D01*
G02Y1358596I0J-1503D01*
G01X1128153D01*
G02Y1361602I0J1503D01*
G37*
G36*
G01X1140393D02*
X1143793D01*
G02Y1358596I0J-1503D01*
G01X1140393D01*
G02Y1361602I0J1503D01*
G37*
G36*
G01X1128153Y1349690D02*
X1131553D01*
G02Y1346684I0J-1503D01*
G01X1128153D01*
G02Y1349690I0J1503D01*
G37*
G36*
G01X1140393D02*
X1143793D01*
G02Y1346684I0J-1503D01*
G01X1140393D01*
G02Y1349690I0J1503D01*
G37*
G36*
G01X1115913Y1409998D02*
X1119313D01*
G02Y1406992I0J-1503D01*
G01X1115913D01*
G02Y1409998I0J1503D01*
G37*
G36*
G01Y1398086D02*
X1119313D01*
G02Y1395080I0J-1503D01*
G01X1115913D01*
G02Y1398086I0J1503D01*
G37*
G36*
G01Y1373888D02*
X1119313D01*
G02Y1370882I0J-1503D01*
G01X1115913D01*
G02Y1373888I0J1503D01*
G37*
G36*
G01Y1385800D02*
X1119313D01*
G02Y1382794I0J-1503D01*
G01X1115913D01*
G02Y1385800I0J1503D01*
G37*
G36*
G01Y1361602D02*
X1119313D01*
G02Y1358596I0J-1503D01*
G01X1115913D01*
G02Y1361602I0J1503D01*
G37*
G36*
G01Y1349690D02*
X1119313D01*
G02Y1346684I0J-1503D01*
G01X1115913D01*
G02Y1349690I0J1503D01*
G37*
G36*
G01X1103673Y1409998D02*
X1107073D01*
G02Y1406992I0J-1503D01*
G01X1103673D01*
G02Y1409998I0J1503D01*
G37*
G36*
G01Y1398086D02*
X1107073D01*
G02Y1395080I0J-1503D01*
G01X1103673D01*
G02Y1398086I0J1503D01*
G37*
G36*
G01Y1385800D02*
X1107073D01*
G02Y1382794I0J-1503D01*
G01X1103673D01*
G02Y1385800I0J1503D01*
G37*
G36*
G01Y1373888D02*
X1107073D01*
G02Y1370882I0J-1503D01*
G01X1103673D01*
G02Y1373888I0J1503D01*
G37*
G36*
G01Y1361602D02*
X1107073D01*
G02Y1358596I0J-1503D01*
G01X1103673D01*
G02Y1361602I0J1503D01*
G37*
G36*
G01Y1349690D02*
X1107073D01*
G02Y1346684I0J-1503D01*
G01X1103673D01*
G02Y1349690I0J1503D01*
G37*
G36*
G01X1079193Y1409998D02*
X1082593D01*
G02Y1406992I0J-1503D01*
G01X1079193D01*
G02Y1409998I0J1503D01*
G37*
G36*
G01X1091433D02*
X1094833D01*
G02Y1406992I0J-1503D01*
G01X1091433D01*
G02Y1409998I0J1503D01*
G37*
G36*
G01X1079193Y1398086D02*
X1082593D01*
G02Y1395080I0J-1503D01*
G01X1079193D01*
G02Y1398086I0J1503D01*
G37*
G36*
G01X1091433D02*
X1094833D01*
G02Y1395080I0J-1503D01*
G01X1091433D01*
G02Y1398086I0J1503D01*
G37*
G36*
G01X1079193Y1385800D02*
X1082593D01*
G02Y1382794I0J-1503D01*
G01X1079193D01*
G02Y1385800I0J1503D01*
G37*
G36*
G01Y1373888D02*
X1082593D01*
G02Y1370882I0J-1503D01*
G01X1079193D01*
G02Y1373888I0J1503D01*
G37*
G36*
G01X1091433Y1385800D02*
X1094833D01*
G02Y1382794I0J-1503D01*
G01X1091433D01*
G02Y1385800I0J1503D01*
G37*
G36*
G01Y1373888D02*
X1094833D01*
G02Y1370882I0J-1503D01*
G01X1091433D01*
G02Y1373888I0J1503D01*
G37*
G36*
G01X1079193Y1361602D02*
X1082593D01*
G02Y1358596I0J-1503D01*
G01X1079193D01*
G02Y1361602I0J1503D01*
G37*
G36*
G01X1091433D02*
X1094833D01*
G02Y1358596I0J-1503D01*
G01X1091433D01*
G02Y1361602I0J1503D01*
G37*
G36*
G01X1079193Y1349690D02*
X1082593D01*
G02Y1346684I0J-1503D01*
G01X1079193D01*
G02Y1349690I0J1503D01*
G37*
G36*
G01X1091433D02*
X1094833D01*
G02Y1346684I0J-1503D01*
G01X1091433D01*
G02Y1349690I0J1503D01*
G37*
G36*
G01X1066953Y1409998D02*
X1070353D01*
G02Y1406992I0J-1503D01*
G01X1066953D01*
G02Y1409998I0J1503D01*
G37*
G36*
G01Y1398086D02*
X1070353D01*
G02Y1395080I0J-1503D01*
G01X1066953D01*
G02Y1398086I0J1503D01*
G37*
G36*
G01X290583Y1349690D02*
X293983D01*
G02Y1346684I0J-1503D01*
G01X290583D01*
G02Y1349690I0J1503D01*
G37*
G36*
G01X241623Y1385800D02*
X245023D01*
G02Y1382794I0J-1503D01*
G01X241623D01*
G02Y1385800I0J1503D01*
G37*
G36*
G01X253863Y1361602D02*
X257263D01*
G02Y1358596I0J-1503D01*
G01X253863D01*
G02Y1361602I0J1503D01*
G37*
G36*
G01Y1349690D02*
X257263D01*
G02Y1346684I0J-1503D01*
G01X253863D01*
G02Y1349690I0J1503D01*
G37*
G36*
G01X1547050Y1409998D02*
X1550450D01*
G02Y1406992I0J-1503D01*
G01X1547050D01*
G02Y1409998I0J1503D01*
G37*
G36*
G01X1559290Y1385800D02*
X1562690D01*
G02Y1382794I0J-1503D01*
G01X1559290D01*
G02Y1385800I0J1503D01*
G37*
G36*
G01X1230326Y1349690D02*
X1233726D01*
G02Y1346684I0J-1503D01*
G01X1230326D01*
G02Y1349690I0J1503D01*
G37*
G36*
G01Y1361602D02*
X1233726D01*
G02Y1358596I0J-1503D01*
G01X1230326D01*
G02Y1361602I0J1503D01*
G37*
G36*
G01Y1373888D02*
X1233726D01*
G02Y1370882I0J-1503D01*
G01X1230326D01*
G02Y1373888I0J1503D01*
G37*
G36*
G01Y1385800D02*
X1233726D01*
G02Y1382794I0J-1503D01*
G01X1230326D01*
G02Y1385800I0J1503D01*
G37*
G36*
G01X1242566Y1349690D02*
X1245966D01*
G02Y1346684I0J-1503D01*
G01X1242566D01*
G02Y1349690I0J1503D01*
G37*
G36*
G01Y1361602D02*
X1245966D01*
G02Y1358596I0J-1503D01*
G01X1242566D01*
G02Y1361602I0J1503D01*
G37*
G36*
G01Y1385800D02*
X1245966D01*
G02Y1382794I0J-1503D01*
G01X1242566D01*
G02Y1385800I0J1503D01*
G37*
G36*
G01Y1373888D02*
X1245966D01*
G02Y1370882I0J-1503D01*
G01X1242566D01*
G02Y1373888I0J1503D01*
G37*
G36*
G01Y1398086D02*
X1245966D01*
G02Y1395080I0J-1503D01*
G01X1242566D01*
G02Y1398086I0J1503D01*
G37*
G36*
G01Y1409998D02*
X1245966D01*
G02Y1406992I0J-1503D01*
G01X1242566D01*
G02Y1409998I0J1503D01*
G37*
G36*
G01X1267046Y1349690D02*
X1270446D01*
G02Y1346684I0J-1503D01*
G01X1267046D01*
G02Y1349690I0J1503D01*
G37*
G36*
G01X1254806D02*
X1258206D01*
G02Y1346684I0J-1503D01*
G01X1254806D01*
G02Y1349690I0J1503D01*
G37*
G36*
G01X1267046Y1361602D02*
X1270446D01*
G02Y1358596I0J-1503D01*
G01X1267046D01*
G02Y1361602I0J1503D01*
G37*
G36*
G01X1254806D02*
X1258206D01*
G02Y1358596I0J-1503D01*
G01X1254806D01*
G02Y1361602I0J1503D01*
G37*
G36*
G01X1267046Y1385800D02*
X1270446D01*
G02Y1382794I0J-1503D01*
G01X1267046D01*
G02Y1385800I0J1503D01*
G37*
G36*
G01Y1373888D02*
X1270446D01*
G02Y1370882I0J-1503D01*
G01X1267046D01*
G02Y1373888I0J1503D01*
G37*
G36*
G01X1254806D02*
X1258206D01*
G02Y1370882I0J-1503D01*
G01X1254806D01*
G02Y1373888I0J1503D01*
G37*
G36*
G01Y1385800D02*
X1258206D01*
G02Y1382794I0J-1503D01*
G01X1254806D01*
G02Y1385800I0J1503D01*
G37*
G36*
G01X1267046Y1398086D02*
X1270446D01*
G02Y1395080I0J-1503D01*
G01X1267046D01*
G02Y1398086I0J1503D01*
G37*
G36*
G01X1254806D02*
X1258206D01*
G02Y1395080I0J-1503D01*
G01X1254806D01*
G02Y1398086I0J1503D01*
G37*
G36*
G01X1267046Y1409998D02*
X1270446D01*
G02Y1406992I0J-1503D01*
G01X1267046D01*
G02Y1409998I0J1503D01*
G37*
G36*
G01X1254806D02*
X1258206D01*
G02Y1406992I0J-1503D01*
G01X1254806D01*
G02Y1409998I0J1503D01*
G37*
G36*
G01X1279286Y1349690D02*
X1282686D01*
G02Y1346684I0J-1503D01*
G01X1279286D01*
G02Y1349690I0J1503D01*
G37*
G36*
G01Y1361602D02*
X1282686D01*
G02Y1358596I0J-1503D01*
G01X1279286D01*
G02Y1361602I0J1503D01*
G37*
G36*
G01X1510330D02*
X1513730D01*
G02Y1358596I0J-1503D01*
G01X1510330D01*
G02Y1361602I0J1503D01*
G37*
G36*
G01X1279286Y1373888D02*
X1282686D01*
G02Y1370882I0J-1503D01*
G01X1279286D01*
G02Y1373888I0J1503D01*
G37*
G36*
G01Y1385800D02*
X1282686D01*
G02Y1382794I0J-1503D01*
G01X1279286D01*
G02Y1385800I0J1503D01*
G37*
G36*
G01X1648118Y1409998D02*
X1651518D01*
G02Y1406992I0J-1503D01*
G01X1648118D01*
G02Y1409998I0J1503D01*
G37*
G36*
G01X1279286Y1398086D02*
X1282686D01*
G02Y1395080I0J-1503D01*
G01X1279286D01*
G02Y1398086I0J1503D01*
G37*
G36*
G01Y1409998D02*
X1282686D01*
G02Y1406992I0J-1503D01*
G01X1279286D01*
G02Y1409998I0J1503D01*
G37*
G36*
G01X1291526Y1349690D02*
X1294926D01*
G02Y1346684I0J-1503D01*
G01X1291526D01*
G02Y1349690I0J1503D01*
G37*
G36*
G01X1559290Y1398086D02*
X1562690D01*
G02Y1395080I0J-1503D01*
G01X1559290D01*
G02Y1398086I0J1503D01*
G37*
G36*
G01X161792Y1409998D02*
X165192D01*
G02Y1406992I0J-1503D01*
G01X161792D01*
G02Y1409998I0J1503D01*
G37*
G36*
G01X186272Y1349690D02*
X189672D01*
G02Y1346684I0J-1503D01*
G01X186272D01*
G02Y1349690I0J1503D01*
G37*
G36*
G01X315063Y1409998D02*
X318463D01*
G02Y1406992I0J-1503D01*
G01X315063D01*
G02Y1409998I0J1503D01*
G37*
G36*
G01X1534810Y1373888D02*
X1538210D01*
G02Y1370882I0J-1503D01*
G01X1534810D01*
G02Y1373888I0J1503D01*
G37*
G36*
G01X1559290Y1409998D02*
X1562690D01*
G02Y1406992I0J-1503D01*
G01X1559290D01*
G02Y1409998I0J1503D01*
G37*
G36*
G01X351783Y1361602D02*
X355183D01*
G02Y1358596I0J-1503D01*
G01X351783D01*
G02Y1361602I0J1503D01*
G37*
G36*
G01X198512Y1385800D02*
X201912D01*
G02Y1382794I0J-1503D01*
G01X198512D01*
G02Y1385800I0J1503D01*
G37*
G36*
G01X1291526Y1361602D02*
X1294926D01*
G02Y1358596I0J-1503D01*
G01X1291526D01*
G02Y1361602I0J1503D01*
G37*
G36*
G01X1635878Y1349690D02*
X1639278D01*
G02Y1346684I0J-1503D01*
G01X1635878D01*
G02Y1349690I0J1503D01*
G37*
G36*
G01Y1361602D02*
X1639278D01*
G02Y1358596I0J-1503D01*
G01X1635878D01*
G02Y1361602I0J1503D01*
G37*
G36*
G01X1291526Y1385800D02*
X1294926D01*
G02Y1382794I0J-1503D01*
G01X1291526D01*
G02Y1385800I0J1503D01*
G37*
G36*
G01Y1373888D02*
X1294926D01*
G02Y1370882I0J-1503D01*
G01X1291526D01*
G02Y1373888I0J1503D01*
G37*
G36*
G01X1635878Y1385800D02*
X1639278D01*
G02Y1382794I0J-1503D01*
G01X1635878D01*
G02Y1385800I0J1503D01*
G37*
G36*
G01Y1373888D02*
X1639278D01*
G02Y1370882I0J-1503D01*
G01X1635878D01*
G02Y1373888I0J1503D01*
G37*
G36*
G01Y1398086D02*
X1639278D01*
G02Y1395080I0J-1503D01*
G01X1635878D01*
G02Y1398086I0J1503D01*
G37*
G36*
G01X1623638Y1349690D02*
X1627038D01*
G02Y1346684I0J-1503D01*
G01X1623638D01*
G02Y1349690I0J1503D01*
G37*
G36*
G01X1611398D02*
X1614798D01*
G02Y1346684I0J-1503D01*
G01X1611398D01*
G02Y1349690I0J1503D01*
G37*
G36*
G01X1623638Y1361602D02*
X1627038D01*
G02Y1358596I0J-1503D01*
G01X1623638D01*
G02Y1361602I0J1503D01*
G37*
G36*
G01X1291526Y1398086D02*
X1294926D01*
G02Y1395080I0J-1503D01*
G01X1291526D01*
G02Y1398086I0J1503D01*
G37*
G36*
G01Y1409998D02*
X1294926D01*
G02Y1406992I0J-1503D01*
G01X1291526D01*
G02Y1409998I0J1503D01*
G37*
G36*
G01X1316006Y1349690D02*
X1319406D01*
G02Y1346684I0J-1503D01*
G01X1316006D01*
G02Y1349690I0J1503D01*
G37*
G36*
G01X1303766D02*
X1307166D01*
G02Y1346684I0J-1503D01*
G01X1303766D01*
G02Y1349690I0J1503D01*
G37*
G36*
G01X1316006Y1361602D02*
X1319406D01*
G02Y1358596I0J-1503D01*
G01X1316006D01*
G02Y1361602I0J1503D01*
G37*
G36*
G01X1303766D02*
X1307166D01*
G02Y1358596I0J-1503D01*
G01X1303766D01*
G02Y1361602I0J1503D01*
G37*
G36*
G01X1316006Y1385800D02*
X1319406D01*
G02Y1382794I0J-1503D01*
G01X1316006D01*
G02Y1385800I0J1503D01*
G37*
G36*
G01X1611398Y1373888D02*
X1614798D01*
G02Y1370882I0J-1503D01*
G01X1611398D01*
G02Y1373888I0J1503D01*
G37*
G36*
G01Y1385800D02*
X1614798D01*
G02Y1382794I0J-1503D01*
G01X1611398D01*
G02Y1385800I0J1503D01*
G37*
G36*
G01X1623638Y1398086D02*
X1627038D01*
G02Y1395080I0J-1503D01*
G01X1623638D01*
G02Y1398086I0J1503D01*
G37*
G36*
G01X1316006Y1373888D02*
X1319406D01*
G02Y1370882I0J-1503D01*
G01X1316006D01*
G02Y1373888I0J1503D01*
G37*
G36*
G01X1303766D02*
X1307166D01*
G02Y1370882I0J-1503D01*
G01X1303766D01*
G02Y1373888I0J1503D01*
G37*
G36*
G01Y1385800D02*
X1307166D01*
G02Y1382794I0J-1503D01*
G01X1303766D01*
G02Y1385800I0J1503D01*
G37*
G36*
G01X1316006Y1398086D02*
X1319406D01*
G02Y1395080I0J-1503D01*
G01X1316006D01*
G02Y1398086I0J1503D01*
G37*
G36*
G01X1303766D02*
X1307166D01*
G02Y1395080I0J-1503D01*
G01X1303766D01*
G02Y1398086I0J1503D01*
G37*
G36*
G01X1316006Y1409998D02*
X1319406D01*
G02Y1406992I0J-1503D01*
G01X1316006D01*
G02Y1409998I0J1503D01*
G37*
G36*
G01X1303766D02*
X1307166D01*
G02Y1406992I0J-1503D01*
G01X1303766D01*
G02Y1409998I0J1503D01*
G37*
G36*
G01X1623638D02*
X1627038D01*
G02Y1406992I0J-1503D01*
G01X1623638D01*
G02Y1409998I0J1503D01*
G37*
G36*
G01X1328246Y1349690D02*
X1331646D01*
G02Y1346684I0J-1503D01*
G01X1328246D01*
G02Y1349690I0J1503D01*
G37*
G36*
G01Y1361602D02*
X1331646D01*
G02Y1358596I0J-1503D01*
G01X1328246D01*
G02Y1361602I0J1503D01*
G37*
G36*
G01X1648118Y1398086D02*
X1651518D01*
G02Y1395080I0J-1503D01*
G01X1648118D01*
G02Y1398086I0J1503D01*
G37*
G36*
G01Y1373888D02*
X1651518D01*
G02Y1370882I0J-1503D01*
G01X1648118D01*
G02Y1373888I0J1503D01*
G37*
G36*
G01Y1385800D02*
X1651518D01*
G02Y1382794I0J-1503D01*
G01X1648118D01*
G02Y1385800I0J1503D01*
G37*
G36*
G01X1328246Y1373888D02*
X1331646D01*
G02Y1370882I0J-1503D01*
G01X1328246D01*
G02Y1373888I0J1503D01*
G37*
G36*
G01X1648118Y1361602D02*
X1651518D01*
G02Y1358596I0J-1503D01*
G01X1648118D01*
G02Y1361602I0J1503D01*
G37*
G36*
G01Y1349690D02*
X1651518D01*
G02Y1346684I0J-1503D01*
G01X1648118D01*
G02Y1349690I0J1503D01*
G37*
G36*
G01X1635878Y1409998D02*
X1639278D01*
G02Y1406992I0J-1503D01*
G01X1635878D01*
G02Y1409998I0J1503D01*
G37*
G36*
G01X1660358D02*
X1663758D01*
G02Y1406992I0J-1503D01*
G01X1660358D01*
G02Y1409998I0J1503D01*
G37*
G36*
G01X1672598D02*
X1675998D01*
G02Y1406992I0J-1503D01*
G01X1672598D01*
G02Y1409998I0J1503D01*
G37*
G36*
G01X1660358Y1398086D02*
X1663758D01*
G02Y1395080I0J-1503D01*
G01X1660358D01*
G02Y1398086I0J1503D01*
G37*
G36*
G01X1672598D02*
X1675998D01*
G02Y1395080I0J-1503D01*
G01X1672598D01*
G02Y1398086I0J1503D01*
G37*
G36*
G01X1660358Y1373888D02*
X1663758D01*
G02Y1370882I0J-1503D01*
G01X1660358D01*
G02Y1373888I0J1503D01*
G37*
G36*
G01Y1385800D02*
X1663758D01*
G02Y1382794I0J-1503D01*
G01X1660358D01*
G02Y1385800I0J1503D01*
G37*
G36*
G01X1672598Y1373888D02*
X1675998D01*
G02Y1370882I0J-1503D01*
G01X1672598D01*
G02Y1373888I0J1503D01*
G37*
G36*
G01X1328246Y1385800D02*
X1331646D01*
G02Y1382794I0J-1503D01*
G01X1328246D01*
G02Y1385800I0J1503D01*
G37*
G36*
G01X1672598D02*
X1675998D01*
G02Y1382794I0J-1503D01*
G01X1672598D01*
G02Y1385800I0J1503D01*
G37*
G36*
G01X174032Y1409998D02*
X177432D01*
G02Y1406992I0J-1503D01*
G01X174032D01*
G02Y1409998I0J1503D01*
G37*
G36*
G01X266103Y1385800D02*
X269503D01*
G02Y1382794I0J-1503D01*
G01X266103D01*
G02Y1385800I0J1503D01*
G37*
G36*
G01X315063D02*
X318463D01*
G02Y1382794I0J-1503D01*
G01X315063D01*
G02Y1385800I0J1503D01*
G37*
G36*
G01X278343Y1409998D02*
X281743D01*
G02Y1406992I0J-1503D01*
G01X278343D01*
G02Y1409998I0J1503D01*
G37*
G36*
G01X1328246Y1398086D02*
X1331646D01*
G02Y1395080I0J-1503D01*
G01X1328246D01*
G02Y1398086I0J1503D01*
G37*
G36*
G01X364023Y1409998D02*
X367423D01*
G02Y1406992I0J-1503D01*
G01X364023D01*
G02Y1409998I0J1503D01*
G37*
G36*
G01X266103D02*
X269503D01*
G02Y1406992I0J-1503D01*
G01X266103D01*
G02Y1409998I0J1503D01*
G37*
G36*
G01X1733798Y1385800D02*
X1737198D01*
G02Y1382794I0J-1503D01*
G01X1733798D01*
G02Y1385800I0J1503D01*
G37*
G36*
G01Y1373888D02*
X1737198D01*
G02Y1370882I0J-1503D01*
G01X1733798D01*
G02Y1373888I0J1503D01*
G37*
G36*
G01Y1398086D02*
X1737198D01*
G02Y1395080I0J-1503D01*
G01X1733798D01*
G02Y1398086I0J1503D01*
G37*
G36*
G01X1721558Y1373888D02*
X1724958D01*
G02Y1370882I0J-1503D01*
G01X1721558D01*
G02Y1373888I0J1503D01*
G37*
G36*
G01X290583D02*
X293983D01*
G02Y1370882I0J-1503D01*
G01X290583D01*
G02Y1373888I0J1503D01*
G37*
G36*
G01X1328246Y1409998D02*
X1331646D01*
G02Y1406992I0J-1503D01*
G01X1328246D01*
G02Y1409998I0J1503D01*
G37*
G36*
G01X1340486Y1349690D02*
X1343886D01*
G02Y1346684I0J-1503D01*
G01X1340486D01*
G02Y1349690I0J1503D01*
G37*
G36*
G01X1583770Y1373888D02*
X1587170D01*
G02Y1370882I0J-1503D01*
G01X1583770D01*
G02Y1373888I0J1503D01*
G37*
G36*
G01X1485850Y1349690D02*
X1489250D01*
G02Y1346684I0J-1503D01*
G01X1485850D01*
G02Y1349690I0J1503D01*
G37*
G36*
G01X1340486Y1361602D02*
X1343886D01*
G02Y1358596I0J-1503D01*
G01X1340486D01*
G02Y1361602I0J1503D01*
G37*
G36*
G01X1733798Y1409998D02*
X1737198D01*
G02Y1406992I0J-1503D01*
G01X1733798D01*
G02Y1409998I0J1503D01*
G37*
G36*
G01X278343Y1373888D02*
X281743D01*
G02Y1370882I0J-1503D01*
G01X278343D01*
G02Y1373888I0J1503D01*
G37*
G36*
G01X266103Y1398086D02*
X269503D01*
G02Y1395080I0J-1503D01*
G01X266103D01*
G02Y1398086I0J1503D01*
G37*
G36*
G01X1733798Y1349690D02*
X1737198D01*
G02Y1346684I0J-1503D01*
G01X1733798D01*
G02Y1349690I0J1503D01*
G37*
G36*
G01X137312Y1385800D02*
X140712D01*
G02Y1382794I0J-1503D01*
G01X137312D01*
G02Y1385800I0J1503D01*
G37*
G36*
G01X1721558Y1398086D02*
X1724958D01*
G02Y1395080I0J-1503D01*
G01X1721558D01*
G02Y1398086I0J1503D01*
G37*
G36*
G01X1340486Y1385800D02*
X1343886D01*
G02Y1382794I0J-1503D01*
G01X1340486D01*
G02Y1385800I0J1503D01*
G37*
G36*
G01Y1373888D02*
X1343886D01*
G02Y1370882I0J-1503D01*
G01X1340486D01*
G02Y1373888I0J1503D01*
G37*
G36*
G01X1721558Y1385800D02*
X1724958D01*
G02Y1382794I0J-1503D01*
G01X1721558D01*
G02Y1385800I0J1503D01*
G37*
G36*
G01X339543Y1398086D02*
X342943D01*
G02Y1395080I0J-1503D01*
G01X339543D01*
G02Y1398086I0J1503D01*
G37*
G36*
G01X327303Y1385800D02*
X330703D01*
G02Y1382794I0J-1503D01*
G01X327303D01*
G02Y1385800I0J1503D01*
G37*
G36*
G01X315063Y1373888D02*
X318463D01*
G02Y1370882I0J-1503D01*
G01X315063D01*
G02Y1373888I0J1503D01*
G37*
G36*
G01X339543D02*
X342943D01*
G02Y1370882I0J-1503D01*
G01X339543D01*
G02Y1373888I0J1503D01*
G37*
G36*
G01X351783Y1385800D02*
X355183D01*
G02Y1382794I0J-1503D01*
G01X351783D01*
G02Y1385800I0J1503D01*
G37*
G36*
G01Y1373888D02*
X355183D01*
G02Y1370882I0J-1503D01*
G01X351783D01*
G02Y1373888I0J1503D01*
G37*
G36*
G01Y1398086D02*
X355183D01*
G02Y1395080I0J-1503D01*
G01X351783D01*
G02Y1398086I0J1503D01*
G37*
G36*
G01Y1409998D02*
X355183D01*
G02Y1406992I0J-1503D01*
G01X351783D01*
G02Y1409998I0J1503D01*
G37*
G36*
G01X315063Y1398086D02*
X318463D01*
G02Y1395080I0J-1503D01*
G01X315063D01*
G02Y1398086I0J1503D01*
G37*
G36*
G01X278343Y1361602D02*
X281743D01*
G02Y1358596I0J-1503D01*
G01X278343D01*
G02Y1361602I0J1503D01*
G37*
G36*
G01X1498090Y1349690D02*
X1501490D01*
G02Y1346684I0J-1503D01*
G01X1498090D01*
G02Y1349690I0J1503D01*
G37*
G36*
G01X266103Y1361602D02*
X269503D01*
G02Y1358596I0J-1503D01*
G01X266103D01*
G02Y1361602I0J1503D01*
G37*
G36*
G01X35825Y1466648D02*
X39225D01*
G02Y1463044I0J-1802D01*
G01X35825D01*
G02Y1466648I0J1802D01*
G37*
G36*
G01X942699Y344560D02*
X939299D01*
G02Y348166I0J1803D01*
G01X942699D01*
G02Y344560I0J-1803D01*
G37*
G36*
G01X942730Y322242D02*
X939330D01*
G02Y325846I0J1802D01*
G01X942730D01*
G02Y322242I0J-1802D01*
G37*
G36*
G01X927963Y342238D02*
X924563D01*
G02Y345844I0J1803D01*
G01X927963D01*
G02Y342238I0J-1803D01*
G37*
G36*
G01X919353Y342348D02*
X915953D01*
G02Y345952I0J1802D01*
G01X919353D01*
G02Y342348I0J-1802D01*
G37*
G36*
G01X302823Y1398086D02*
X306223D01*
G02Y1395080I0J-1503D01*
G01X302823D01*
G02Y1398086I0J1503D01*
G37*
G36*
G01X389015Y794228D02*
X392415D01*
G02Y791222I0J-1503D01*
G01X389015D01*
G02Y794228I0J1503D01*
G37*
G36*
G01X302823Y1373888D02*
X306223D01*
G02Y1370882I0J-1503D01*
G01X302823D01*
G02Y1373888I0J1503D01*
G37*
G36*
G01X1534810Y1385800D02*
X1538210D01*
G02Y1382794I0J-1503D01*
G01X1534810D01*
G02Y1385800I0J1503D01*
G37*
G36*
G01X327303Y1398086D02*
X330703D01*
G02Y1395080I0J-1503D01*
G01X327303D01*
G02Y1398086I0J1503D01*
G37*
G36*
G01X339543Y1409998D02*
X342943D01*
G02Y1406992I0J-1503D01*
G01X339543D01*
G02Y1409998I0J1503D01*
G37*
G36*
G01X302823Y1385800D02*
X306223D01*
G02Y1382794I0J-1503D01*
G01X302823D01*
G02Y1385800I0J1503D01*
G37*
G36*
G01X278343D02*
X281743D01*
G02Y1382794I0J-1503D01*
G01X278343D01*
G02Y1385800I0J1503D01*
G37*
G36*
G01X1340486Y1398086D02*
X1343886D01*
G02Y1395080I0J-1503D01*
G01X1340486D01*
G02Y1398086I0J1503D01*
G37*
G36*
G01Y1409998D02*
X1343886D01*
G02Y1406992I0J-1503D01*
G01X1340486D01*
G02Y1409998I0J1503D01*
G37*
G36*
G01X1583770Y1385800D02*
X1587170D01*
G02Y1382794I0J-1503D01*
G01X1583770D01*
G02Y1385800I0J1503D01*
G37*
G36*
G01X1571530Y1349690D02*
X1574930D01*
G02Y1346684I0J-1503D01*
G01X1571530D01*
G02Y1349690I0J1503D01*
G37*
G36*
G01Y1373888D02*
X1574930D01*
G02Y1370882I0J-1503D01*
G01X1571530D01*
G02Y1373888I0J1503D01*
G37*
G36*
G01Y1385800D02*
X1574930D01*
G02Y1382794I0J-1503D01*
G01X1571530D01*
G02Y1385800I0J1503D01*
G37*
G36*
G01X1473610Y1398086D02*
X1477010D01*
G02Y1395080I0J-1503D01*
G01X1473610D01*
G02Y1398086I0J1503D01*
G37*
G36*
G01Y1409998D02*
X1477010D01*
G02Y1406992I0J-1503D01*
G01X1473610D01*
G02Y1409998I0J1503D01*
G37*
G36*
G01X1583770Y1398086D02*
X1587170D01*
G02Y1395080I0J-1503D01*
G01X1583770D01*
G02Y1398086I0J1503D01*
G37*
G36*
G01Y1409998D02*
X1587170D01*
G02Y1406992I0J-1503D01*
G01X1583770D01*
G02Y1409998I0J1503D01*
G37*
G36*
G01X1485850Y1398086D02*
X1489250D01*
G02Y1395080I0J-1503D01*
G01X1485850D01*
G02Y1398086I0J1503D01*
G37*
G36*
G01X1498090Y1373888D02*
X1501490D01*
G02Y1370882I0J-1503D01*
G01X1498090D01*
G02Y1373888I0J1503D01*
G37*
G36*
G01X1522570Y1361602D02*
X1525970D01*
G02Y1358596I0J-1503D01*
G01X1522570D01*
G02Y1361602I0J1503D01*
G37*
G36*
G01X1498090Y1409998D02*
X1501490D01*
G02Y1406992I0J-1503D01*
G01X1498090D01*
G02Y1409998I0J1503D01*
G37*
G36*
G01X1352726Y1349690D02*
X1356126D01*
G02Y1346684I0J-1503D01*
G01X1352726D01*
G02Y1349690I0J1503D01*
G37*
G36*
G01X1510330Y1398086D02*
X1513730D01*
G02Y1395080I0J-1503D01*
G01X1510330D01*
G02Y1398086I0J1503D01*
G37*
G36*
G01X1611398Y1361602D02*
X1614798D01*
G02Y1358596I0J-1503D01*
G01X1611398D01*
G02Y1361602I0J1503D01*
G37*
G36*
G01X1623638Y1373888D02*
X1627038D01*
G02Y1370882I0J-1503D01*
G01X1623638D01*
G02Y1373888I0J1503D01*
G37*
G36*
G01X1547050D02*
X1550450D01*
G02Y1370882I0J-1503D01*
G01X1547050D01*
G02Y1373888I0J1503D01*
G37*
G36*
G01X1352726Y1361602D02*
X1356126D01*
G02Y1358596I0J-1503D01*
G01X1352726D01*
G02Y1361602I0J1503D01*
G37*
G36*
G01Y1385800D02*
X1356126D01*
G02Y1382794I0J-1503D01*
G01X1352726D01*
G02Y1385800I0J1503D01*
G37*
G36*
G01Y1373888D02*
X1356126D01*
G02Y1370882I0J-1503D01*
G01X1352726D01*
G02Y1373888I0J1503D01*
G37*
G36*
G01X1684838Y1409998D02*
X1688238D01*
G02Y1406992I0J-1503D01*
G01X1684838D01*
G02Y1409998I0J1503D01*
G37*
G36*
G01X1709318Y1373888D02*
X1712718D01*
G02Y1370882I0J-1503D01*
G01X1709318D01*
G02Y1373888I0J1503D01*
G37*
G36*
G01Y1385800D02*
X1712718D01*
G02Y1382794I0J-1503D01*
G01X1709318D01*
G02Y1385800I0J1503D01*
G37*
G36*
G01X1733798Y1361602D02*
X1737198D01*
G02Y1358596I0J-1503D01*
G01X1733798D01*
G02Y1361602I0J1503D01*
G37*
G36*
G01X1697078Y1373888D02*
X1700478D01*
G02Y1370882I0J-1503D01*
G01X1697078D01*
G02Y1373888I0J1503D01*
G37*
G36*
G01X1709318Y1409998D02*
X1712718D01*
G02Y1406992I0J-1503D01*
G01X1709318D01*
G02Y1409998I0J1503D01*
G37*
G36*
G01X1697078Y1398086D02*
X1700478D01*
G02Y1395080I0J-1503D01*
G01X1697078D01*
G02Y1398086I0J1503D01*
G37*
G36*
G01X1709318D02*
X1712718D01*
G02Y1395080I0J-1503D01*
G01X1709318D01*
G02Y1398086I0J1503D01*
G37*
G36*
G01X1721558Y1349690D02*
X1724958D01*
G02Y1346684I0J-1503D01*
G01X1721558D01*
G02Y1349690I0J1503D01*
G37*
G36*
G01Y1361602D02*
X1724958D01*
G02Y1358596I0J-1503D01*
G01X1721558D01*
G02Y1361602I0J1503D01*
G37*
G36*
G01Y1409998D02*
X1724958D01*
G02Y1406992I0J-1503D01*
G01X1721558D01*
G02Y1409998I0J1503D01*
G37*
G36*
G01X1352726Y1398086D02*
X1356126D01*
G02Y1395080I0J-1503D01*
G01X1352726D01*
G02Y1398086I0J1503D01*
G37*
G36*
G01X174032Y1361602D02*
X177432D01*
G02Y1358596I0J-1503D01*
G01X174032D01*
G02Y1361602I0J1503D01*
G37*
G36*
G01X198512Y1349690D02*
X201912D01*
G02Y1346684I0J-1503D01*
G01X198512D01*
G02Y1349690I0J1503D01*
G37*
G36*
G01Y1398086D02*
X201912D01*
G02Y1395080I0J-1503D01*
G01X198512D01*
G02Y1398086I0J1503D01*
G37*
G36*
G01X186272D02*
X189672D01*
G02Y1395080I0J-1503D01*
G01X186272D01*
G02Y1398086I0J1503D01*
G37*
G36*
G01X161792Y1349690D02*
X165192D01*
G02Y1346684I0J-1503D01*
G01X161792D01*
G02Y1349690I0J1503D01*
G37*
G36*
G01X186272Y1361602D02*
X189672D01*
G02Y1358596I0J-1503D01*
G01X186272D01*
G02Y1361602I0J1503D01*
G37*
G36*
G01X100592Y1349690D02*
X103992D01*
G02Y1346684I0J-1503D01*
G01X100592D01*
G02Y1349690I0J1503D01*
G37*
G36*
G01X112832D02*
X116232D01*
G02Y1346684I0J-1503D01*
G01X112832D01*
G02Y1349690I0J1503D01*
G37*
G36*
G01X149552Y1398086D02*
X152952D01*
G02Y1395080I0J-1503D01*
G01X149552D01*
G02Y1398086I0J1503D01*
G37*
G36*
G01X161792D02*
X165192D01*
G02Y1395080I0J-1503D01*
G01X161792D01*
G02Y1398086I0J1503D01*
G37*
G36*
G01Y1373888D02*
X165192D01*
G02Y1370882I0J-1503D01*
G01X161792D01*
G02Y1373888I0J1503D01*
G37*
G36*
G01Y1385800D02*
X165192D01*
G02Y1382794I0J-1503D01*
G01X161792D01*
G02Y1385800I0J1503D01*
G37*
G36*
G01X198512Y1361602D02*
X201912D01*
G02Y1358596I0J-1503D01*
G01X198512D01*
G02Y1361602I0J1503D01*
G37*
G36*
G01X137312D02*
X140712D01*
G02Y1358596I0J-1503D01*
G01X137312D01*
G02Y1361602I0J1503D01*
G37*
G36*
G01X161792D02*
X165192D01*
G02Y1358596I0J-1503D01*
G01X161792D01*
G02Y1361602I0J1503D01*
G37*
G36*
G01X149552Y1349690D02*
X152952D01*
G02Y1346684I0J-1503D01*
G01X149552D01*
G02Y1349690I0J1503D01*
G37*
G36*
G01X137312D02*
X140712D01*
G02Y1346684I0J-1503D01*
G01X137312D01*
G02Y1349690I0J1503D01*
G37*
G36*
G01X76112Y1361602D02*
X79512D01*
G02Y1358596I0J-1503D01*
G01X76112D01*
G02Y1361602I0J1503D01*
G37*
G36*
G01X174032Y1385800D02*
X177432D01*
G02Y1382794I0J-1503D01*
G01X174032D01*
G02Y1385800I0J1503D01*
G37*
G36*
G01X125072Y1409998D02*
X128472D01*
G02Y1406992I0J-1503D01*
G01X125072D01*
G02Y1409998I0J1503D01*
G37*
G36*
G01Y1398086D02*
X128472D01*
G02Y1395080I0J-1503D01*
G01X125072D01*
G02Y1398086I0J1503D01*
G37*
G36*
G01Y1373888D02*
X128472D01*
G02Y1370882I0J-1503D01*
G01X125072D01*
G02Y1373888I0J1503D01*
G37*
G36*
G01Y1385800D02*
X128472D01*
G02Y1382794I0J-1503D01*
G01X125072D01*
G02Y1385800I0J1503D01*
G37*
G36*
G01X1571530Y1361602D02*
X1574930D01*
G02Y1358596I0J-1503D01*
G01X1571530D01*
G02Y1361602I0J1503D01*
G37*
G36*
G01X100592Y1385800D02*
X103992D01*
G02Y1382794I0J-1503D01*
G01X100592D01*
G02Y1385800I0J1503D01*
G37*
G36*
G01X76112Y1373888D02*
X79512D01*
G02Y1370882I0J-1503D01*
G01X76112D01*
G02Y1373888I0J1503D01*
G37*
G36*
G01X88352Y1409998D02*
X91752D01*
G02Y1406992I0J-1503D01*
G01X88352D01*
G02Y1409998I0J1503D01*
G37*
G36*
G01X149552D02*
X152952D01*
G02Y1406992I0J-1503D01*
G01X149552D01*
G02Y1409998I0J1503D01*
G37*
G36*
G01X137312Y1373888D02*
X140712D01*
G02Y1370882I0J-1503D01*
G01X137312D01*
G02Y1373888I0J1503D01*
G37*
G36*
G01X253863Y1385800D02*
X257263D01*
G02Y1382794I0J-1503D01*
G01X253863D01*
G02Y1385800I0J1503D01*
G37*
G36*
G01X186272Y1409998D02*
X189672D01*
G02Y1406992I0J-1503D01*
G01X186272D01*
G02Y1409998I0J1503D01*
G37*
G36*
G01X125072Y1361602D02*
X128472D01*
G02Y1358596I0J-1503D01*
G01X125072D01*
G02Y1361602I0J1503D01*
G37*
G36*
G01Y1349690D02*
X128472D01*
G02Y1346684I0J-1503D01*
G01X125072D01*
G02Y1349690I0J1503D01*
G37*
G36*
G01X149552Y1373888D02*
X152952D01*
G02Y1370882I0J-1503D01*
G01X149552D01*
G02Y1373888I0J1503D01*
G37*
G36*
G01X174032Y1349690D02*
X177432D01*
G02Y1346684I0J-1503D01*
G01X174032D01*
G02Y1349690I0J1503D01*
G37*
G36*
G01Y1373888D02*
X177432D01*
G02Y1370882I0J-1503D01*
G01X174032D01*
G02Y1373888I0J1503D01*
G37*
G36*
G01X76112Y1385800D02*
X79512D01*
G02Y1382794I0J-1503D01*
G01X76112D01*
G02Y1385800I0J1503D01*
G37*
G36*
G01X1583770Y1349690D02*
X1587170D01*
G02Y1346684I0J-1503D01*
G01X1583770D01*
G02Y1349690I0J1503D01*
G37*
G36*
G01X1697078Y1385800D02*
X1700478D01*
G02Y1382794I0J-1503D01*
G01X1697078D01*
G02Y1385800I0J1503D01*
G37*
G36*
G01X88352Y1361602D02*
X91752D01*
G02Y1358596I0J-1503D01*
G01X88352D01*
G02Y1361602I0J1503D01*
G37*
G36*
G01Y1349690D02*
X91752D01*
G02Y1346684I0J-1503D01*
G01X88352D01*
G02Y1349690I0J1503D01*
G37*
G36*
G01X1697078Y1409998D02*
X1700478D01*
G02Y1406992I0J-1503D01*
G01X1697078D01*
G02Y1409998I0J1503D01*
G37*
G36*
G01X112832Y1373888D02*
X116232D01*
G02Y1370882I0J-1503D01*
G01X112832D01*
G02Y1373888I0J1503D01*
G37*
G36*
G01Y1409998D02*
X116232D01*
G02Y1406992I0J-1503D01*
G01X112832D01*
G02Y1409998I0J1503D01*
G37*
G36*
G01X100592D02*
X103992D01*
G02Y1406992I0J-1503D01*
G01X100592D01*
G02Y1409998I0J1503D01*
G37*
G36*
G01X724208Y1385800D02*
X727608D01*
G02Y1382794I0J-1503D01*
G01X724208D01*
G02Y1385800I0J1503D01*
G37*
G36*
G01X88352D02*
X91752D01*
G02Y1382794I0J-1503D01*
G01X88352D01*
G02Y1385800I0J1503D01*
G37*
G36*
G01X760928Y1361602D02*
X764328D01*
G02Y1358596I0J-1503D01*
G01X760928D01*
G02Y1361602I0J1503D01*
G37*
G36*
G01X100592Y1373888D02*
X103992D01*
G02Y1370882I0J-1503D01*
G01X100592D01*
G02Y1373888I0J1503D01*
G37*
G36*
G01X137312Y1398086D02*
X140712D01*
G02Y1395080I0J-1503D01*
G01X137312D01*
G02Y1398086I0J1503D01*
G37*
G36*
G01Y1409998D02*
X140712D01*
G02Y1406992I0J-1503D01*
G01X137312D01*
G02Y1409998I0J1503D01*
G37*
G36*
G01X112832Y1385800D02*
X116232D01*
G02Y1382794I0J-1503D01*
G01X112832D01*
G02Y1385800I0J1503D01*
G37*
G36*
G01X663008Y1361602D02*
X666408D01*
G02Y1358596I0J-1503D01*
G01X663008D01*
G02Y1361602I0J1503D01*
G37*
G36*
G01X100592Y1398086D02*
X103992D01*
G02Y1395080I0J-1503D01*
G01X100592D01*
G02Y1398086I0J1503D01*
G37*
G36*
G01X748688Y1385800D02*
X752088D01*
G02Y1382794I0J-1503D01*
G01X748688D01*
G02Y1385800I0J1503D01*
G37*
G36*
G01X1352726Y1409998D02*
X1356126D01*
G02Y1406992I0J-1503D01*
G01X1352726D01*
G02Y1409998I0J1503D01*
G37*
G36*
G01X100592Y1361602D02*
X103992D01*
G02Y1358596I0J-1503D01*
G01X100592D01*
G02Y1361602I0J1503D01*
G37*
G36*
G01X112832D02*
X116232D01*
G02Y1358596I0J-1503D01*
G01X112832D01*
G02Y1361602I0J1503D01*
G37*
G36*
G01X88352Y1398086D02*
X91752D01*
G02Y1395080I0J-1503D01*
G01X88352D01*
G02Y1398086I0J1503D01*
G37*
G36*
G01X1660358Y1361602D02*
X1663758D01*
G02Y1358596I0J-1503D01*
G01X1660358D01*
G02Y1361602I0J1503D01*
G37*
G36*
G01X1066953Y1349690D02*
X1070353D01*
G02Y1346684I0J-1503D01*
G01X1066953D01*
G02Y1349690I0J1503D01*
G37*
G36*
G01X663008D02*
X666408D01*
G02Y1346684I0J-1503D01*
G01X663008D01*
G02Y1349690I0J1503D01*
G37*
G36*
G01X1583770Y1361602D02*
X1587170D01*
G02Y1358596I0J-1503D01*
G01X1583770D01*
G02Y1361602I0J1503D01*
G37*
G36*
G01X1571530Y1398086D02*
X1574930D01*
G02Y1395080I0J-1503D01*
G01X1571530D01*
G02Y1398086I0J1503D01*
G37*
G36*
G01X1559290Y1361602D02*
X1562690D01*
G02Y1358596I0J-1503D01*
G01X1559290D01*
G02Y1361602I0J1503D01*
G37*
G36*
G01Y1373888D02*
X1562690D01*
G02Y1370882I0J-1503D01*
G01X1559290D01*
G02Y1373888I0J1503D01*
G37*
G36*
G01X1623638Y1385800D02*
X1627038D01*
G02Y1382794I0J-1503D01*
G01X1623638D01*
G02Y1385800I0J1503D01*
G37*
G36*
G01X76112Y1349690D02*
X79512D01*
G02Y1346684I0J-1503D01*
G01X76112D01*
G02Y1349690I0J1503D01*
G37*
G36*
G01X1066953Y1361602D02*
X1070353D01*
G02Y1358596I0J-1503D01*
G01X1066953D01*
G02Y1361602I0J1503D01*
G37*
G36*
G01X1547050Y1385800D02*
X1550450D01*
G02Y1382794I0J-1503D01*
G01X1547050D01*
G02Y1385800I0J1503D01*
G37*
G36*
G01X1672598Y1349690D02*
X1675998D01*
G02Y1346684I0J-1503D01*
G01X1672598D01*
G02Y1349690I0J1503D01*
G37*
G36*
G01X1660358D02*
X1663758D01*
G02Y1346684I0J-1503D01*
G01X1660358D01*
G02Y1349690I0J1503D01*
G37*
G36*
G01X1672598Y1361602D02*
X1675998D01*
G02Y1358596I0J-1503D01*
G01X1672598D01*
G02Y1361602I0J1503D01*
G37*
G36*
G01X1709318Y1349690D02*
X1712718D01*
G02Y1346684I0J-1503D01*
G01X1709318D01*
G02Y1349690I0J1503D01*
G37*
G36*
G01X1697078D02*
X1700478D01*
G02Y1346684I0J-1503D01*
G01X1697078D01*
G02Y1349690I0J1503D01*
G37*
G36*
G01X1684838Y1385800D02*
X1688238D01*
G02Y1382794I0J-1503D01*
G01X1684838D01*
G02Y1385800I0J1503D01*
G37*
G36*
G01X1709318Y1361602D02*
X1712718D01*
G02Y1358596I0J-1503D01*
G01X1709318D01*
G02Y1361602I0J1503D01*
G37*
G36*
G01X1697078D02*
X1700478D01*
G02Y1358596I0J-1503D01*
G01X1697078D01*
G02Y1361602I0J1503D01*
G37*
G36*
G01X1684838D02*
X1688238D01*
G02Y1358596I0J-1503D01*
G01X1684838D01*
G02Y1361602I0J1503D01*
G37*
G36*
G01Y1373888D02*
X1688238D01*
G02Y1370882I0J-1503D01*
G01X1684838D01*
G02Y1373888I0J1503D01*
G37*
G36*
G01Y1398086D02*
X1688238D01*
G02Y1395080I0J-1503D01*
G01X1684838D01*
G02Y1398086I0J1503D01*
G37*
G36*
G01X1066953Y1373888D02*
X1070353D01*
G02Y1370882I0J-1503D01*
G01X1066953D01*
G02Y1373888I0J1503D01*
G37*
G36*
G01Y1385800D02*
X1070353D01*
G02Y1382794I0J-1503D01*
G01X1066953D01*
G02Y1385800I0J1503D01*
G37*
G36*
G01X1547050Y1398086D02*
X1550450D01*
G02Y1395080I0J-1503D01*
G01X1547050D01*
G02Y1398086I0J1503D01*
G37*
G36*
G01X549168Y783102D02*
G02Y780098I0J-1502D01*
G01X545813D01*
X545808D01*
G02X545944Y783092I-38J1502D01*
G01X545956Y783090D01*
X548978D01*
X548990Y783092D01*
G02X549168Y783102I173J-1492D01*
G37*
G36*
G01X278343Y1349690D02*
X281743D01*
G02Y1346684I0J-1503D01*
G01X278343D01*
G02Y1349690I0J1503D01*
G37*
G36*
G01X945982Y888540D02*
X949382D01*
G02Y884936I0J-1802D01*
G01X945982D01*
G02Y888540I0J1802D01*
G37*
G36*
G01X1684838Y1349690D02*
X1688238D01*
G02Y1346684I0J-1503D01*
G01X1684838D01*
G02Y1349690I0J1503D01*
G37*
G36*
G01X1571530Y1409998D02*
X1574930D01*
G02Y1406992I0J-1503D01*
G01X1571530D01*
G02Y1409998I0J1503D01*
G37*
G36*
G01X1473610Y1373888D02*
X1477010D01*
G02Y1370882I0J-1503D01*
G01X1473610D01*
G02Y1373888I0J1503D01*
G37*
G36*
G01X1498090Y1398086D02*
X1501490D01*
G02Y1395080I0J-1503D01*
G01X1498090D01*
G02Y1398086I0J1503D01*
G37*
G36*
G01Y1385800D02*
X1501490D01*
G02Y1382794I0J-1503D01*
G01X1498090D01*
G02Y1385800I0J1503D01*
G37*
G36*
G01X1510330Y1409998D02*
X1513730D01*
G02Y1406992I0J-1503D01*
G01X1510330D01*
G02Y1409998I0J1503D01*
G37*
G36*
G01X1522570Y1349690D02*
X1525970D01*
G02Y1346684I0J-1503D01*
G01X1522570D01*
G02Y1349690I0J1503D01*
G37*
G36*
G01X146948Y1135604D02*
X143208D01*
G02Y1138210I0J1303D01*
G01X146948D01*
G02Y1135604I0J-1303D01*
G37*
G36*
G01X165649Y1131864D02*
X161909D01*
G02Y1134470I0J1303D01*
G01X165649D01*
G02Y1131864I0J-1303D01*
G37*
G36*
G01X154429D02*
X150689D01*
G02Y1134470I0J1303D01*
G01X154429D01*
G02Y1131864I0J-1303D01*
G37*
G36*
G01X173129Y1135604D02*
X169389D01*
G02Y1138210I0J1303D01*
G01X173129D01*
G02Y1135604I0J-1303D01*
G37*
G36*
G01X440402Y1361602D02*
X443802D01*
G02Y1358596I0J-1503D01*
G01X440402D01*
G02Y1361602I0J1503D01*
G37*
G36*
G01Y1349690D02*
X443802D01*
G02Y1346684I0J-1503D01*
G01X440402D01*
G02Y1349690I0J1503D01*
G37*
G36*
G01X452642Y1361602D02*
X456042D01*
G02Y1358596I0J-1503D01*
G01X452642D01*
G02Y1361602I0J1503D01*
G37*
G36*
G01Y1349690D02*
X456042D01*
G02Y1346684I0J-1503D01*
G01X452642D01*
G02Y1349690I0J1503D01*
G37*
G36*
G01X501602Y1385800D02*
X505002D01*
G02Y1382794I0J-1503D01*
G01X501602D01*
G02Y1385800I0J1503D01*
G37*
G36*
G01X513842D02*
X517242D01*
G02Y1382794I0J-1503D01*
G01X513842D01*
G02Y1385800I0J1503D01*
G37*
G36*
G01Y1373888D02*
X517242D01*
G02Y1370882I0J-1503D01*
G01X513842D01*
G02Y1373888I0J1503D01*
G37*
G36*
G01X501602D02*
X505002D01*
G02Y1370882I0J-1503D01*
G01X501602D01*
G02Y1373888I0J1503D01*
G37*
G36*
G01X464882Y1349690D02*
X468282D01*
G02Y1346684I0J-1503D01*
G01X464882D01*
G02Y1349690I0J1503D01*
G37*
G36*
G01X477122D02*
X480522D01*
G02Y1346684I0J-1503D01*
G01X477122D01*
G02Y1349690I0J1503D01*
G37*
G36*
G01X526082Y1385800D02*
X529482D01*
G02Y1382794I0J-1503D01*
G01X526082D01*
G02Y1385800I0J1503D01*
G37*
G36*
G01X538322D02*
X541722D01*
G02Y1382794I0J-1503D01*
G01X538322D01*
G02Y1385800I0J1503D01*
G37*
G36*
G01X526082Y1373888D02*
X529482D01*
G02Y1370882I0J-1503D01*
G01X526082D01*
G02Y1373888I0J1503D01*
G37*
G36*
G01X538322D02*
X541722D01*
G02Y1370882I0J-1503D01*
G01X538322D01*
G02Y1373888I0J1503D01*
G37*
G36*
G01X464882Y1361602D02*
X468282D01*
G02Y1358596I0J-1503D01*
G01X464882D01*
G02Y1361602I0J1503D01*
G37*
G36*
G01X477122D02*
X480522D01*
G02Y1358596I0J-1503D01*
G01X477122D01*
G02Y1361602I0J1503D01*
G37*
G36*
G01X489362Y1349690D02*
X492762D01*
G02Y1346684I0J-1503D01*
G01X489362D01*
G02Y1349690I0J1503D01*
G37*
G36*
G01X440402Y1373888D02*
X443802D01*
G02Y1370882I0J-1503D01*
G01X440402D01*
G02Y1373888I0J1503D01*
G37*
G36*
G01X550562Y1385800D02*
X553962D01*
G02Y1382794I0J-1503D01*
G01X550562D01*
G02Y1385800I0J1503D01*
G37*
G36*
G01Y1373888D02*
X553962D01*
G02Y1370882I0J-1503D01*
G01X550562D01*
G02Y1373888I0J1503D01*
G37*
G36*
G01X489362Y1361602D02*
X492762D01*
G02Y1358596I0J-1503D01*
G01X489362D01*
G02Y1361602I0J1503D01*
G37*
G36*
G01X440402Y1385800D02*
X443802D01*
G02Y1382794I0J-1503D01*
G01X440402D01*
G02Y1385800I0J1503D01*
G37*
G36*
G01X452642Y1373888D02*
X456042D01*
G02Y1370882I0J-1503D01*
G01X452642D01*
G02Y1373888I0J1503D01*
G37*
G36*
G01X562802Y1385800D02*
X566202D01*
G02Y1382794I0J-1503D01*
G01X562802D01*
G02Y1385800I0J1503D01*
G37*
G36*
G01X452642Y1409998D02*
X456042D01*
G02Y1406992I0J-1503D01*
G01X452642D01*
G02Y1409998I0J1503D01*
G37*
G36*
G01Y1398086D02*
X456042D01*
G02Y1395080I0J-1503D01*
G01X452642D01*
G02Y1398086I0J1503D01*
G37*
G36*
G01X562802Y1373888D02*
X566202D01*
G02Y1370882I0J-1503D01*
G01X562802D01*
G02Y1373888I0J1503D01*
G37*
G36*
G01X452642Y1385800D02*
X456042D01*
G02Y1382794I0J-1503D01*
G01X452642D01*
G02Y1385800I0J1503D01*
G37*
G36*
G01X464882Y1409998D02*
X468282D01*
G02Y1406992I0J-1503D01*
G01X464882D01*
G02Y1409998I0J1503D01*
G37*
G36*
G01Y1398086D02*
X468282D01*
G02Y1395080I0J-1503D01*
G01X464882D01*
G02Y1398086I0J1503D01*
G37*
G36*
G01Y1385800D02*
X468282D01*
G02Y1382794I0J-1503D01*
G01X464882D01*
G02Y1385800I0J1503D01*
G37*
G36*
G01X477122D02*
X480522D01*
G02Y1382794I0J-1503D01*
G01X477122D01*
G02Y1385800I0J1503D01*
G37*
G36*
G01Y1373888D02*
X480522D01*
G02Y1370882I0J-1503D01*
G01X477122D01*
G02Y1373888I0J1503D01*
G37*
G36*
G01X464882D02*
X468282D01*
G02Y1370882I0J-1503D01*
G01X464882D01*
G02Y1373888I0J1503D01*
G37*
G36*
G01X489362D02*
X492762D01*
G02Y1370882I0J-1503D01*
G01X489362D01*
G02Y1373888I0J1503D01*
G37*
G36*
G01Y1409998D02*
X492762D01*
G02Y1406992I0J-1503D01*
G01X489362D01*
G02Y1409998I0J1503D01*
G37*
G36*
G01Y1398086D02*
X492762D01*
G02Y1395080I0J-1503D01*
G01X489362D01*
G02Y1398086I0J1503D01*
G37*
G36*
G01X477122Y1409998D02*
X480522D01*
G02Y1406992I0J-1503D01*
G01X477122D01*
G02Y1409998I0J1503D01*
G37*
G36*
G01Y1398086D02*
X480522D01*
G02Y1395080I0J-1503D01*
G01X477122D01*
G02Y1398086I0J1503D01*
G37*
G36*
G01X489362Y1385800D02*
X492762D01*
G02Y1382794I0J-1503D01*
G01X489362D01*
G02Y1385800I0J1503D01*
G37*
G36*
G01X501602Y1361602D02*
X505002D01*
G02Y1358596I0J-1503D01*
G01X501602D01*
G02Y1361602I0J1503D01*
G37*
G36*
G01X513842D02*
X517242D01*
G02Y1358596I0J-1503D01*
G01X513842D01*
G02Y1361602I0J1503D01*
G37*
G36*
G01X501602Y1349690D02*
X505002D01*
G02Y1346684I0J-1503D01*
G01X501602D01*
G02Y1349690I0J1503D01*
G37*
G36*
G01X513842D02*
X517242D01*
G02Y1346684I0J-1503D01*
G01X513842D01*
G02Y1349690I0J1503D01*
G37*
G36*
G01X501602Y1398086D02*
X505002D01*
G02Y1395080I0J-1503D01*
G01X501602D01*
G02Y1398086I0J1503D01*
G37*
G36*
G01Y1409998D02*
X505002D01*
G02Y1406992I0J-1503D01*
G01X501602D01*
G02Y1409998I0J1503D01*
G37*
G36*
G01X526082Y1361602D02*
X529482D01*
G02Y1358596I0J-1503D01*
G01X526082D01*
G02Y1361602I0J1503D01*
G37*
G36*
G01Y1349690D02*
X529482D01*
G02Y1346684I0J-1503D01*
G01X526082D01*
G02Y1349690I0J1503D01*
G37*
G36*
G01X513842Y1398086D02*
X517242D01*
G02Y1395080I0J-1503D01*
G01X513842D01*
G02Y1398086I0J1503D01*
G37*
G36*
G01X526082Y1409998D02*
X529482D01*
G02Y1406992I0J-1503D01*
G01X526082D01*
G02Y1409998I0J1503D01*
G37*
G36*
G01X513842D02*
X517242D01*
G02Y1406992I0J-1503D01*
G01X513842D01*
G02Y1409998I0J1503D01*
G37*
G36*
G01X526082Y1398086D02*
X529482D01*
G02Y1395080I0J-1503D01*
G01X526082D01*
G02Y1398086I0J1503D01*
G37*
G36*
G01X538322Y1361602D02*
X541722D01*
G02Y1358596I0J-1503D01*
G01X538322D01*
G02Y1361602I0J1503D01*
G37*
G36*
G01X550562D02*
X553962D01*
G02Y1358596I0J-1503D01*
G01X550562D01*
G02Y1361602I0J1503D01*
G37*
G36*
G01X538322Y1349690D02*
X541722D01*
G02Y1346684I0J-1503D01*
G01X538322D01*
G02Y1349690I0J1503D01*
G37*
G36*
G01X550562D02*
X553962D01*
G02Y1346684I0J-1503D01*
G01X550562D01*
G02Y1349690I0J1503D01*
G37*
G36*
G01X538322Y1398086D02*
X541722D01*
G02Y1395080I0J-1503D01*
G01X538322D01*
G02Y1398086I0J1503D01*
G37*
G36*
G01Y1409998D02*
X541722D01*
G02Y1406992I0J-1503D01*
G01X538322D01*
G02Y1409998I0J1503D01*
G37*
G36*
G01X562802Y1361602D02*
X566202D01*
G02Y1358596I0J-1503D01*
G01X562802D01*
G02Y1361602I0J1503D01*
G37*
G36*
G01Y1349690D02*
X566202D01*
G02Y1346684I0J-1503D01*
G01X562802D01*
G02Y1349690I0J1503D01*
G37*
G36*
G01X550562Y1398086D02*
X553962D01*
G02Y1395080I0J-1503D01*
G01X550562D01*
G02Y1398086I0J1503D01*
G37*
G36*
G01X562802D02*
X566202D01*
G02Y1395080I0J-1503D01*
G01X562802D01*
G02Y1398086I0J1503D01*
G37*
G36*
G01X550562Y1409998D02*
X553962D01*
G02Y1406992I0J-1503D01*
G01X550562D01*
G02Y1409998I0J1503D01*
G37*
G36*
G01X562802D02*
X566202D01*
G02Y1406992I0J-1503D01*
G01X562802D01*
G02Y1409998I0J1503D01*
G37*
G36*
G01X650768Y1361602D02*
X654168D01*
G02Y1358596I0J-1503D01*
G01X650768D01*
G02Y1361602I0J1503D01*
G37*
G36*
G01Y1349690D02*
X654168D01*
G02Y1346684I0J-1503D01*
G01X650768D01*
G02Y1349690I0J1503D01*
G37*
G36*
G01X626288Y1409998D02*
X629688D01*
G02Y1406992I0J-1503D01*
G01X626288D01*
G02Y1409998I0J1503D01*
G37*
G36*
G01X638528Y1385800D02*
X641928D01*
G02Y1382794I0J-1503D01*
G01X638528D01*
G02Y1385800I0J1503D01*
G37*
G36*
G01Y1373888D02*
X641928D01*
G02Y1370882I0J-1503D01*
G01X638528D01*
G02Y1373888I0J1503D01*
G37*
G36*
G01X626288Y1398086D02*
X629688D01*
G02Y1395080I0J-1503D01*
G01X626288D01*
G02Y1398086I0J1503D01*
G37*
G36*
G01X675248Y1361602D02*
X678648D01*
G02Y1358596I0J-1503D01*
G01X675248D01*
G02Y1361602I0J1503D01*
G37*
G36*
G01X650768Y1385800D02*
X654168D01*
G02Y1382794I0J-1503D01*
G01X650768D01*
G02Y1385800I0J1503D01*
G37*
G36*
G01X675248Y1349690D02*
X678648D01*
G02Y1346684I0J-1503D01*
G01X675248D01*
G02Y1349690I0J1503D01*
G37*
G36*
G01X650768Y1373888D02*
X654168D01*
G02Y1370882I0J-1503D01*
G01X650768D01*
G02Y1373888I0J1503D01*
G37*
G36*
G01X638528Y1409998D02*
X641928D01*
G02Y1406992I0J-1503D01*
G01X638528D01*
G02Y1409998I0J1503D01*
G37*
G36*
G01Y1398086D02*
X641928D01*
G02Y1395080I0J-1503D01*
G01X638528D01*
G02Y1398086I0J1503D01*
G37*
G36*
G01X687488Y1361602D02*
X690888D01*
G02Y1358596I0J-1503D01*
G01X687488D01*
G02Y1361602I0J1503D01*
G37*
G36*
G01Y1349690D02*
X690888D01*
G02Y1346684I0J-1503D01*
G01X687488D01*
G02Y1349690I0J1503D01*
G37*
G36*
G01X663008Y1385800D02*
X666408D01*
G02Y1382794I0J-1503D01*
G01X663008D01*
G02Y1385800I0J1503D01*
G37*
G36*
G01X650768Y1409998D02*
X654168D01*
G02Y1406992I0J-1503D01*
G01X650768D01*
G02Y1409998I0J1503D01*
G37*
G36*
G01X663008Y1373888D02*
X666408D01*
G02Y1370882I0J-1503D01*
G01X663008D01*
G02Y1373888I0J1503D01*
G37*
G36*
G01X650768Y1398086D02*
X654168D01*
G02Y1395080I0J-1503D01*
G01X650768D01*
G02Y1398086I0J1503D01*
G37*
G36*
G01X699728Y1361602D02*
X703128D01*
G02Y1358596I0J-1503D01*
G01X699728D01*
G02Y1361602I0J1503D01*
G37*
G36*
G01X687488Y1385800D02*
X690888D01*
G02Y1382794I0J-1503D01*
G01X687488D01*
G02Y1385800I0J1503D01*
G37*
G36*
G01X699728Y1349690D02*
X703128D01*
G02Y1346684I0J-1503D01*
G01X699728D01*
G02Y1349690I0J1503D01*
G37*
G36*
G01X687488Y1373888D02*
X690888D01*
G02Y1370882I0J-1503D01*
G01X687488D01*
G02Y1373888I0J1503D01*
G37*
G36*
G01X675248Y1385800D02*
X678648D01*
G02Y1382794I0J-1503D01*
G01X675248D01*
G02Y1385800I0J1503D01*
G37*
G36*
G01Y1373888D02*
X678648D01*
G02Y1370882I0J-1503D01*
G01X675248D01*
G02Y1373888I0J1503D01*
G37*
G36*
G01X711968Y1349690D02*
X715368D01*
G02Y1346684I0J-1503D01*
G01X711968D01*
G02Y1349690I0J1503D01*
G37*
G36*
G01Y1361602D02*
X715368D01*
G02Y1358596I0J-1503D01*
G01X711968D01*
G02Y1361602I0J1503D01*
G37*
G36*
G01X663008Y1409998D02*
X666408D01*
G02Y1406992I0J-1503D01*
G01X663008D01*
G02Y1409998I0J1503D01*
G37*
G36*
G01X699728Y1385800D02*
X703128D01*
G02Y1382794I0J-1503D01*
G01X699728D01*
G02Y1385800I0J1503D01*
G37*
G36*
G01Y1373888D02*
X703128D01*
G02Y1370882I0J-1503D01*
G01X699728D01*
G02Y1373888I0J1503D01*
G37*
G36*
G01X663008Y1398086D02*
X666408D01*
G02Y1395080I0J-1503D01*
G01X663008D01*
G02Y1398086I0J1503D01*
G37*
G36*
G01X724208Y1397992D02*
X727608D01*
G02Y1394986I0J-1503D01*
G01X724208D01*
G02Y1397992I0J1503D01*
G37*
G36*
G01Y1349690D02*
X727608D01*
G02Y1346684I0J-1503D01*
G01X724208D01*
G02Y1349690I0J1503D01*
G37*
G36*
G01X675248Y1409998D02*
X678648D01*
G02Y1406992I0J-1503D01*
G01X675248D01*
G02Y1409998I0J1503D01*
G37*
G36*
G01Y1398086D02*
X678648D01*
G02Y1395080I0J-1503D01*
G01X675248D01*
G02Y1398086I0J1503D01*
G37*
G36*
G01X724208Y1361602D02*
X727608D01*
G02Y1358596I0J-1503D01*
G01X724208D01*
G02Y1361602I0J1503D01*
G37*
G36*
G01Y1409904D02*
X727608D01*
G02Y1406898I0J-1503D01*
G01X724208D01*
G02Y1409904I0J1503D01*
G37*
G36*
G01X736448Y1349690D02*
X739848D01*
G02Y1346684I0J-1503D01*
G01X736448D01*
G02Y1349690I0J1503D01*
G37*
G36*
G01X711968Y1373888D02*
X715368D01*
G02Y1370882I0J-1503D01*
G01X711968D01*
G02Y1373888I0J1503D01*
G37*
G36*
G01X736448Y1361602D02*
X739848D01*
G02Y1358596I0J-1503D01*
G01X736448D01*
G02Y1361602I0J1503D01*
G37*
G36*
G01X711968Y1385800D02*
X715368D01*
G02Y1382794I0J-1503D01*
G01X711968D01*
G02Y1385800I0J1503D01*
G37*
G36*
G01X687488Y1409998D02*
X690888D01*
G02Y1406992I0J-1503D01*
G01X687488D01*
G02Y1409998I0J1503D01*
G37*
G36*
G01Y1398086D02*
X690888D01*
G02Y1395080I0J-1503D01*
G01X687488D01*
G02Y1398086I0J1503D01*
G37*
G36*
G01X736448Y1373888D02*
X739848D01*
G02Y1370882I0J-1503D01*
G01X736448D01*
G02Y1373888I0J1503D01*
G37*
G36*
G01X748688Y1349690D02*
X752088D01*
G02Y1346684I0J-1503D01*
G01X748688D01*
G02Y1349690I0J1503D01*
G37*
G36*
G01X724208Y1373888D02*
X727608D01*
G02Y1370882I0J-1503D01*
G01X724208D01*
G02Y1373888I0J1503D01*
G37*
G36*
G01X736448Y1385800D02*
X739848D01*
G02Y1382794I0J-1503D01*
G01X736448D01*
G02Y1385800I0J1503D01*
G37*
G36*
G01X748688Y1361602D02*
X752088D01*
G02Y1358596I0J-1503D01*
G01X748688D01*
G02Y1361602I0J1503D01*
G37*
G36*
G01X736448Y1409904D02*
X739848D01*
G02Y1406898I0J-1503D01*
G01X736448D01*
G02Y1409904I0J1503D01*
G37*
G36*
G01Y1397992D02*
X739848D01*
G02Y1394986I0J-1503D01*
G01X736448D01*
G02Y1397992I0J1503D01*
G37*
G36*
G01X699728Y1409998D02*
X703128D01*
G02Y1406992I0J-1503D01*
G01X699728D01*
G02Y1409998I0J1503D01*
G37*
G36*
G01Y1398086D02*
X703128D01*
G02Y1395080I0J-1503D01*
G01X699728D01*
G02Y1398086I0J1503D01*
G37*
G36*
G01X748688Y1373888D02*
X752088D01*
G02Y1370882I0J-1503D01*
G01X748688D01*
G02Y1373888I0J1503D01*
G37*
G36*
G01X773168Y1349690D02*
X776568D01*
G02Y1346684I0J-1503D01*
G01X773168D01*
G02Y1349690I0J1503D01*
G37*
G36*
G01X760928D02*
X764328D01*
G02Y1346684I0J-1503D01*
G01X760928D01*
G02Y1349690I0J1503D01*
G37*
G36*
G01X711968Y1409998D02*
X715368D01*
G02Y1406992I0J-1503D01*
G01X711968D01*
G02Y1409998I0J1503D01*
G37*
G36*
G01Y1398086D02*
X715368D01*
G02Y1395080I0J-1503D01*
G01X711968D01*
G02Y1398086I0J1503D01*
G37*
G36*
G01X773168Y1361602D02*
X776568D01*
G02Y1358596I0J-1503D01*
G01X773168D01*
G02Y1361602I0J1503D01*
G37*
G36*
G01X760928Y1373888D02*
X764328D01*
G02Y1370882I0J-1503D01*
G01X760928D01*
G02Y1373888I0J1503D01*
G37*
G36*
G01Y1385800D02*
X764328D01*
G02Y1382794I0J-1503D01*
G01X760928D01*
G02Y1385800I0J1503D01*
G37*
G36*
G01X149552D02*
X152952D01*
G02Y1382794I0J-1503D01*
G01X149552D01*
G02Y1385800I0J1503D01*
G37*
G36*
G01Y1361602D02*
X152952D01*
G02Y1358596I0J-1503D01*
G01X149552D01*
G02Y1361602I0J1503D01*
G37*
G36*
G01X253863Y1373888D02*
X257263D01*
G02Y1370882I0J-1503D01*
G01X253863D01*
G02Y1373888I0J1503D01*
G37*
G36*
G01X198512D02*
X201912D01*
G02Y1370882I0J-1503D01*
G01X198512D01*
G02Y1373888I0J1503D01*
G37*
G36*
G01Y1409998D02*
X201912D01*
G02Y1406992I0J-1503D01*
G01X198512D01*
G02Y1409998I0J1503D01*
G37*
G36*
G01X364023Y1349690D02*
X367423D01*
G02Y1346684I0J-1503D01*
G01X364023D01*
G02Y1349690I0J1503D01*
G37*
G36*
G01X921754Y329200D02*
G02X921570Y328812I-503J1D01*
G03X921542Y328784I127J-155D01*
G02X921154Y328600I-389J319D01*
G01X920352D01*
G02X920203Y328622I-2J502D01*
G03X920025Y328592I-59J-191D01*
G01X919765Y328399D01*
G03X919684Y328236I119J-161D01*
G01Y327739D01*
G03X919756Y327585I200J0D01*
G01X919993Y327388D01*
G03X920159Y327346I127J154D01*
G02X920251Y327354I89J-494D01*
G01X921252D01*
G02X921754Y326852I0J-502D01*
G01Y326052D01*
G02X921252Y325550I-502J0D01*
G01X920253D01*
X920251D01*
G02X920159Y325558I-3J502D01*
G03X919993Y325516I-39J-196D01*
G01X919756Y325319D01*
G03X919684Y325165I128J-154D01*
G01Y324817D01*
G02X919608Y324297I-1802J-2D01*
G03X919928Y324086I191J-58D01*
G02X919935Y324092I331J-379D01*
G03X919962Y324119I-127J154D01*
G02X920350Y324304I389J-317D01*
G01X921154D01*
G02X921542Y324120I-1J-503D01*
G03X921570Y324092I155J127D01*
G02X921754Y323704I-319J-389D01*
G01Y322900D01*
G02X921570Y322512I-503J1D01*
G03X921542Y322484I127J-155D01*
G02X921154Y322300I-389J319D01*
G01X920350D01*
G02X919962Y322484I1J503D01*
G03X919934Y322512I-155J-127D01*
G02X919750Y322900I319J389D01*
G01Y323706D01*
G03X919383Y323819I-200J2D01*
G02X917882Y323014I-1501J997D01*
G02X916863Y323330I1J1803D01*
G01X916818Y323361D01*
X916706Y323368D01*
X916345Y323177D01*
G03X916238Y323000I93J-177D01*
G01Y322902D01*
G02X916053Y322512I-504J0D01*
G03X916025Y322484I127J-155D01*
G02X915637Y322300I-389J319D01*
G01X914833D01*
G02X914445Y322484I1J503D01*
G03X914417Y322512I-155J-127D01*
G02X914232Y322902I319J390D01*
G01Y323702D01*
G02X914417Y324092I504J0D01*
G03X914445Y324120I-127J155D01*
G02X914833Y324304I389J-319D01*
G01X915655D01*
X915667D01*
X915704Y324302D01*
X915783Y324331D01*
X916054Y324603D01*
X916084Y324681D01*
X916082Y324724D01*
G02X916080Y324817I1800J85D01*
G01Y325365D01*
G03X915880Y325565I-200J0D01*
G01X915859D01*
X915838Y325560D01*
G02X915735Y325550I-100J492D01*
G01X914733D01*
G02X914232Y326052I1J502D01*
G01Y326852D01*
G02X914735Y327354I503J-1D01*
G01X915734D01*
X915735D01*
G02X915838Y327344I3J-502D01*
G01X915859Y327339D01*
X915880D01*
G03X916080Y327539I0J200D01*
G01Y328218D01*
G02X916092Y328425I1802J-1D01*
G03X915826Y328637I-199J24D01*
G03X915820Y328635I60J-190D01*
G02X915637Y328600I-184J467D01*
G01X914833D01*
G02X914445Y328784I1J503D01*
G03X914417Y328812I-155J-127D01*
G02X914232Y329202I319J390D01*
G01Y330002D01*
G02X914417Y330392I504J0D01*
G03X914445Y330420I-127J155D01*
G02X914833Y330604I389J-319D01*
G01X915637D01*
G02X916025Y330420I-1J-503D01*
G03X916053Y330392I155J127D01*
G02X916238Y330002I-319J-390D01*
G01Y329604D01*
G03X916438Y329404I200J0D01*
G03X916582Y329465I0J200D01*
G02X917882Y330020I1301J-1248D01*
G02X919083Y329561I-1J-1803D01*
G03X919298Y329528I133J149D01*
G01X919632Y329677D01*
G03X919750Y329860I-82J182D01*
G01Y330004D01*
G02X919934Y330392I503J-1D01*
G03X919962Y330420I-127J155D01*
G02X920350Y330604I389J-319D01*
G01X921154D01*
G02X921542Y330420I-1J-503D01*
G03X921570Y330392I155J127D01*
G02X921754Y330004I-319J-389D01*
G01Y329200D01*
G37*
G36*
G01X942998Y337635D02*
G02X943387Y337820I389J-316D01*
G01X944187D01*
G02X944576Y337635I0J-501D01*
G03X944605Y337606I155J126D01*
G02X944790Y337217I-316J-389D01*
G01Y336417D01*
G02X944605Y336028I-501J0D01*
G03X944576Y335999I126J-155D01*
G02X944187Y335814I-389J316D01*
G01X943387D01*
G02X943281Y335826I3J503D01*
G01X943280D01*
X943235Y335836D01*
X943144Y335813D01*
X942831Y335546D01*
X942794Y335460D01*
X942797Y335413D01*
G02X942800Y335313I-1800J-104D01*
G01Y334966D01*
G03X942866Y334817I200J-1D01*
G01X943085Y334618D01*
G03X943238Y334567I134J148D01*
G02X943287Y334570I55J-500D01*
G01X944287D01*
G02X944790Y334067I0J-503D01*
G01Y333267D01*
G02X944287Y332764I-503J0D01*
G01X943287D01*
G02X943238Y332767I6J503D01*
G03X943085Y332716I-19J-199D01*
G01X942866Y332517D01*
G03X942800Y332368I134J-148D01*
G01Y331913D01*
G02X942799Y331902I-1789J157D01*
G01Y331901D01*
G03X942873Y331746I200J0D01*
G01X943115Y331549D01*
G03X943283Y331509I126J156D01*
G02X943387Y331520I105J-492D01*
G01X944187D01*
G02X944576Y331335I0J-501D01*
G03X944605Y331306I155J126D01*
G02X944790Y330917I-316J-389D01*
G01Y330117D01*
G02X944605Y329728I-501J0D01*
G03X944576Y329699I126J-155D01*
G02X944187Y329514I-389J316D01*
G01X943387D01*
G02X942998Y329699I0J501D01*
G03X942969Y329728I-155J-126D01*
G02X942784Y330117I316J389D01*
G01Y330203D01*
G03X942670Y330383I-200J0D01*
G01X942292Y330564D01*
X942178Y330550D01*
X942133Y330513D01*
G02X940997Y330110I-1136J1400D01*
G02X939927Y330463I1J1803D01*
G01X939881Y330497D01*
X939769Y330506D01*
X939400Y330319D01*
G03X939290Y330141I90J-178D01*
G01Y330117D01*
G02X939105Y329728I-501J0D01*
G03X939076Y329699I126J-155D01*
G02X938687Y329514I-389J316D01*
G01X937887D01*
G02X937498Y329699I0J501D01*
G03X937469Y329728I-155J-126D01*
G02X937284Y330117I316J389D01*
G01Y330917D01*
G02X937469Y331306I501J0D01*
G03X937498Y331335I-126J155D01*
G02X937887Y331520I389J-316D01*
G01X938687D01*
G02X938920Y331462I-1J-503D01*
G03X939211Y331666I93J177D01*
G02X939194Y331913I1786J247D01*
G01Y332365D01*
G03X939135Y332507I-200J0D01*
G01X938934Y332707D01*
G03X938793Y332765I-141J-142D01*
G01X938791D01*
G02X938787Y332764I-120J473D01*
G01X937787D01*
G02X937284Y333267I0J503D01*
G01Y334067D01*
G02X937787Y334570I503J0D01*
G01X938787D01*
G02X938791Y334569I-116J-474D01*
G01X938793D01*
G03X938934Y334627I0J200D01*
G01X939135Y334827D01*
G03X939194Y334969I-141J142D01*
G01Y335313D01*
G02X939197Y335401I1802J-17D01*
G01Y335403D01*
X939199Y335447D01*
X939166Y335528D01*
X938877Y335797D01*
X938792Y335824D01*
X938748Y335818D01*
G02X938687Y335814I-63J499D01*
G01X937887D01*
G02X937498Y335999I0J501D01*
G03X937469Y336028I-155J-126D01*
G02X937284Y336417I316J389D01*
G01Y337217D01*
G02X937469Y337606I501J0D01*
G03X937498Y337635I-126J155D01*
G02X937887Y337820I389J-316D01*
G01X938687D01*
G02X939076Y337635I0J-501D01*
G03X939105Y337606I155J126D01*
G02X939290Y337217I-316J-389D01*
G01Y337085D01*
G03X939400Y336907I200J0D01*
G01X939769Y336720D01*
X939881Y336729D01*
X939927Y336763D01*
G02X940997Y337116I1071J-1450D01*
G02X942133Y336713I0J-1803D01*
G01X942178Y336676D01*
X942292Y336662D01*
X942670Y336843D01*
G03X942784Y337023I-86J180D01*
G01Y337217D01*
G02X942969Y337606I501J0D01*
G03X942998Y337635I-126J155D01*
G37*
G54D74*
X978614Y1210568D03*
Y1214838D03*
X914637Y1210568D03*
Y1214838D03*
X70947Y1201565D03*
Y1205835D03*
X1822594Y1211054D03*
Y1215324D03*
G54D80*
X665748Y1101376D03*
X748030Y1086417D03*
X751771Y1078936D03*
X658268Y1101376D03*
X740550Y1086416D03*
X744290Y1097637D03*
X748031Y1105117D03*
X688189Y1086417D03*
Y1082677D03*
X766731Y1075196D03*
X740550Y1082676D03*
X748030Y1082677D03*
X744290Y1078936D03*
Y1093897D03*
X740551Y1101376D03*
X751771Y1097637D03*
Y1093897D03*
X748031Y1101376D03*
X740551Y1105117D03*
X320866Y1221062D03*
X313385Y1209842D03*
X320866Y1213582D03*
X324606Y1221062D03*
X313385Y1217322D03*
X317125Y1236023D03*
X313385Y1224803D03*
X324606Y1228543D03*
X317125Y1232283D03*
X313385Y1228543D03*
X320866D03*
X324606Y1239763D03*
X313385Y1247243D03*
X320866D03*
X317125Y1250984D03*
X320866Y1239763D03*
X313385Y1243503D03*
X324606Y1247243D03*
X317125Y1254724D03*
X320866Y1198621D03*
X313385Y1202362D03*
X324606Y1198621D03*
X317125Y1202362D03*
X320866Y1206102D03*
X324606D03*
X317125Y1217322D03*
Y1209842D03*
X324606Y1213582D03*
X313385Y1120078D03*
X324606Y1123818D03*
X317125Y1112598D03*
X324606Y1116338D03*
X313385Y1112598D03*
X317125Y1120078D03*
X320866Y1116338D03*
Y1123818D03*
X313385Y1127558D03*
X317125Y1135039D03*
X313385D03*
X324606Y1131299D03*
X317125Y1127558D03*
X320866Y1131299D03*
Y1090157D03*
X317125Y1093897D03*
X324606Y1090157D03*
Y1082676D03*
X317124Y1078936D03*
X313384Y1082677D03*
Y1086417D03*
X320866Y1082676D03*
X313385Y1101377D03*
X320866D03*
X324606D03*
X317125Y1097637D03*
X324606Y1108858D03*
X320866D03*
X317124Y1075196D03*
X305905Y1224803D03*
X302165Y1236023D03*
X294685Y1250984D03*
X298425Y1247243D03*
X309645Y1250984D03*
X298425Y1243503D03*
X305905D03*
Y1247243D03*
X302165Y1250984D03*
X294685Y1254724D03*
X309645D03*
X302165D03*
X298425Y1213582D03*
X305905Y1209842D03*
Y1217322D03*
X302165Y1209842D03*
X298425Y1206102D03*
X302165Y1217322D03*
Y1232283D03*
X309645D03*
X294685Y1236023D03*
X298425Y1224803D03*
X294685Y1232283D03*
X298425Y1228543D03*
X309645Y1236023D03*
X305905Y1228543D03*
Y1127559D03*
Y1135039D03*
X302165D03*
Y1127559D03*
X298425Y1123818D03*
Y1131299D03*
Y1198621D03*
X305905Y1202362D03*
X302165D03*
X298425Y1105117D03*
Y1101376D03*
X309644Y1097637D03*
X302164D03*
X305905Y1105117D03*
X294684Y1097637D03*
X313385Y1105117D03*
X305905Y1101376D03*
X302165Y1120078D03*
X305905Y1112598D03*
X298425Y1116338D03*
X305905Y1120078D03*
X302165Y1112598D03*
X294684Y1093897D03*
X309644D03*
X302164D03*
X305904Y1082677D03*
X302164Y1078936D03*
X305904Y1086417D03*
X294684Y1078936D03*
X309644D03*
X298424Y1086416D03*
Y1082676D03*
X294684Y1075196D03*
X302164D03*
X309644D03*
X283464Y1243503D03*
X279724Y1250984D03*
X283464Y1247243D03*
X287204Y1250984D03*
X290944Y1247243D03*
Y1243503D03*
X287204Y1254724D03*
X279724D03*
X294685Y1213582D03*
Y1206102D03*
X279724Y1232283D03*
Y1236023D03*
X287204Y1232283D03*
X283464Y1224803D03*
Y1228543D03*
X287204Y1236023D03*
X290944Y1224803D03*
Y1228543D03*
X294684Y1123818D03*
Y1131299D03*
X294685Y1198621D03*
X287203Y1093897D03*
X279723D03*
X290943Y1086417D03*
X287203Y1078936D03*
X290943Y1082677D03*
X283463Y1082676D03*
X279723Y1078936D03*
X283463Y1086416D03*
X283464Y1101376D03*
Y1105117D03*
X290944Y1101376D03*
X279723Y1097637D03*
X290944Y1105117D03*
X287203Y1097637D03*
X294684Y1116338D03*
X287203Y1075196D03*
X279723D03*
X268503Y1228543D03*
X264763Y1236023D03*
Y1250984D03*
X268503Y1243503D03*
Y1247243D03*
X272244Y1250984D03*
X275984Y1243503D03*
Y1247243D03*
X264763Y1254724D03*
X272244D03*
X264763Y1232283D03*
X268503Y1224803D03*
X275984D03*
X272244Y1236023D03*
X275984Y1228543D03*
X272244Y1232283D03*
X264762Y1097637D03*
X268503Y1105117D03*
X272243Y1097637D03*
X275984Y1105117D03*
X268503Y1101376D03*
X275984D03*
X264762Y1075196D03*
X272243D03*
Y1093897D03*
X264762D03*
X275982Y1082677D03*
Y1086417D03*
X268502Y1082676D03*
X272243Y1078936D03*
X268502Y1086416D03*
X264762Y1078936D03*
X261023Y1243503D03*
X246062D03*
X249803Y1250984D03*
X261023Y1247243D03*
X246062D03*
X257283Y1250984D03*
X253543Y1247243D03*
Y1243503D03*
X257283Y1254724D03*
X249803D03*
X261023Y1224803D03*
X253543Y1228543D03*
X249803Y1232283D03*
X246062Y1228543D03*
X257283Y1232283D03*
Y1236023D03*
X246062Y1224803D03*
X261023Y1228543D03*
X253543Y1224803D03*
X249803Y1236023D03*
X249802Y1097637D03*
X257282D03*
X253543Y1105117D03*
Y1101376D03*
X261023Y1105117D03*
Y1101376D03*
X249802Y1075196D03*
X257282D03*
X249802Y1093897D03*
X257282D03*
X249802Y1078936D03*
X261022Y1086417D03*
X253542Y1082676D03*
X257282Y1078936D03*
X246061Y1082677D03*
Y1086417D03*
X253542Y1086416D03*
X261022Y1082677D03*
X234842Y1254724D03*
X242322D03*
X238582Y1224803D03*
Y1228543D03*
X242322Y1236023D03*
Y1232283D03*
X234842D03*
Y1236023D03*
X238582Y1247243D03*
X242322Y1250984D03*
X234842D03*
X238582Y1243503D03*
X246062Y1105117D03*
X242321Y1097637D03*
X234841D03*
X238582Y1101376D03*
X246062D03*
X238582Y1105117D03*
X234841Y1075195D03*
X242321Y1075196D03*
X234841Y1093897D03*
X242321D03*
Y1078936D03*
X238581Y1082676D03*
X234841Y1078935D03*
X238581Y1086416D03*
X219881Y1254724D03*
X227362D03*
X231102Y1228543D03*
Y1224803D03*
X219881Y1232283D03*
Y1236023D03*
X223622Y1224803D03*
X227362Y1232283D03*
X223622Y1228543D03*
X227362Y1236023D03*
X231102Y1243503D03*
Y1247243D03*
X223622Y1243503D03*
Y1247243D03*
X219881Y1250984D03*
X227362D03*
Y1093897D03*
X219881D03*
Y1078936D03*
X231102Y1082677D03*
Y1086417D03*
X223622Y1082677D03*
X227362Y1078936D03*
X223622Y1086417D03*
X231102Y1101376D03*
X219881Y1097637D03*
X223621Y1101376D03*
Y1105117D03*
X227362Y1097637D03*
X231102Y1105117D03*
X227362Y1075196D03*
X219881D03*
X216141Y1247243D03*
X208661Y1243503D03*
X216141D03*
X204921Y1250984D03*
X208661Y1247243D03*
X201181Y1243503D03*
X212401Y1250984D03*
X201181Y1247243D03*
X212401Y1254724D03*
X204921D03*
Y1232283D03*
X201181Y1224803D03*
X212401Y1232283D03*
X208661Y1228543D03*
X212401Y1236023D03*
X216141Y1224803D03*
X208661D03*
X201181Y1228543D03*
X216141D03*
X204921Y1236023D03*
X208661Y1082677D03*
X216141Y1086417D03*
X201181Y1082677D03*
X216141D03*
X201181Y1086417D03*
X208661D03*
X204921Y1078936D03*
Y1097637D03*
X216141Y1101376D03*
X208661D03*
X212401Y1097637D03*
X208661Y1105117D03*
X216141D03*
X201181Y1101376D03*
Y1105117D03*
X204921Y1075196D03*
X212401D03*
Y1093897D03*
X204921D03*
X212401Y1078936D03*
X197440Y1250984D03*
X193700Y1247243D03*
Y1243503D03*
X189960Y1250984D03*
X186220Y1247243D03*
Y1243503D03*
X197440Y1254724D03*
X189960D03*
X197440Y1236023D03*
X186220Y1224803D03*
X193700Y1228543D03*
X197440Y1232283D03*
X189960Y1236023D03*
X186220Y1228543D03*
X193700Y1224803D03*
X189960Y1232283D03*
X197440Y1093897D03*
X189960D03*
X186220Y1082677D03*
Y1086417D03*
X189960Y1078936D03*
X193700Y1086417D03*
Y1082677D03*
X197440Y1078936D03*
X193700Y1105117D03*
X189960Y1097637D03*
X186220Y1105117D03*
X197440Y1097637D03*
X193700Y1101376D03*
X186220D03*
X189960Y1075196D03*
X197440D03*
X178740Y1247243D03*
X182480Y1250984D03*
X171259Y1247243D03*
X174999Y1250984D03*
X171259Y1243503D03*
X178740D03*
X182480Y1254724D03*
X174999D03*
X171259Y1198621D03*
X174999Y1206102D03*
X171259Y1213582D03*
X174999D03*
X178740Y1228543D03*
X171259Y1224803D03*
X182480Y1236023D03*
Y1232283D03*
X174999D03*
X171259Y1228543D03*
X178740Y1224803D03*
X174999Y1236023D03*
Y1191141D03*
X171259D03*
X174999Y1198621D03*
X171259Y1206102D03*
X174999Y1093897D03*
X182480D03*
X174999Y1078936D03*
X182480D03*
X178740Y1082677D03*
Y1086417D03*
X182480Y1097637D03*
X174999D03*
X178740Y1101376D03*
Y1105117D03*
X174999Y1075196D03*
X182480D03*
X152559Y1250984D03*
X156299Y1243503D03*
Y1247243D03*
X163779Y1243503D03*
X160039Y1250984D03*
X163779Y1247243D03*
X167519Y1250984D03*
X152559Y1254724D03*
X167519D03*
X160039D03*
X167519Y1209842D03*
X163779D03*
Y1217322D03*
X167519D03*
X152559D03*
X160039Y1236023D03*
X163779Y1224803D03*
X156299D03*
X167519Y1232283D03*
X156299Y1228543D03*
X163779D03*
X167519Y1236023D03*
X160039Y1232283D03*
X152559Y1236023D03*
Y1232283D03*
X156299Y1202362D03*
Y1194881D03*
X152559Y1202362D03*
Y1194881D03*
X163779D03*
Y1202362D03*
X167519Y1194881D03*
Y1202362D03*
X156299Y1217322D03*
Y1209842D03*
X152559D03*
X156299Y1187401D03*
X163779D03*
X152559D03*
X167519D03*
X148818Y1239763D03*
X145078D03*
Y1198621D03*
X148818D03*
X145078Y1206102D03*
X148818D03*
X145078Y1221062D03*
X148818D03*
Y1213582D03*
X145078D03*
Y1228543D03*
X148818D03*
Y1247243D03*
X145078D03*
Y1191141D03*
X148818D03*
X1643503Y1078936D03*
X1647242Y1082677D03*
X1636022Y1075196D03*
X1643503D03*
X1639762Y1086416D03*
Y1082676D03*
X1658463Y1097637D03*
X1636022Y1078936D03*
X1647242Y1086417D03*
X1617322Y1101376D03*
X1639763D03*
X1636022Y1097637D03*
Y1093897D03*
X1662204Y1101376D03*
X1658463Y1075196D03*
X1650983D03*
X1658463Y1078936D03*
X1654723Y1086416D03*
Y1082676D03*
X1662203Y1082677D03*
Y1086417D03*
X1621062Y1093897D03*
X1658463D03*
X1628542Y1097637D03*
X1643503D03*
Y1093897D03*
X1647244Y1101376D03*
X1650983Y1078936D03*
X662008D03*
X1621062Y1097637D03*
X1632283Y1101376D03*
X1624803D03*
X1654724D03*
X699408Y1093897D03*
X736810D03*
Y1097637D03*
X658268Y1082677D03*
X1059251Y1239763D03*
X759251Y1075196D03*
X751771D03*
X1059251Y1247243D03*
X658268Y1086417D03*
X669488Y1093897D03*
X639567D03*
X635827Y1101376D03*
Y1105117D03*
X639567Y1097637D03*
X632086D03*
Y1075196D03*
X639567D03*
X774212Y1093897D03*
X729330Y1097637D03*
X721849Y1093897D03*
X781693Y1101377D03*
X669488Y1097637D03*
X1628542Y1093897D03*
X650787Y1082677D03*
Y1101376D03*
X647047Y1097637D03*
X762992Y1120078D03*
X635827Y1082677D03*
X777953Y1101377D03*
X770472D03*
X647047Y1075196D03*
X654527D03*
X770472Y1105117D03*
X669488Y1075196D03*
X774212Y1097637D03*
X643307Y1101376D03*
Y1105117D03*
X647047Y1078936D03*
X654527D03*
X643307Y1082677D03*
Y1086417D03*
X774211Y1078936D03*
X770471Y1086417D03*
Y1082677D03*
X777953Y1082676D03*
X781693D03*
Y1090157D03*
X777953D03*
X650787Y1105117D03*
X762992Y1112598D03*
X650787Y1086417D03*
X639567Y1078936D03*
X635827Y1086417D03*
X762992Y1135039D03*
Y1127559D03*
X1647244Y1105116D03*
X662008Y1093897D03*
X755511Y1082676D03*
X662008Y1097637D03*
X658268Y1105117D03*
X774211Y1075196D03*
X755511Y1086416D03*
X676968Y1075196D03*
X632086Y1093897D03*
Y1078936D03*
X1624803Y1105116D03*
X1650983Y1097637D03*
Y1093897D03*
X1673424Y1075196D03*
X1680904D03*
X1665944D03*
X1669684Y1082676D03*
Y1086416D03*
X1673424Y1078936D03*
X1680904D03*
X1677164Y1086417D03*
Y1082677D03*
X1665944Y1078936D03*
X1677165Y1101376D03*
X1669685D03*
X1680904Y1093897D03*
Y1097637D03*
X1673424Y1093897D03*
Y1097637D03*
X1665944D03*
Y1093897D03*
X1688384Y1075196D03*
Y1078936D03*
X1684644Y1086417D03*
Y1082677D03*
X1692126Y1082676D03*
X1695866D03*
Y1090157D03*
X1692126D03*
X1688385Y1097637D03*
Y1093897D03*
X1684645Y1101377D03*
X1695866D03*
X1692126D03*
X1550000Y1105116D03*
X1564960D03*
X1557480D03*
X1572441D03*
X1579921D03*
X1594881D03*
X1587401D03*
X1609842D03*
X1602362D03*
X1516338Y1191141D03*
Y1198621D03*
Y1206102D03*
Y1213582D03*
X1535039Y1187401D03*
X1527559D03*
X1523819D03*
X1535039Y1194881D03*
Y1202362D03*
X1523819Y1194881D03*
X1527559D03*
X1523819Y1202362D03*
X1527559D03*
X1520078Y1191141D03*
Y1198621D03*
Y1206102D03*
X1535039Y1217322D03*
Y1209842D03*
X1527559D03*
X1523819D03*
Y1217322D03*
X1527559D03*
X1520078Y1213582D03*
X1538779Y1187401D03*
Y1194881D03*
Y1202362D03*
Y1217322D03*
Y1209842D03*
X1546259Y1191141D03*
X1542519D03*
Y1198621D03*
X1546259D03*
X1542519Y1206102D03*
X1546259D03*
X762991Y1082677D03*
X602165Y1228543D03*
X613386Y1243503D03*
Y1247243D03*
X609646Y1250984D03*
Y1254724D03*
X617126D03*
Y1250984D03*
X620866Y1247243D03*
Y1243503D03*
X665748Y1105117D03*
X613386Y1202362D03*
X609646D03*
X613386Y1194881D03*
X609646D03*
X613386Y1217322D03*
X609646D03*
Y1209842D03*
X613386D03*
X620866Y1187401D03*
Y1202362D03*
Y1194881D03*
Y1209842D03*
X624606Y1187401D03*
X632086Y1206102D03*
X628346D03*
X632086Y1198621D03*
X628346D03*
X624606Y1202362D03*
Y1194881D03*
X628346Y1191141D03*
X632086D03*
Y1213582D03*
X628346D03*
X624606Y1209842D03*
X620866Y1217322D03*
X624606D03*
X762992Y1105117D03*
X684449Y1075196D03*
X755512Y1101376D03*
X766731Y1097637D03*
X759251Y1078936D03*
X755512Y1105117D03*
X766731Y1093897D03*
Y1078936D03*
X762991Y1086417D03*
X759251Y1097637D03*
X762992Y1101376D03*
X759251Y1093897D03*
X1516338Y1221062D03*
Y1228543D03*
X662008Y1075196D03*
X647047Y1093897D03*
X654527Y1097637D03*
Y1093897D03*
X669488Y1078936D03*
X602165Y1239763D03*
X736810Y1078936D03*
X744290Y1075196D03*
X721849Y1078936D03*
X725589Y1086416D03*
Y1082676D03*
X729330Y1078936D03*
X733069Y1086417D03*
Y1082677D03*
X729330Y1075196D03*
X718110Y1101376D03*
X1617321Y1082677D03*
X714369Y1093897D03*
X1617321Y1086417D03*
X714369Y1097637D03*
X706889Y1093897D03*
Y1097637D03*
Y1078936D03*
X710629Y1086416D03*
Y1082676D03*
X714369Y1078936D03*
X718109Y1082677D03*
Y1086417D03*
X684449Y1078936D03*
X680709Y1086417D03*
Y1082677D03*
X676968Y1078936D03*
X673228Y1082677D03*
Y1086417D03*
X703149Y1105117D03*
X699408Y1097637D03*
X691928Y1093897D03*
Y1078935D03*
X695668Y1086416D03*
Y1082676D03*
X699408Y1078936D03*
X703148Y1086417D03*
Y1082677D03*
X691928Y1075195D03*
X699408Y1075196D03*
X691928Y1097637D03*
X695669Y1101376D03*
Y1105117D03*
X703149Y1101376D03*
X714369Y1075196D03*
X706889D03*
X710630Y1105117D03*
Y1101376D03*
X718110Y1105117D03*
X736810Y1075196D03*
X721849D03*
X684449Y1097637D03*
Y1093897D03*
X1527559Y1224803D03*
X676968Y1097637D03*
Y1093897D03*
X688189Y1105117D03*
Y1101376D03*
X1520078Y1221062D03*
X680708Y1105117D03*
Y1101376D03*
X673228Y1105117D03*
Y1101376D03*
X725590Y1105117D03*
X733071Y1101376D03*
Y1105117D03*
X725590Y1101376D03*
X665748Y1082677D03*
Y1086417D03*
X721849Y1097637D03*
X729330Y1093897D03*
X1516338Y1239763D03*
X770472Y1224803D03*
Y1228543D03*
X777953D03*
X781693D03*
X774212Y1232283D03*
Y1236023D03*
X781693Y1213582D03*
X777953D03*
X781693Y1221062D03*
X777953D03*
X774212Y1217322D03*
X770472D03*
Y1209842D03*
X774212D03*
X781693Y1198621D03*
X777953D03*
X774212Y1202362D03*
X770472D03*
X777953Y1206102D03*
X781693D03*
X762992Y1243503D03*
Y1247243D03*
X766732Y1250984D03*
Y1254724D03*
X759252D03*
Y1250984D03*
X755512Y1247243D03*
Y1243503D03*
Y1224803D03*
Y1228543D03*
X762992Y1224803D03*
Y1228543D03*
X759252Y1232283D03*
Y1236023D03*
X766732D03*
Y1232283D03*
X762992Y1217322D03*
X759252D03*
X755512Y1213582D03*
X759252Y1209842D03*
X762992D03*
Y1202362D03*
X759252D03*
X755512Y1206102D03*
Y1198621D03*
X751772Y1250984D03*
Y1254724D03*
Y1236023D03*
Y1232283D03*
Y1213582D03*
Y1206102D03*
Y1198621D03*
X759252Y1127559D03*
Y1135039D03*
X755512Y1131299D03*
X759252Y1112598D03*
Y1120078D03*
X755512Y1116338D03*
Y1123818D03*
X751771Y1131299D03*
Y1116338D03*
Y1123818D03*
X770472Y1135039D03*
X774212D03*
X777953Y1131299D03*
X781693D03*
X774212Y1127558D03*
X770472D03*
X777953Y1123818D03*
X781693D03*
X774212Y1120078D03*
X770472D03*
X777953Y1116338D03*
X781693D03*
X774212Y1112598D03*
X777953Y1108858D03*
X781693D03*
X1632283Y1105116D03*
X1617322D03*
X1639763D03*
X1662204D03*
X1654724D03*
X1677165D03*
X1669685D03*
X1684645Y1105117D03*
X1673425Y1112598D03*
Y1120078D03*
X1669685Y1116338D03*
Y1123818D03*
X1665945Y1116338D03*
Y1123818D03*
X1677165Y1112598D03*
Y1120078D03*
X1673425Y1127559D03*
X1669685Y1131299D03*
X1665945D03*
X1677165Y1127559D03*
X1692126Y1123818D03*
X1695866D03*
X1688385Y1120078D03*
X1684645D03*
X1692126Y1116338D03*
X1695866D03*
X1684645Y1112598D03*
X1688385D03*
X1692126Y1108858D03*
X1695866D03*
X1692126Y1131299D03*
X1695866D03*
X1688385Y1127558D03*
X1684645D03*
X1673425Y1135039D03*
X1677165D03*
X1684645D03*
X1688385D03*
X1059251Y1191141D03*
Y1198621D03*
Y1206102D03*
Y1213582D03*
X1077952Y1187401D03*
X1070472D03*
X1066732D03*
X1077952Y1194881D03*
Y1202362D03*
X1066732Y1194881D03*
X1070472D03*
X1066732Y1202362D03*
X1070472D03*
X1062991Y1191141D03*
Y1198621D03*
Y1206102D03*
X1077952Y1217322D03*
Y1209842D03*
X1070472D03*
X1066732D03*
Y1217322D03*
X1070472D03*
X1062991Y1213582D03*
X1081692Y1187401D03*
Y1194881D03*
Y1202362D03*
Y1217322D03*
Y1209842D03*
X1089172Y1191141D03*
X1085432D03*
Y1198621D03*
X1089172D03*
X1085432Y1206102D03*
X1089172D03*
X1059251Y1221062D03*
Y1228543D03*
X1062991Y1221062D03*
X1070472Y1224803D03*
Y1228543D03*
X1077952Y1224803D03*
Y1228543D03*
X1066732Y1232283D03*
Y1236023D03*
X1074212D03*
Y1232283D03*
X1062991Y1228543D03*
X1077952Y1243503D03*
Y1247243D03*
X1074212Y1250984D03*
Y1254724D03*
X1066732D03*
Y1250984D03*
X1070472Y1247243D03*
Y1243503D03*
X1062991Y1247243D03*
Y1239763D03*
X1085432Y1213582D03*
X1089172D03*
X1081692Y1232283D03*
Y1236023D03*
X1085432Y1224803D03*
Y1228543D03*
X1089172Y1232283D03*
Y1236023D03*
Y1250984D03*
Y1254724D03*
X1081692D03*
Y1250984D03*
X1085432Y1247243D03*
Y1243503D03*
X1092913Y1224803D03*
Y1228543D03*
Y1243503D03*
Y1247243D03*
X1100393Y1224803D03*
Y1228543D03*
X1104133Y1236023D03*
Y1232283D03*
X1107873Y1228543D03*
Y1224803D03*
X1096653Y1232283D03*
Y1236023D03*
X1100393Y1243503D03*
Y1247243D03*
X1104133Y1254724D03*
Y1250984D03*
X1107873Y1247243D03*
Y1243503D03*
X1096653Y1250984D03*
Y1254724D03*
X1115354Y1224803D03*
Y1228543D03*
X1119094Y1236023D03*
Y1232283D03*
X1122834Y1228543D03*
Y1224803D03*
X1126574Y1232283D03*
Y1236023D03*
X1111613Y1232283D03*
Y1236023D03*
X1115354Y1243503D03*
Y1247243D03*
X1119094Y1254724D03*
Y1250984D03*
X1122834Y1247243D03*
Y1243503D03*
X1126574Y1250984D03*
Y1254724D03*
X1111613Y1250984D03*
Y1254724D03*
X1130314Y1224803D03*
Y1228543D03*
X1141535Y1236023D03*
Y1232283D03*
X1134054Y1236023D03*
Y1232283D03*
X1137795Y1228543D03*
Y1224803D03*
X1130314Y1243503D03*
Y1247243D03*
X1134054Y1254724D03*
Y1250984D03*
X1137795Y1247243D03*
Y1243503D03*
X1141535Y1250984D03*
Y1254724D03*
X1149015Y1236023D03*
Y1232283D03*
X1152755Y1224803D03*
X1156495Y1232283D03*
Y1236023D03*
X1152755Y1228543D03*
X1145275Y1224803D03*
Y1228543D03*
X1149015Y1254724D03*
Y1250984D03*
X1152755Y1247243D03*
Y1243503D03*
X1156495Y1250984D03*
Y1254724D03*
X1145275Y1243503D03*
Y1247243D03*
X1163976Y1236023D03*
Y1232283D03*
X1167716Y1228543D03*
Y1224803D03*
X1175196D03*
Y1228543D03*
X1171456Y1232283D03*
Y1236023D03*
X1160235Y1224803D03*
Y1228543D03*
X1163976Y1254724D03*
Y1250984D03*
X1167716Y1243503D03*
Y1247243D03*
X1171456Y1250984D03*
Y1254724D03*
X1175196Y1247243D03*
Y1243503D03*
X1160235Y1247243D03*
Y1243503D03*
X1178936Y1236023D03*
Y1232283D03*
X1182676Y1224803D03*
Y1228543D03*
X1186417Y1236023D03*
Y1232283D03*
X1190157Y1228543D03*
Y1224803D03*
X1178936Y1254724D03*
Y1250984D03*
X1182676Y1243503D03*
Y1247243D03*
X1186417Y1250984D03*
Y1254724D03*
X1190157Y1247243D03*
Y1243503D03*
X1197637Y1224803D03*
Y1228543D03*
X1201377Y1232283D03*
Y1236023D03*
X1205117Y1228543D03*
Y1224803D03*
X1193897Y1236023D03*
Y1232283D03*
X1197637Y1247243D03*
X1205117Y1243503D03*
Y1247243D03*
X1201377Y1254724D03*
Y1250984D03*
X1197637Y1243503D03*
X1193897Y1254724D03*
Y1250984D03*
X1212598Y1224803D03*
Y1228543D03*
X1220078Y1224803D03*
Y1228543D03*
X1216338Y1232283D03*
Y1236023D03*
X1223818D03*
Y1232283D03*
X1208858Y1236023D03*
Y1232283D03*
X1220078Y1243503D03*
Y1247243D03*
X1223818Y1250984D03*
Y1254724D03*
X1216338D03*
Y1250984D03*
X1212598Y1247243D03*
Y1243503D03*
X1208858Y1250984D03*
Y1254724D03*
X1227558Y1224803D03*
Y1228543D03*
X1235039D03*
X1238779D03*
X1231298Y1232283D03*
Y1236023D03*
X1238779Y1239763D03*
X1235039D03*
X1238779Y1247243D03*
X1235039D03*
X1231298Y1250984D03*
Y1254724D03*
X1227558Y1247243D03*
Y1243503D03*
X1220078Y1202362D03*
X1216338D03*
X1212598Y1206102D03*
Y1198621D03*
X1208858Y1206102D03*
Y1198621D03*
X1220078Y1217322D03*
X1216338D03*
X1212598Y1213582D03*
X1216338Y1209842D03*
X1220078D03*
X1208858Y1213582D03*
X1238779Y1198621D03*
X1235039D03*
X1231298Y1202362D03*
X1227558D03*
X1235039Y1206102D03*
X1238779D03*
Y1213582D03*
X1235039D03*
X1238779Y1221062D03*
X1235039D03*
X1231298Y1217322D03*
X1227558D03*
Y1209842D03*
X1231298D03*
X1089172Y1075196D03*
Y1078936D03*
X1092913Y1086417D03*
Y1082677D03*
X1089172Y1097637D03*
Y1093897D03*
X1092913Y1101376D03*
X1104133Y1075196D03*
X1096653D03*
X1104133Y1078936D03*
X1107873Y1082677D03*
Y1086417D03*
X1100393D03*
Y1082677D03*
X1096653Y1078936D03*
X1104133Y1093897D03*
Y1097637D03*
X1107873Y1101376D03*
X1100393D03*
X1096653Y1097637D03*
Y1093897D03*
X1126574Y1075196D03*
X1119094D03*
X1111613D03*
X1126574Y1078936D03*
X1122834Y1086417D03*
Y1082677D03*
X1119094Y1078936D03*
X1115354Y1086417D03*
Y1082677D03*
X1111613Y1078936D03*
X1126574Y1093897D03*
Y1097637D03*
X1119094Y1093897D03*
Y1097637D03*
X1115354Y1101376D03*
X1122834D03*
X1111613Y1097637D03*
Y1093897D03*
X1141535Y1075196D03*
X1134054D03*
X1141535Y1078936D03*
X1137795Y1086417D03*
Y1082677D03*
X1134054Y1078936D03*
X1130314Y1082677D03*
Y1086417D03*
X1141535Y1097637D03*
Y1093897D03*
X1134054Y1097637D03*
Y1093897D03*
X1137794Y1101376D03*
X1130314D03*
X1149014Y1075195D03*
X1156494Y1075196D03*
X1149014Y1078935D03*
X1152754Y1086416D03*
Y1082676D03*
X1156494Y1078936D03*
X1145275Y1086417D03*
Y1082677D03*
X1152755Y1101376D03*
X1156494Y1093897D03*
Y1097637D03*
X1149014D03*
Y1093897D03*
X1145275Y1101376D03*
X1163975Y1075196D03*
X1171455D03*
X1163975Y1078936D03*
X1167715Y1086416D03*
Y1082676D03*
X1171455Y1078936D03*
X1175195Y1082677D03*
Y1086417D03*
X1160234D03*
Y1082677D03*
X1175196Y1101376D03*
X1167716D03*
X1171455Y1093897D03*
Y1097637D03*
X1163975Y1093897D03*
Y1097637D03*
X1160235Y1101376D03*
X1178935Y1075196D03*
X1186416D03*
X1178935Y1078936D03*
X1182675Y1086416D03*
Y1082676D03*
X1186416Y1078936D03*
X1190155Y1086417D03*
Y1082677D03*
X1190157Y1101376D03*
X1182676D03*
X1186416Y1093897D03*
Y1097637D03*
X1178935Y1093897D03*
Y1097637D03*
X1201376Y1075196D03*
X1193896D03*
X1201376Y1078936D03*
X1197636Y1086416D03*
Y1082676D03*
X1205116Y1082677D03*
Y1086417D03*
X1193896Y1078936D03*
X1205117Y1101376D03*
X1197637D03*
X1201376Y1097637D03*
Y1093897D03*
X1193896Y1097637D03*
Y1093897D03*
X1216337Y1075196D03*
X1223817D03*
X1208857D03*
X1212597Y1082676D03*
Y1086416D03*
X1216337Y1078936D03*
X1223817D03*
X1220077Y1086417D03*
Y1082677D03*
X1208857Y1078936D03*
X1220078Y1101376D03*
X1212598D03*
X1223817Y1093897D03*
Y1097637D03*
X1216337Y1093897D03*
Y1097637D03*
X1208857D03*
Y1093897D03*
X1231297Y1075196D03*
Y1078936D03*
X1227557Y1086417D03*
Y1082677D03*
X1235039Y1082676D03*
X1238779D03*
Y1090157D03*
X1235039D03*
X1231298Y1097637D03*
Y1093897D03*
X1227558Y1101377D03*
X1238779D03*
X1235039D03*
X1092913Y1105116D03*
X1107873D03*
X1100393D03*
X1115354D03*
X1122834D03*
X1137794D03*
X1130314D03*
X1152755D03*
X1145275D03*
X1175196D03*
X1167716D03*
X1160235D03*
X1190157D03*
X1182676D03*
X1205117D03*
X1197637D03*
X1220078D03*
X1212598D03*
X1227558Y1105117D03*
X1216338Y1112598D03*
Y1120078D03*
X1212598Y1116338D03*
Y1123818D03*
X1208858Y1116338D03*
Y1123818D03*
X1220078Y1112598D03*
Y1120078D03*
X1216338Y1127559D03*
X1212598Y1131299D03*
X1208858D03*
X1220078Y1127559D03*
X1235039Y1123818D03*
X1238779D03*
X1231298Y1120078D03*
X1227558D03*
X1235039Y1116338D03*
X1238779D03*
X1227558Y1112598D03*
X1231298D03*
X1235039Y1108858D03*
X1238779D03*
X1235039Y1131299D03*
X1238779D03*
X1231298Y1127558D03*
X1227558D03*
X1216338Y1135039D03*
X1220078D03*
X1227558D03*
X1231298D03*
X1557480Y1086417D03*
Y1082677D03*
X1553740Y1078936D03*
X1561220Y1093897D03*
Y1097637D03*
X1564960Y1101376D03*
X1557480D03*
X1553740Y1097637D03*
Y1093897D03*
X1583661Y1075196D03*
X1576181D03*
X1568700D03*
X1583661Y1078936D03*
X1579921Y1086417D03*
Y1082677D03*
X1576181Y1078936D03*
X1572441Y1086417D03*
Y1082677D03*
X1568700Y1078936D03*
X1583661Y1093897D03*
Y1097637D03*
X1576181Y1093897D03*
Y1097637D03*
X1572441Y1101376D03*
X1579921D03*
X1568700Y1097637D03*
Y1093897D03*
X1598622Y1075196D03*
X1591141D03*
X1598622Y1078936D03*
X1594882Y1086417D03*
Y1082677D03*
X1591141Y1078936D03*
X1587401Y1082677D03*
Y1086417D03*
X1598622Y1097637D03*
Y1093897D03*
X1591141Y1097637D03*
Y1093897D03*
X1594881Y1101376D03*
X1587401D03*
X1606101Y1075195D03*
X1613581Y1075196D03*
X1606101Y1078935D03*
X1609841Y1086416D03*
Y1082676D03*
X1613581Y1078936D03*
X1602362Y1086417D03*
Y1082677D03*
X1609842Y1101376D03*
X1613581Y1093897D03*
Y1097637D03*
X1606101D03*
Y1093897D03*
X1602362Y1101376D03*
X1621062Y1075196D03*
X1628542D03*
X1621062Y1078936D03*
X1624802Y1086416D03*
Y1082676D03*
X1628542Y1078936D03*
X1632282Y1082677D03*
Y1086417D03*
X1546259Y1078936D03*
X1550000Y1086417D03*
Y1082677D03*
X1546259Y1097637D03*
Y1093897D03*
X1550000Y1101376D03*
X1561220Y1075196D03*
X1553740D03*
X1561220Y1078936D03*
X1564960Y1082677D03*
Y1086417D03*
X1695866Y1213582D03*
X1692126D03*
X1695866Y1221062D03*
X1692126D03*
X1688385Y1217322D03*
X1684645D03*
Y1209842D03*
X1688385D03*
X1546259Y1075196D03*
X609646Y1187401D03*
X613386D03*
X1665945Y1198621D03*
X1677165Y1217322D03*
X1673425D03*
X1669685Y1213582D03*
X1673425Y1209842D03*
X1677165D03*
X1665945Y1213582D03*
X1695866Y1198621D03*
X1692126D03*
X1688385Y1202362D03*
X1684645D03*
X1692126Y1206102D03*
X1695866D03*
X1665945D03*
X1695866Y1239763D03*
X1692126D03*
X1695866Y1247243D03*
X1692126D03*
X1688385Y1250984D03*
Y1254724D03*
X1684645Y1247243D03*
Y1243503D03*
X1677165Y1202362D03*
X1673425D03*
X1669685Y1206102D03*
Y1198621D03*
X1665945Y1250984D03*
Y1254724D03*
X1684645Y1224803D03*
Y1228543D03*
X1692126D03*
X1695866D03*
X1688385Y1232283D03*
Y1236023D03*
X1527559Y1228543D03*
X1535039Y1224803D03*
Y1228543D03*
X1523819Y1232283D03*
Y1236023D03*
X1531299D03*
Y1232283D03*
X1520078Y1228543D03*
X1535039Y1243503D03*
Y1247243D03*
X1531299Y1250984D03*
Y1254724D03*
X1523819D03*
Y1250984D03*
X1527559Y1247243D03*
Y1243503D03*
X1520078Y1247243D03*
Y1239763D03*
X1542519Y1213582D03*
X1546259D03*
X1538779Y1232283D03*
Y1236023D03*
X1542519Y1224803D03*
Y1228543D03*
X1546259Y1232283D03*
Y1236023D03*
Y1250984D03*
Y1254724D03*
X1538779D03*
Y1250984D03*
X1542519Y1247243D03*
Y1243503D03*
X1550000Y1224803D03*
Y1228543D03*
Y1243503D03*
Y1247243D03*
X1557480Y1224803D03*
Y1228543D03*
X1561220Y1236023D03*
Y1232283D03*
X1564960Y1228543D03*
Y1224803D03*
X1553740Y1232283D03*
Y1236023D03*
X1557480Y1243503D03*
Y1247243D03*
X1561220Y1254724D03*
Y1250984D03*
X1564960Y1247243D03*
Y1243503D03*
X1553740Y1250984D03*
Y1254724D03*
X1572441Y1224803D03*
Y1228543D03*
X1576181Y1236023D03*
Y1232283D03*
X1579921Y1228543D03*
Y1224803D03*
X1583661Y1232283D03*
Y1236023D03*
X1568700Y1232283D03*
Y1236023D03*
X1572441Y1243503D03*
Y1247243D03*
X1576181Y1254724D03*
Y1250984D03*
X1579921Y1247243D03*
Y1243503D03*
X1583661Y1250984D03*
Y1254724D03*
X1568700Y1250984D03*
Y1254724D03*
X1587401Y1224803D03*
Y1228543D03*
X1598622Y1236023D03*
Y1232283D03*
X1591141Y1236023D03*
Y1232283D03*
X1594882Y1228543D03*
Y1224803D03*
X1587401Y1243503D03*
Y1247243D03*
X1591141Y1254724D03*
Y1250984D03*
X1594882Y1247243D03*
Y1243503D03*
X1598622Y1250984D03*
Y1254724D03*
X1606102Y1236023D03*
Y1232283D03*
X1609842Y1224803D03*
X1613582Y1232283D03*
Y1236023D03*
X1609842Y1228543D03*
X1602362Y1224803D03*
Y1228543D03*
X1606102Y1254724D03*
Y1250984D03*
X1609842Y1247243D03*
Y1243503D03*
X1613582Y1250984D03*
Y1254724D03*
X1602362Y1243503D03*
Y1247243D03*
X1621063Y1236023D03*
Y1232283D03*
X1624803Y1228543D03*
Y1224803D03*
X1632283D03*
Y1228543D03*
X1628543Y1232283D03*
Y1236023D03*
X1617322Y1224803D03*
Y1228543D03*
X1621063Y1254724D03*
Y1250984D03*
X1624803Y1243503D03*
Y1247243D03*
X1628543Y1250984D03*
Y1254724D03*
X1632283Y1247243D03*
Y1243503D03*
X1617322Y1247243D03*
Y1243503D03*
X1636023Y1236023D03*
Y1232283D03*
X1639763Y1224803D03*
Y1228543D03*
X1643504Y1236023D03*
Y1232283D03*
X1647244Y1228543D03*
Y1224803D03*
X1636023Y1254724D03*
Y1250984D03*
X1639763Y1243503D03*
Y1247243D03*
X1643504Y1250984D03*
Y1254724D03*
X1647244Y1247243D03*
Y1243503D03*
X1654724Y1224803D03*
Y1228543D03*
X1658464Y1232283D03*
Y1236023D03*
X1662204Y1228543D03*
Y1224803D03*
X1650984Y1236023D03*
Y1232283D03*
X1654724Y1247243D03*
X1662204Y1243503D03*
Y1247243D03*
X1658464Y1254724D03*
Y1250984D03*
X1654724Y1243503D03*
X1650984Y1254724D03*
Y1250984D03*
X1669685Y1224803D03*
Y1228543D03*
X1677165Y1224803D03*
Y1228543D03*
X1673425Y1232283D03*
Y1236023D03*
X1680905D03*
Y1232283D03*
X1665945Y1236023D03*
Y1232283D03*
X1677165Y1243503D03*
Y1247243D03*
X1680905Y1250984D03*
Y1254724D03*
X1673425D03*
Y1250984D03*
X1669685Y1247243D03*
Y1243503D03*
X770472D03*
Y1247243D03*
X774212Y1254724D03*
Y1250984D03*
X777953Y1247243D03*
X781693D03*
X777953Y1239763D03*
X781693D03*
X605905Y1228543D03*
Y1239763D03*
Y1247243D03*
X617126Y1232283D03*
Y1236023D03*
X609646D03*
Y1232283D03*
X620866Y1228543D03*
Y1224803D03*
X613386Y1228543D03*
Y1224803D03*
X770472Y1112598D03*
X639567Y1236023D03*
Y1232283D03*
X632086Y1236023D03*
Y1232283D03*
X635827Y1228543D03*
Y1224803D03*
X628346Y1228543D03*
Y1224803D03*
X624606Y1236023D03*
Y1232283D03*
X639567Y1254724D03*
Y1250984D03*
X628346Y1243503D03*
Y1247243D03*
X624606Y1250984D03*
Y1254724D03*
X632086D03*
Y1250984D03*
X635827Y1247243D03*
Y1243503D03*
X654527Y1236023D03*
Y1232283D03*
X650787Y1224803D03*
Y1228543D03*
X647047Y1232283D03*
Y1236023D03*
X643307Y1228543D03*
Y1224803D03*
X654527Y1254724D03*
Y1250984D03*
X650787Y1243503D03*
Y1247243D03*
X647047Y1250984D03*
Y1254724D03*
X643307Y1247243D03*
Y1243503D03*
X669488Y1236023D03*
Y1232283D03*
X665748Y1224803D03*
Y1228543D03*
X662008Y1232283D03*
Y1236023D03*
X658268Y1228543D03*
Y1224803D03*
X669488Y1254724D03*
Y1250984D03*
X665748Y1243503D03*
Y1247243D03*
X662008Y1250984D03*
Y1254724D03*
X658268Y1247243D03*
Y1243503D03*
X688189Y1228543D03*
Y1224803D03*
X680709D03*
Y1228543D03*
X676968Y1232283D03*
Y1236023D03*
X684449Y1232283D03*
Y1236023D03*
X673228Y1228543D03*
Y1224803D03*
X684449Y1254724D03*
Y1250984D03*
X688189Y1247243D03*
Y1243503D03*
X680709D03*
Y1247243D03*
X676968Y1250984D03*
Y1254724D03*
X673228Y1247243D03*
Y1243503D03*
X695669Y1228543D03*
X699409Y1236023D03*
Y1232283D03*
X703149Y1228543D03*
Y1224803D03*
X695669D03*
X691929Y1232283D03*
Y1236023D03*
X703149Y1243503D03*
Y1247243D03*
X699409Y1254724D03*
Y1250984D03*
X695669Y1243503D03*
Y1247243D03*
X691929Y1250984D03*
Y1254724D03*
X714370Y1236023D03*
Y1232283D03*
X718110Y1228543D03*
Y1224803D03*
X710630D03*
Y1228543D03*
X706890Y1232283D03*
Y1236023D03*
X718110Y1243503D03*
Y1247243D03*
X714370Y1254724D03*
Y1250984D03*
X710630Y1247243D03*
Y1243503D03*
X706890Y1250984D03*
Y1254724D03*
X733071Y1224803D03*
Y1228543D03*
X736811Y1232283D03*
Y1236023D03*
X729331Y1232283D03*
Y1236023D03*
X725590Y1228543D03*
Y1224803D03*
X721850Y1232283D03*
Y1236023D03*
X733071Y1243503D03*
Y1247243D03*
X736811Y1250984D03*
Y1254724D03*
X729331D03*
Y1250984D03*
X725590Y1247243D03*
Y1243503D03*
X721850Y1250984D03*
Y1254724D03*
X748031Y1224803D03*
Y1228543D03*
X744291Y1236023D03*
Y1232283D03*
X740551Y1228543D03*
Y1224803D03*
Y1243503D03*
X744291Y1250984D03*
Y1254724D03*
X748031Y1247243D03*
Y1243503D03*
X740551Y1247243D03*
X602165Y1206102D03*
X605905D03*
X602165Y1198621D03*
X605905D03*
X602165Y1191141D03*
X605905D03*
X602165Y1221062D03*
X605905D03*
Y1213582D03*
X602165D03*
X1516338Y1247243D03*
X602165D03*
G54D78*
X970071Y1409152D03*
Y1365652D03*
G54D71*
X743337Y374862D03*
G54D64*
X1819042Y-27188D03*
Y-37188D03*
Y-47188D03*
X1753686Y-85978D03*
Y-75978D03*
Y-65978D03*
X1564906Y-27086D03*
Y-47086D03*
Y-37086D03*
X1574906Y-66006D03*
Y-86006D03*
Y-76006D03*
X1534542Y-27058D03*
Y-37058D03*
Y-47058D03*
X1499186Y-65978D03*
Y-75978D03*
Y-85978D03*
X1280406Y-26956D03*
Y-46956D03*
Y-36956D03*
X1320406Y-86006D03*
Y-66006D03*
Y-76006D03*
X1248042Y-26928D03*
X1242686Y-65978D03*
Y-75978D03*
Y-85978D03*
X993906Y-26826D03*
Y-46826D03*
Y-36826D03*
X1063906Y-66006D03*
Y-86006D03*
Y-76006D03*
X964542Y-26798D03*
Y-36798D03*
X939542D03*
Y-26798D03*
X989386Y-65978D03*
Y-75978D03*
X964386D03*
Y-65978D03*
X710406Y-26826D03*
Y-36826D03*
X735406D03*
Y-26826D03*
X830406Y-66006D03*
Y-76006D03*
X855406D03*
Y-66006D03*
X1248042Y-36928D03*
Y-46928D03*
X1018906Y-36826D03*
Y-46826D03*
X1217686Y-65978D03*
Y-75978D03*
X1305406Y-36956D03*
Y-46956D03*
Y-26956D03*
X1018906Y-26826D03*
X1217686Y-85978D03*
X1223042Y-26928D03*
Y-36928D03*
X1088906Y-76006D03*
Y-86006D03*
X1345406D03*
Y-76006D03*
Y-66006D03*
X1088906D03*
X1223042Y-46928D03*
X1474186Y-65978D03*
Y-75978D03*
Y-85978D03*
X1509542Y-27058D03*
Y-37058D03*
Y-47058D03*
X1794042Y-27188D03*
Y-37188D03*
Y-47188D03*
X1728686Y-65978D03*
Y-75978D03*
Y-85978D03*
X1589906Y-37086D03*
Y-47086D03*
Y-27086D03*
X1599906Y-76006D03*
Y-86006D03*
Y-66006D03*
G54D77*
X909360Y274606D03*
G54D72*
X1729390Y144095D03*
X1627028D03*
X1169941D03*
X1067579D03*
X965217D03*
X815217D03*
G54D70*
X640522Y630650D03*
X1657510Y374862D03*
X1554695Y630650D03*
X1200423Y374862D03*
X1097608Y630650D03*
X286250Y374862D03*
X183435Y630650D03*
G54D76*
X51043Y144095D03*
X57933Y66811D03*
X153405Y144095D03*
X160295Y66811D03*
X255767Y144095D03*
X262657Y66811D03*
X358129Y144095D03*
X365019Y66811D03*
X508130Y144095D03*
X515020Y66811D03*
X610492Y144095D03*
X617382Y66811D03*
X712854Y144095D03*
X719744Y66811D03*
X822106D03*
X972106D03*
X1074468D03*
X1176830D03*
X1272302Y144095D03*
X1279192Y66811D03*
X1422303Y144095D03*
X1429193Y66811D03*
X1524665Y144095D03*
X1531555Y66811D03*
X1633917D03*
X1736279D03*
G54D69*
X736447Y630650D03*
X1650620D03*
X1561585Y374862D03*
X1193533Y630650D03*
X1104498Y374862D03*
X279360Y630650D03*
X190325Y374862D03*
G54D68*
X1817323Y56693D03*
G54D67*
X924650Y1326119D03*
X370202Y1313064D03*
X559070Y686509D03*
X561570Y694509D03*
X559070Y702509D03*
X561570Y710509D03*
X559070Y718509D03*
X460950Y326485D03*
X463950Y334359D03*
X460950Y342233D03*
X463950Y350107D03*
X937000Y313983D03*
X66856Y105949D03*
X169218D03*
X271580D03*
X373942D03*
X893284Y235040D03*
X899352Y310261D03*
X1079748Y321042D03*
X1209184Y461917D03*
X1302896Y342096D03*
X1438116Y105949D03*
X1540478D03*
X1642840D03*
X1745202D03*
X1089096Y543562D03*
X1754906Y822634D03*
X212980Y485254D03*
X205680Y478168D03*
X138290Y485260D03*
X148692Y478199D03*
X788482Y476118D03*
X778080Y483179D03*
X721092Y483210D03*
X713792Y476124D03*
X1245568Y476118D03*
X1235166Y483179D03*
X1178178Y483210D03*
X1170878Y476124D03*
X1584240Y485254D03*
X1576940Y478168D03*
X1519952Y478199D03*
X1509550Y485260D03*
X35688Y127128D03*
X28388Y120042D03*
Y134215D03*
X35688Y112955D03*
X130750Y120042D03*
Y134215D03*
X148692Y421047D03*
X138290Y413987D03*
X140690Y399813D03*
X148692Y406874D03*
Y392701D03*
X138050Y127128D03*
Y112955D03*
X138290Y471087D03*
Y442333D03*
Y428160D03*
X148692Y435221D03*
X205680Y399782D03*
X212980Y406868D03*
Y392695D03*
Y471081D03*
Y435215D03*
X205680Y442302D03*
Y428128D03*
Y413955D03*
X212980Y421041D03*
X233112Y134215D03*
Y120042D03*
X240412Y127128D03*
Y112955D03*
X342774Y127128D03*
X335474Y134215D03*
Y120042D03*
X342774Y112955D03*
X533092Y127096D03*
Y112923D03*
X543494Y134209D03*
Y120035D03*
X635454Y127096D03*
Y112923D03*
X645856Y134209D03*
Y120035D03*
X748218Y134209D03*
X737816Y127096D03*
X748218Y120035D03*
X737816Y112923D03*
X721092Y469037D03*
X778080Y469006D03*
X840178Y127096D03*
Y112923D03*
X850580Y134209D03*
Y120035D03*
X990178Y127096D03*
Y112923D03*
X1000580Y134209D03*
Y120035D03*
X1092540Y127096D03*
Y112923D03*
X1102942Y134209D03*
Y120035D03*
X1178178Y469037D03*
X1205304Y134209D03*
X1194902Y127096D03*
X1205304Y120035D03*
X1194902Y112923D03*
X1235166Y469006D03*
X1297264Y127096D03*
Y112923D03*
X1307666Y134209D03*
Y120035D03*
X1399648Y120042D03*
Y134215D03*
X1406948Y127128D03*
Y112955D03*
X1509310D03*
X1509550Y428160D03*
Y413987D03*
X1511950Y399813D03*
X1502010Y134215D03*
X1509310Y127128D03*
X1502010Y120042D03*
X1519952Y421047D03*
Y406874D03*
Y392701D03*
X1509550Y471087D03*
Y442333D03*
X1519952Y435221D03*
X1576940Y442302D03*
Y428128D03*
Y413955D03*
Y399782D03*
X1584240Y421041D03*
Y406868D03*
Y392695D03*
X1604372Y134215D03*
X1611672Y127128D03*
X1604372Y120042D03*
X1611672Y112955D03*
X1584240Y471081D03*
Y435215D03*
X1706734Y134215D03*
Y120042D03*
X1714034Y127128D03*
Y112955D03*
X148692Y536506D03*
Y522333D03*
X138290Y515221D03*
X148692Y492373D03*
X138290Y529394D03*
X205680Y492341D03*
Y536475D03*
X212980Y529388D03*
Y515215D03*
X205680Y522302D03*
X713792Y612817D03*
Y598644D03*
Y584471D03*
Y570297D03*
Y534431D03*
Y520258D03*
Y490297D03*
X721092Y591557D03*
Y577384D03*
Y563210D03*
Y527344D03*
Y513171D03*
Y605730D03*
X778080Y563179D03*
Y527313D03*
Y513139D03*
Y591525D03*
Y605699D03*
Y577352D03*
X788482Y570291D03*
Y534425D03*
Y520252D03*
Y490291D03*
Y612811D03*
Y598638D03*
Y584465D03*
X1170878Y612817D03*
Y598644D03*
Y584471D03*
Y570297D03*
Y534431D03*
Y520258D03*
Y490297D03*
X1178178Y563210D03*
Y527344D03*
Y513171D03*
Y605730D03*
Y591557D03*
Y577384D03*
X1235166Y527313D03*
Y513139D03*
Y605699D03*
Y591525D03*
Y577352D03*
Y563179D03*
X1245568Y570291D03*
Y534425D03*
Y520252D03*
Y490291D03*
Y612811D03*
Y598638D03*
Y584465D03*
X1509550Y529394D03*
Y515221D03*
X1519952Y536506D03*
Y522333D03*
Y492373D03*
X1576940Y536475D03*
Y522302D03*
Y492341D03*
X1584240Y529388D03*
Y515215D03*
X7982Y1527335D03*
G54D65*
X1592187Y-81006D03*
X1582187Y-42086D03*
X1736405Y-80978D03*
X1801761Y-42188D03*
X1517261Y-42058D03*
X1481905Y-80978D03*
X1230761Y-41928D03*
X1337687Y-81006D03*
X1081187D03*
X1225405Y-80978D03*
X1297687Y-41956D03*
X1011187Y-41826D03*
X213969Y1460153D03*
Y1449153D03*
X227249Y1460153D03*
Y1449153D03*
G54D79*
X1817323Y1567323D03*
G54D66*
X1009333Y1344993D03*
X1015659Y681354D03*
X933725Y587636D03*
X933741Y596387D03*
X486837Y703006D03*
X394883Y340077D03*
X217907Y1428752D03*
X415203Y1497818D03*
X397267Y1516347D03*
X295011Y461917D03*
X523943Y105949D03*
X626305D03*
X728667D03*
X752097Y461917D03*
X831029Y105949D03*
X981029D03*
X1083391D03*
X1080351Y329955D03*
X1185753Y105949D03*
X1288115D03*
X1366535Y353200D03*
Y337452D03*
X1363535Y345326D03*
Y329578D03*
X1666271Y461919D03*
X174923Y543562D03*
X632009D03*
X1546183Y543564D03*
X385091Y1299153D03*
X454385Y1303545D03*
X256705Y476124D03*
X264005Y483210D03*
X605779Y478199D03*
X595377Y485260D03*
X331395Y476118D03*
X320993Y483179D03*
X670067Y485254D03*
X662767Y478168D03*
X1127153Y485254D03*
X1119853Y478168D03*
X1062865Y478199D03*
X1052463Y485260D03*
X1702655Y476118D03*
X1692253Y483179D03*
X1635265Y483210D03*
X1627965Y476124D03*
X76005Y127096D03*
Y112923D03*
X86407Y120035D03*
Y134209D03*
X178367Y127096D03*
Y112923D03*
X188769Y134209D03*
Y120035D03*
X264005Y469037D03*
X291131Y134209D03*
Y120035D03*
X280729Y127096D03*
Y112923D03*
X320993Y469005D03*
X393493Y134209D03*
X383091Y127096D03*
X393493Y120035D03*
X383091Y112923D03*
X485475Y134215D03*
Y120042D03*
X492775Y127128D03*
Y112955D03*
X587837Y134215D03*
Y120042D03*
X597777Y399813D03*
X595137Y127128D03*
Y112955D03*
X595377Y471087D03*
Y442333D03*
Y428160D03*
Y413987D03*
X605779Y435221D03*
Y421047D03*
Y406874D03*
Y392701D03*
X670067Y435215D03*
X662767Y442302D03*
Y428128D03*
Y413955D03*
X670067Y421041D03*
X662767Y399782D03*
X670067Y406868D03*
Y392695D03*
Y471081D03*
X690199Y120042D03*
X697499Y127128D03*
X690199Y134215D03*
X697499Y112955D03*
X799861D03*
Y127128D03*
X792561Y120042D03*
Y134215D03*
X949861Y112955D03*
X942561Y120042D03*
Y134215D03*
X949861Y127128D03*
X1044923Y134215D03*
X1052223Y127128D03*
X1044923Y120042D03*
X1052223Y112955D03*
X1052463Y471087D03*
Y442333D03*
Y428160D03*
Y413987D03*
X1054863Y399813D03*
X1062865Y435221D03*
Y421047D03*
Y406874D03*
Y392701D03*
X1119853Y399782D03*
Y442302D03*
Y428128D03*
Y413955D03*
X1154585Y112955D03*
X1127153Y471081D03*
Y435215D03*
Y421041D03*
Y406868D03*
Y392695D03*
X1154585Y127128D03*
X1147285Y134215D03*
Y120042D03*
X1249647Y134215D03*
Y120042D03*
X1256947Y127128D03*
Y112955D03*
X1447265Y127096D03*
Y112923D03*
X1457667Y134209D03*
Y120035D03*
X1560029Y134209D03*
X1549627Y127096D03*
X1560029Y120035D03*
X1549627Y112923D03*
X1651989Y127096D03*
Y112923D03*
X1635265Y469037D03*
X1662391Y134209D03*
Y120035D03*
X1692253Y469006D03*
X1754351Y127096D03*
Y112923D03*
X1764753Y134209D03*
Y120035D03*
X264005Y513171D03*
X256705Y520258D03*
Y490297D03*
Y612817D03*
X264005Y591557D03*
Y605730D03*
X256705Y598644D03*
X264005Y577384D03*
X256705Y584471D03*
Y570297D03*
X264005Y563210D03*
X256705Y534431D03*
X264005Y527344D03*
X320993Y513139D03*
Y591525D03*
Y605699D03*
Y577352D03*
Y563179D03*
Y527313D03*
X331395Y490291D03*
Y612811D03*
Y598638D03*
Y584465D03*
Y570291D03*
Y534425D03*
Y520252D03*
X595377Y529394D03*
Y515221D03*
X605779Y536506D03*
Y522333D03*
Y492373D03*
X670067Y529388D03*
X662767Y536475D03*
Y522302D03*
X670067Y515215D03*
X662767Y492341D03*
X1052463Y529394D03*
Y515221D03*
X1062865Y536506D03*
Y522333D03*
Y492373D03*
X1119853Y536475D03*
Y522302D03*
Y492341D03*
X1127153Y529388D03*
Y515215D03*
X1627965Y584471D03*
Y570297D03*
Y534431D03*
Y520258D03*
Y490297D03*
Y612817D03*
Y598644D03*
X1635265Y527344D03*
Y513171D03*
Y605730D03*
Y591557D03*
Y577384D03*
Y563210D03*
X1692253Y605699D03*
Y591525D03*
Y577352D03*
Y563179D03*
Y527313D03*
Y513139D03*
X1702655Y534425D03*
Y520252D03*
Y490291D03*
Y612811D03*
Y598638D03*
Y584465D03*
Y570291D03*
G54D75*
X770472Y1490945D03*
X820079Y388583D03*
X1020866D03*
X1070472Y1490945D03*
G54D63*
X19685Y-83298D03*
X1821260D03*
X26789Y1373669D03*
X1796847Y1517889D03*
X1809883Y120792D03*
X184851Y334492D03*
X19685Y1801195D03*
X1821260D03*
G54D73*
X1030905Y1066535D03*
Y1263386D03*
X810038Y1066535D03*
Y1263386D03*
X573818Y1066535D03*
Y1263386D03*
X352952Y1066535D03*
Y1263386D03*
X116731Y1066535D03*
Y1263386D03*
X1724212Y1066535D03*
Y1263386D03*
X1487991Y1066535D03*
Y1263386D03*
X1267125Y1066535D03*
Y1263386D03*
%LPC*%
G75*
G36*
G01X145878Y1198621D02*
G02I-800J0D01*
G37*
G36*
G01Y1191141D02*
G02I-800J0D01*
G37*
G36*
G01X149618D02*
G02I-800J0D01*
G37*
G36*
G01Y1198621D02*
G02I-800J0D01*
G37*
G36*
G01X145878Y1221062D02*
G02I-800J0D01*
G37*
G36*
G01X149618D02*
G02I-800J0D01*
G37*
G36*
G01Y1213582D02*
G02I-800J0D01*
G37*
G36*
G01X145878D02*
G02I-800J0D01*
G37*
G36*
G01Y1206102D02*
G02I-800J0D01*
G37*
G36*
G01X149618D02*
G02I-800J0D01*
G37*
G36*
G01X145878Y1228543D02*
G02I-800J0D01*
G37*
G36*
G01X149618D02*
G02I-800J0D01*
G37*
G36*
G01Y1247243D02*
G02I-800J0D01*
G37*
G36*
G01X145878D02*
G02I-800J0D01*
G37*
G36*
G01X149618Y1239763D02*
G02I-800J0D01*
G37*
G36*
G01X145878D02*
G02I-800J0D01*
G37*
G36*
G01X157099Y1187401D02*
G02I-800J0D01*
G37*
G36*
G01X164579D02*
G02I-800J0D01*
G37*
G36*
G01X153359D02*
G02I-800J0D01*
G37*
G36*
G01X157099Y1202362D02*
G02I-800J0D01*
G37*
G36*
G01Y1194881D02*
G02I-800J0D01*
G37*
G36*
G01X153359Y1202362D02*
G02I-800J0D01*
G37*
G36*
G01Y1194881D02*
G02I-800J0D01*
G37*
G36*
G01X164579D02*
G02I-800J0D01*
G37*
G36*
G01Y1202362D02*
G02I-800J0D01*
G37*
G36*
G01X157099Y1217322D02*
G02I-800J0D01*
G37*
G36*
G01Y1209842D02*
G02I-800J0D01*
G37*
G36*
G01X153359D02*
G02I-800J0D01*
G37*
G36*
G01X164579D02*
G02I-800J0D01*
G37*
G36*
G01Y1217322D02*
G02I-800J0D01*
G37*
G36*
G01X153359D02*
G02I-800J0D01*
G37*
G36*
G01X160839Y1236023D02*
G02I-800J0D01*
G37*
G36*
G01X164579Y1224803D02*
G02I-800J0D01*
G37*
G36*
G01X157099D02*
G02I-800J0D01*
G37*
G36*
G01Y1228543D02*
G02I-800J0D01*
G37*
G36*
G01X164579D02*
G02I-800J0D01*
G37*
G36*
G01X160839Y1232283D02*
G02I-800J0D01*
G37*
G36*
G01X153359Y1236023D02*
G02I-800J0D01*
G37*
G36*
G01Y1232283D02*
G02I-800J0D01*
G37*
G36*
G01Y1250984D02*
G02I-800J0D01*
G37*
G36*
G01X157099Y1243503D02*
G02I-800J0D01*
G37*
G36*
G01Y1247243D02*
G02I-800J0D01*
G37*
G36*
G01X164579Y1243503D02*
G02I-800J0D01*
G37*
G36*
G01X160839Y1250984D02*
G02I-800J0D01*
G37*
G36*
G01X164579Y1247243D02*
G02I-800J0D01*
G37*
G36*
G01X153359Y1254724D02*
G02I-800J0D01*
G37*
G36*
G01X160839D02*
G02I-800J0D01*
G37*
G36*
G01X175799Y1075196D02*
G02I-800J0D01*
G37*
G36*
G01Y1078936D02*
G02I-800J0D01*
G37*
G36*
G01X179540Y1082677D02*
G02I-800J0D01*
G37*
G36*
G01Y1086417D02*
G02I-800J0D01*
G37*
G36*
G01X175799Y1093897D02*
G02I-800J0D01*
G37*
G36*
G01Y1097637D02*
G02I-800J0D01*
G37*
G36*
G01X179540Y1101376D02*
G02I-800J0D01*
G37*
G36*
G01Y1105117D02*
G02I-800J0D01*
G37*
G36*
G01X168319Y1187401D02*
G02I-800J0D01*
G37*
G36*
G01X175799Y1198621D02*
G02I-800J0D01*
G37*
G36*
G01Y1191141D02*
G02I-800J0D01*
G37*
G36*
G01X168319Y1194881D02*
G02I-800J0D01*
G37*
G36*
G01X172059Y1198621D02*
G02I-800J0D01*
G37*
G36*
G01Y1191141D02*
G02I-800J0D01*
G37*
G36*
G01X168319Y1202362D02*
G02I-800J0D01*
G37*
G36*
G01Y1209842D02*
G02I-800J0D01*
G37*
G36*
G01X172059Y1213582D02*
G02I-800J0D01*
G37*
G36*
G01Y1206102D02*
G02I-800J0D01*
G37*
G36*
G01X175799D02*
G02I-800J0D01*
G37*
G36*
G01X168319Y1217322D02*
G02I-800J0D01*
G37*
G36*
G01X175799Y1213582D02*
G02I-800J0D01*
G37*
G36*
G01X179540Y1228543D02*
G02I-800J0D01*
G37*
G36*
G01X172059Y1224803D02*
G02I-800J0D01*
G37*
G36*
G01X175799Y1232283D02*
G02I-800J0D01*
G37*
G36*
G01X172059Y1228543D02*
G02I-800J0D01*
G37*
G36*
G01X179540Y1224803D02*
G02I-800J0D01*
G37*
G36*
G01X175799Y1236023D02*
G02I-800J0D01*
G37*
G36*
G01X168319Y1232283D02*
G02I-800J0D01*
G37*
G36*
G01Y1236023D02*
G02I-800J0D01*
G37*
G36*
G01Y1250984D02*
G02I-800J0D01*
G37*
G36*
G01X179540Y1247243D02*
G02I-800J0D01*
G37*
G36*
G01X172059D02*
G02I-800J0D01*
G37*
G36*
G01X175799Y1250984D02*
G02I-800J0D01*
G37*
G36*
G01X172059Y1243503D02*
G02I-800J0D01*
G37*
G36*
G01X179540D02*
G02I-800J0D01*
G37*
G36*
G01X168319Y1254724D02*
G02I-800J0D01*
G37*
G36*
G01X175799D02*
G02I-800J0D01*
G37*
G36*
G01X190760Y1075196D02*
G02I-800J0D01*
G37*
G36*
G01X183280D02*
G02I-800J0D01*
G37*
G36*
G01X198240D02*
G02I-800J0D01*
G37*
G36*
G01X187020Y1082677D02*
G02I-800J0D01*
G37*
G36*
G01Y1086417D02*
G02I-800J0D01*
G37*
G36*
G01X183280Y1078936D02*
G02I-800J0D01*
G37*
G36*
G01X190760D02*
G02I-800J0D01*
G37*
G36*
G01X194500Y1086417D02*
G02I-800J0D01*
G37*
G36*
G01Y1082677D02*
G02I-800J0D01*
G37*
G36*
G01X198240Y1078936D02*
G02I-800J0D01*
G37*
G36*
G01X194500Y1105117D02*
G02I-800J0D01*
G37*
G36*
G01X198240Y1093897D02*
G02I-800J0D01*
G37*
G36*
G01X190760Y1097637D02*
G02I-800J0D01*
G37*
G36*
G01X187020Y1105117D02*
G02I-800J0D01*
G37*
G36*
G01X198240Y1097637D02*
G02I-800J0D01*
G37*
G36*
G01X183280Y1093897D02*
G02I-800J0D01*
G37*
G36*
G01Y1097637D02*
G02I-800J0D01*
G37*
G36*
G01X194500Y1101376D02*
G02I-800J0D01*
G37*
G36*
G01X187020D02*
G02I-800J0D01*
G37*
G36*
G01X190760Y1093897D02*
G02I-800J0D01*
G37*
G36*
G01X183280Y1236023D02*
G02I-800J0D01*
G37*
G36*
G01X198240D02*
G02I-800J0D01*
G37*
G36*
G01X187020Y1224803D02*
G02I-800J0D01*
G37*
G36*
G01X183280Y1232283D02*
G02I-800J0D01*
G37*
G36*
G01X194500Y1228543D02*
G02I-800J0D01*
G37*
G36*
G01X198240Y1232283D02*
G02I-800J0D01*
G37*
G36*
G01X190760Y1236023D02*
G02I-800J0D01*
G37*
G36*
G01X187020Y1228543D02*
G02I-800J0D01*
G37*
G36*
G01X194500Y1224803D02*
G02I-800J0D01*
G37*
G36*
G01X190760Y1232283D02*
G02I-800J0D01*
G37*
G36*
G01X183280Y1250984D02*
G02I-800J0D01*
G37*
G36*
G01X198240D02*
G02I-800J0D01*
G37*
G36*
G01X194500Y1247243D02*
G02I-800J0D01*
G37*
G36*
G01Y1243503D02*
G02I-800J0D01*
G37*
G36*
G01X190760Y1250984D02*
G02I-800J0D01*
G37*
G36*
G01X187020Y1247243D02*
G02I-800J0D01*
G37*
G36*
G01Y1243503D02*
G02I-800J0D01*
G37*
G36*
G01X183280Y1254724D02*
G02I-800J0D01*
G37*
G36*
G01X198240D02*
G02I-800J0D01*
G37*
G36*
G01X190760D02*
G02I-800J0D01*
G37*
G36*
G01X205721Y1075196D02*
G02I-800J0D01*
G37*
G36*
G01X213201D02*
G02I-800J0D01*
G37*
G36*
G01Y1078936D02*
G02I-800J0D01*
G37*
G36*
G01X209461Y1082677D02*
G02I-800J0D01*
G37*
G36*
G01X201981D02*
G02I-800J0D01*
G37*
G36*
G01Y1086417D02*
G02I-800J0D01*
G37*
G36*
G01X209461D02*
G02I-800J0D01*
G37*
G36*
G01X205721Y1078936D02*
G02I-800J0D01*
G37*
G36*
G01Y1097637D02*
G02I-800J0D01*
G37*
G36*
G01X209461Y1101376D02*
G02I-800J0D01*
G37*
G36*
G01X213201Y1097637D02*
G02I-800J0D01*
G37*
G36*
G01X209461Y1105117D02*
G02I-800J0D01*
G37*
G36*
G01X213201Y1093897D02*
G02I-800J0D01*
G37*
G36*
G01X201981Y1101376D02*
G02I-800J0D01*
G37*
G36*
G01X205721Y1093897D02*
G02I-800J0D01*
G37*
G36*
G01X201981Y1105117D02*
G02I-800J0D01*
G37*
G36*
G01X205721Y1232283D02*
G02I-800J0D01*
G37*
G36*
G01X201981Y1224803D02*
G02I-800J0D01*
G37*
G36*
G01X213201Y1232283D02*
G02I-800J0D01*
G37*
G36*
G01X209461Y1228543D02*
G02I-800J0D01*
G37*
G36*
G01X213201Y1236023D02*
G02I-800J0D01*
G37*
G36*
G01X209461Y1224803D02*
G02I-800J0D01*
G37*
G36*
G01X201981Y1228543D02*
G02I-800J0D01*
G37*
G36*
G01X205721Y1236023D02*
G02I-800J0D01*
G37*
G36*
G01X209461Y1243503D02*
G02I-800J0D01*
G37*
G36*
G01X205721Y1250984D02*
G02I-800J0D01*
G37*
G36*
G01X209461Y1247243D02*
G02I-800J0D01*
G37*
G36*
G01X201981Y1243503D02*
G02I-800J0D01*
G37*
G36*
G01X213201Y1250984D02*
G02I-800J0D01*
G37*
G36*
G01X201981Y1247243D02*
G02I-800J0D01*
G37*
G36*
G01X213201Y1254724D02*
G02I-800J0D01*
G37*
G36*
G01X205721D02*
G02I-800J0D01*
G37*
G36*
G01X228162Y1075196D02*
G02I-800J0D01*
G37*
G36*
G01X220681D02*
G02I-800J0D01*
G37*
G36*
G01Y1078936D02*
G02I-800J0D01*
G37*
G36*
G01X216941Y1086417D02*
G02I-800J0D01*
G37*
G36*
G01X224422Y1082677D02*
G02I-800J0D01*
G37*
G36*
G01X228162Y1078936D02*
G02I-800J0D01*
G37*
G36*
G01X216941Y1082677D02*
G02I-800J0D01*
G37*
G36*
G01X224422Y1086417D02*
G02I-800J0D01*
G37*
G36*
G01X216941Y1101376D02*
G02I-800J0D01*
G37*
G36*
G01X228162Y1093897D02*
G02I-800J0D01*
G37*
G36*
G01X220681Y1097637D02*
G02I-800J0D01*
G37*
G36*
G01X224421Y1101376D02*
G02I-800J0D01*
G37*
G36*
G01Y1105117D02*
G02I-800J0D01*
G37*
G36*
G01X216941D02*
G02I-800J0D01*
G37*
G36*
G01X220681Y1093897D02*
G02I-800J0D01*
G37*
G36*
G01X228162Y1097637D02*
G02I-800J0D01*
G37*
G36*
G01X220681Y1232283D02*
G02I-800J0D01*
G37*
G36*
G01Y1236023D02*
G02I-800J0D01*
G37*
G36*
G01X216941Y1224803D02*
G02I-800J0D01*
G37*
G36*
G01X224422D02*
G02I-800J0D01*
G37*
G36*
G01X228162Y1232283D02*
G02I-800J0D01*
G37*
G36*
G01X224422Y1228543D02*
G02I-800J0D01*
G37*
G36*
G01X216941D02*
G02I-800J0D01*
G37*
G36*
G01X228162Y1236023D02*
G02I-800J0D01*
G37*
G36*
G01X224422Y1243503D02*
G02I-800J0D01*
G37*
G36*
G01X216941Y1247243D02*
G02I-800J0D01*
G37*
G36*
G01X224422D02*
G02I-800J0D01*
G37*
G36*
G01X216941Y1243503D02*
G02I-800J0D01*
G37*
G36*
G01X220681Y1250984D02*
G02I-800J0D01*
G37*
G36*
G01X228162D02*
G02I-800J0D01*
G37*
G36*
G01X220681Y1254724D02*
G02I-800J0D01*
G37*
G36*
G01X228162D02*
G02I-800J0D01*
G37*
G36*
G01X235641Y1075195D02*
G02I-800J0D01*
G37*
G36*
G01X243121Y1075196D02*
G02I-800J0D01*
G37*
G36*
G01X231902Y1082677D02*
G02I-800J0D01*
G37*
G36*
G01Y1086417D02*
G02I-800J0D01*
G37*
G36*
G01X243121Y1078936D02*
G02I-800J0D01*
G37*
G36*
G01X246861Y1082677D02*
G02I-800J0D01*
G37*
G36*
G01X239381Y1082676D02*
G02I-800J0D01*
G37*
G36*
G01X235641Y1078935D02*
G02I-800J0D01*
G37*
G36*
G01X246861Y1086417D02*
G02I-800J0D01*
G37*
G36*
G01X239381Y1086416D02*
G02I-800J0D01*
G37*
G36*
G01X231902Y1101376D02*
G02I-800J0D01*
G37*
G36*
G01X235641Y1093897D02*
G02I-800J0D01*
G37*
G36*
G01X246862Y1105117D02*
G02I-800J0D01*
G37*
G36*
G01X243121Y1097637D02*
G02I-800J0D01*
G37*
G36*
G01X235641D02*
G02I-800J0D01*
G37*
G36*
G01X239382Y1101376D02*
G02I-800J0D01*
G37*
G36*
G01X246862D02*
G02I-800J0D01*
G37*
G36*
G01X239382Y1105117D02*
G02I-800J0D01*
G37*
G36*
G01X243121Y1093897D02*
G02I-800J0D01*
G37*
G36*
G01X231902Y1105117D02*
G02I-800J0D01*
G37*
G36*
G01X239382Y1224803D02*
G02I-800J0D01*
G37*
G36*
G01Y1228543D02*
G02I-800J0D01*
G37*
G36*
G01X231902D02*
G02I-800J0D01*
G37*
G36*
G01X243122Y1236023D02*
G02I-800J0D01*
G37*
G36*
G01X231902Y1224803D02*
G02I-800J0D01*
G37*
G36*
G01X243122Y1232283D02*
G02I-800J0D01*
G37*
G36*
G01X246862Y1228543D02*
G02I-800J0D01*
G37*
G36*
G01X235642Y1232283D02*
G02I-800J0D01*
G37*
G36*
G01X246862Y1224803D02*
G02I-800J0D01*
G37*
G36*
G01X235642Y1236023D02*
G02I-800J0D01*
G37*
G36*
G01X239382Y1247243D02*
G02I-800J0D01*
G37*
G36*
G01X246862Y1243503D02*
G02I-800J0D01*
G37*
G36*
G01X231902D02*
G02I-800J0D01*
G37*
G36*
G01X243122Y1250984D02*
G02I-800J0D01*
G37*
G36*
G01X235642D02*
G02I-800J0D01*
G37*
G36*
G01X246862Y1247243D02*
G02I-800J0D01*
G37*
G36*
G01X239382Y1243503D02*
G02I-800J0D01*
G37*
G36*
G01X231902Y1247243D02*
G02I-800J0D01*
G37*
G36*
G01X235642Y1254724D02*
G02I-800J0D01*
G37*
G36*
G01X243122D02*
G02I-800J0D01*
G37*
G36*
G01X250602Y1075196D02*
G02I-800J0D01*
G37*
G36*
G01X258082D02*
G02I-800J0D01*
G37*
G36*
G01X250602Y1078936D02*
G02I-800J0D01*
G37*
G36*
G01X261822Y1086417D02*
G02I-800J0D01*
G37*
G36*
G01X254342Y1082676D02*
G02I-800J0D01*
G37*
G36*
G01X258082Y1078936D02*
G02I-800J0D01*
G37*
G36*
G01X254342Y1086416D02*
G02I-800J0D01*
G37*
G36*
G01X261822Y1082677D02*
G02I-800J0D01*
G37*
G36*
G01X250602Y1097637D02*
G02I-800J0D01*
G37*
G36*
G01X258082D02*
G02I-800J0D01*
G37*
G36*
G01X250602Y1093897D02*
G02I-800J0D01*
G37*
G36*
G01X254343Y1105117D02*
G02I-800J0D01*
G37*
G36*
G01Y1101376D02*
G02I-800J0D01*
G37*
G36*
G01X258082Y1093897D02*
G02I-800J0D01*
G37*
G36*
G01X261823Y1105117D02*
G02I-800J0D01*
G37*
G36*
G01Y1101376D02*
G02I-800J0D01*
G37*
G36*
G01Y1224803D02*
G02I-800J0D01*
G37*
G36*
G01X254343Y1228543D02*
G02I-800J0D01*
G37*
G36*
G01X250603Y1232283D02*
G02I-800J0D01*
G37*
G36*
G01X258083D02*
G02I-800J0D01*
G37*
G36*
G01Y1236023D02*
G02I-800J0D01*
G37*
G36*
G01X261823Y1228543D02*
G02I-800J0D01*
G37*
G36*
G01X254343Y1224803D02*
G02I-800J0D01*
G37*
G36*
G01X250603Y1236023D02*
G02I-800J0D01*
G37*
G36*
G01X261823Y1243503D02*
G02I-800J0D01*
G37*
G36*
G01X250603Y1250984D02*
G02I-800J0D01*
G37*
G36*
G01X261823Y1247243D02*
G02I-800J0D01*
G37*
G36*
G01X258083Y1250984D02*
G02I-800J0D01*
G37*
G36*
G01X254343Y1247243D02*
G02I-800J0D01*
G37*
G36*
G01Y1243503D02*
G02I-800J0D01*
G37*
G36*
G01X258083Y1254724D02*
G02I-800J0D01*
G37*
G36*
G01X250603D02*
G02I-800J0D01*
G37*
G36*
G01X280523Y1075196D02*
G02I-800J0D01*
G37*
G36*
G01X265562D02*
G02I-800J0D01*
G37*
G36*
G01X273043D02*
G02I-800J0D01*
G37*
G36*
G01X276782Y1082677D02*
G02I-800J0D01*
G37*
G36*
G01Y1086417D02*
G02I-800J0D01*
G37*
G36*
G01X269302Y1082676D02*
G02I-800J0D01*
G37*
G36*
G01X273043Y1078936D02*
G02I-800J0D01*
G37*
G36*
G01X269302Y1086416D02*
G02I-800J0D01*
G37*
G36*
G01X280523Y1078936D02*
G02I-800J0D01*
G37*
G36*
G01X265562D02*
G02I-800J0D01*
G37*
G36*
G01Y1097637D02*
G02I-800J0D01*
G37*
G36*
G01X269303Y1105117D02*
G02I-800J0D01*
G37*
G36*
G01X273043Y1097637D02*
G02I-800J0D01*
G37*
G36*
G01X276784Y1105117D02*
G02I-800J0D01*
G37*
G36*
G01X280523Y1093897D02*
G02I-800J0D01*
G37*
G36*
G01X273043D02*
G02I-800J0D01*
G37*
G36*
G01X280523Y1097637D02*
G02I-800J0D01*
G37*
G36*
G01X269303Y1101376D02*
G02I-800J0D01*
G37*
G36*
G01X276784D02*
G02I-800J0D01*
G37*
G36*
G01X265562Y1093897D02*
G02I-800J0D01*
G37*
G36*
G01X265563Y1232283D02*
G02I-800J0D01*
G37*
G36*
G01X269303Y1224803D02*
G02I-800J0D01*
G37*
G36*
G01X276784D02*
G02I-800J0D01*
G37*
G36*
G01X273044Y1236023D02*
G02I-800J0D01*
G37*
G36*
G01X280524Y1232283D02*
G02I-800J0D01*
G37*
G36*
G01Y1236023D02*
G02I-800J0D01*
G37*
G36*
G01X276784Y1228543D02*
G02I-800J0D01*
G37*
G36*
G01X273044Y1232283D02*
G02I-800J0D01*
G37*
G36*
G01X269303Y1228543D02*
G02I-800J0D01*
G37*
G36*
G01X265563Y1236023D02*
G02I-800J0D01*
G37*
G36*
G01Y1250984D02*
G02I-800J0D01*
G37*
G36*
G01X269303Y1243503D02*
G02I-800J0D01*
G37*
G36*
G01Y1247243D02*
G02I-800J0D01*
G37*
G36*
G01X273044Y1250984D02*
G02I-800J0D01*
G37*
G36*
G01X276784Y1243503D02*
G02I-800J0D01*
G37*
G36*
G01Y1247243D02*
G02I-800J0D01*
G37*
G36*
G01X280524Y1250984D02*
G02I-800J0D01*
G37*
G36*
G01X265563Y1254724D02*
G02I-800J0D01*
G37*
G36*
G01X273044D02*
G02I-800J0D01*
G37*
G36*
G01X280524D02*
G02I-800J0D01*
G37*
G36*
G01X288003Y1075196D02*
G02I-800J0D01*
G37*
G36*
G01X295484D02*
G02I-800J0D01*
G37*
G36*
G01X291743Y1086417D02*
G02I-800J0D01*
G37*
G36*
G01X288003Y1078936D02*
G02I-800J0D01*
G37*
G36*
G01X291743Y1082677D02*
G02I-800J0D01*
G37*
G36*
G01X284263Y1082676D02*
G02I-800J0D01*
G37*
G36*
G01Y1086416D02*
G02I-800J0D01*
G37*
G36*
G01X295484Y1078936D02*
G02I-800J0D01*
G37*
G36*
G01X284264Y1101376D02*
G02I-800J0D01*
G37*
G36*
G01X295484Y1093897D02*
G02I-800J0D01*
G37*
G36*
G01X288003D02*
G02I-800J0D01*
G37*
G36*
G01X295484Y1097637D02*
G02I-800J0D01*
G37*
G36*
G01X284264Y1105117D02*
G02I-800J0D01*
G37*
G36*
G01X291744Y1101376D02*
G02I-800J0D01*
G37*
G36*
G01Y1105117D02*
G02I-800J0D01*
G37*
G36*
G01X288003Y1097637D02*
G02I-800J0D01*
G37*
G36*
G01X295484Y1123818D02*
G02I-800J0D01*
G37*
G36*
G01Y1116338D02*
G02I-800J0D01*
G37*
G36*
G01Y1131299D02*
G02I-800J0D01*
G37*
G36*
G01X295485Y1198621D02*
G02I-800J0D01*
G37*
G36*
G01Y1213582D02*
G02I-800J0D01*
G37*
G36*
G01Y1206102D02*
G02I-800J0D01*
G37*
G36*
G01X288004Y1232283D02*
G02I-800J0D01*
G37*
G36*
G01X284264Y1224803D02*
G02I-800J0D01*
G37*
G36*
G01Y1228543D02*
G02I-800J0D01*
G37*
G36*
G01X288004Y1236023D02*
G02I-800J0D01*
G37*
G36*
G01X295485D02*
G02I-800J0D01*
G37*
G36*
G01X291744Y1224803D02*
G02I-800J0D01*
G37*
G36*
G01X295485Y1232283D02*
G02I-800J0D01*
G37*
G36*
G01X291744Y1228543D02*
G02I-800J0D01*
G37*
G36*
G01X284264Y1243503D02*
G02I-800J0D01*
G37*
G36*
G01Y1247243D02*
G02I-800J0D01*
G37*
G36*
G01X288004Y1250984D02*
G02I-800J0D01*
G37*
G36*
G01X295485D02*
G02I-800J0D01*
G37*
G36*
G01X291744Y1247243D02*
G02I-800J0D01*
G37*
G36*
G01Y1243503D02*
G02I-800J0D01*
G37*
G36*
G01X288004Y1254724D02*
G02I-800J0D01*
G37*
G36*
G01X295485D02*
G02I-800J0D01*
G37*
G36*
G01X302964Y1075196D02*
G02I-800J0D01*
G37*
G36*
G01X310444D02*
G02I-800J0D01*
G37*
G36*
G01X306704Y1082677D02*
G02I-800J0D01*
G37*
G36*
G01X302964Y1078936D02*
G02I-800J0D01*
G37*
G36*
G01X306704Y1086417D02*
G02I-800J0D01*
G37*
G36*
G01X310444Y1078936D02*
G02I-800J0D01*
G37*
G36*
G01X299224Y1086416D02*
G02I-800J0D01*
G37*
G36*
G01Y1082676D02*
G02I-800J0D01*
G37*
G36*
G01X299225Y1105117D02*
G02I-800J0D01*
G37*
G36*
G01Y1101376D02*
G02I-800J0D01*
G37*
G36*
G01X310444Y1097637D02*
G02I-800J0D01*
G37*
G36*
G01X302964D02*
G02I-800J0D01*
G37*
G36*
G01X306705Y1105117D02*
G02I-800J0D01*
G37*
G36*
G01X310444Y1093897D02*
G02I-800J0D01*
G37*
G36*
G01X306705Y1101376D02*
G02I-800J0D01*
G37*
G36*
G01X302964Y1093897D02*
G02I-800J0D01*
G37*
G36*
G01X302965Y1120078D02*
G02I-800J0D01*
G37*
G36*
G01X306705Y1112598D02*
G02I-800J0D01*
G37*
G36*
G01X299225Y1116338D02*
G02I-800J0D01*
G37*
G36*
G01X306705Y1120078D02*
G02I-800J0D01*
G37*
G36*
G01X302965Y1112598D02*
G02I-800J0D01*
G37*
G36*
G01X299225Y1123818D02*
G02I-800J0D01*
G37*
G36*
G01X306705Y1127559D02*
G02I-800J0D01*
G37*
G36*
G01Y1135039D02*
G02I-800J0D01*
G37*
G36*
G01X302965D02*
G02I-800J0D01*
G37*
G36*
G01Y1127559D02*
G02I-800J0D01*
G37*
G36*
G01X299225Y1131299D02*
G02I-800J0D01*
G37*
G36*
G01Y1198621D02*
G02I-800J0D01*
G37*
G36*
G01X306705Y1202362D02*
G02I-800J0D01*
G37*
G36*
G01X302965D02*
G02I-800J0D01*
G37*
G36*
G01X299225Y1213582D02*
G02I-800J0D01*
G37*
G36*
G01X306705Y1209842D02*
G02I-800J0D01*
G37*
G36*
G01Y1217322D02*
G02I-800J0D01*
G37*
G36*
G01X302965Y1209842D02*
G02I-800J0D01*
G37*
G36*
G01X299225Y1206102D02*
G02I-800J0D01*
G37*
G36*
G01X302965Y1217322D02*
G02I-800J0D01*
G37*
G36*
G01Y1232283D02*
G02I-800J0D01*
G37*
G36*
G01X310445D02*
G02I-800J0D01*
G37*
G36*
G01X299225Y1224803D02*
G02I-800J0D01*
G37*
G36*
G01Y1228543D02*
G02I-800J0D01*
G37*
G36*
G01X310445Y1236023D02*
G02I-800J0D01*
G37*
G36*
G01X306705Y1228543D02*
G02I-800J0D01*
G37*
G36*
G01Y1224803D02*
G02I-800J0D01*
G37*
G36*
G01X302965Y1236023D02*
G02I-800J0D01*
G37*
G36*
G01X299225Y1247243D02*
G02I-800J0D01*
G37*
G36*
G01X310445Y1250984D02*
G02I-800J0D01*
G37*
G36*
G01X299225Y1243503D02*
G02I-800J0D01*
G37*
G36*
G01X306705D02*
G02I-800J0D01*
G37*
G36*
G01Y1247243D02*
G02I-800J0D01*
G37*
G36*
G01X302965Y1250984D02*
G02I-800J0D01*
G37*
G36*
G01X310445Y1254724D02*
G02I-800J0D01*
G37*
G36*
G01X302965D02*
G02I-800J0D01*
G37*
G36*
G01X317924Y1075196D02*
G02I-800J0D01*
G37*
G36*
G01X321666Y1090157D02*
G02I-800J0D01*
G37*
G36*
G01X325406D02*
G02I-800J0D01*
G37*
G36*
G01Y1082676D02*
G02I-800J0D01*
G37*
G36*
G01X317924Y1078936D02*
G02I-800J0D01*
G37*
G36*
G01X314184Y1082677D02*
G02I-800J0D01*
G37*
G36*
G01Y1086417D02*
G02I-800J0D01*
G37*
G36*
G01X321666Y1082676D02*
G02I-800J0D01*
G37*
G36*
G01X314185Y1101377D02*
G02I-800J0D01*
G37*
G36*
G01X317925Y1093897D02*
G02I-800J0D01*
G37*
G36*
G01X321666Y1101377D02*
G02I-800J0D01*
G37*
G36*
G01X314185Y1105117D02*
G02I-800J0D01*
G37*
G36*
G01X325406Y1101377D02*
G02I-800J0D01*
G37*
G36*
G01X317925Y1097637D02*
G02I-800J0D01*
G37*
G36*
G01X314185Y1120078D02*
G02I-800J0D01*
G37*
G36*
G01X325406Y1123818D02*
G02I-800J0D01*
G37*
G36*
G01Y1108858D02*
G02I-800J0D01*
G37*
G36*
G01X321666D02*
G02I-800J0D01*
G37*
G36*
G01X317925Y1112598D02*
G02I-800J0D01*
G37*
G36*
G01X325406Y1116338D02*
G02I-800J0D01*
G37*
G36*
G01X314185Y1112598D02*
G02I-800J0D01*
G37*
G36*
G01X317925Y1120078D02*
G02I-800J0D01*
G37*
G36*
G01X321666Y1116338D02*
G02I-800J0D01*
G37*
G36*
G01Y1123818D02*
G02I-800J0D01*
G37*
G36*
G01X314185Y1127558D02*
G02I-800J0D01*
G37*
G36*
G01X317925Y1135039D02*
G02I-800J0D01*
G37*
G36*
G01X314185D02*
G02I-800J0D01*
G37*
G36*
G01X325406Y1131299D02*
G02I-800J0D01*
G37*
G36*
G01X317925Y1127558D02*
G02I-800J0D01*
G37*
G36*
G01X321666Y1131299D02*
G02I-800J0D01*
G37*
G36*
G01Y1198621D02*
G02I-800J0D01*
G37*
G36*
G01X314185Y1202362D02*
G02I-800J0D01*
G37*
G36*
G01X325406Y1198621D02*
G02I-800J0D01*
G37*
G36*
G01X317925Y1202362D02*
G02I-800J0D01*
G37*
G36*
G01Y1217322D02*
G02I-800J0D01*
G37*
G36*
G01Y1209842D02*
G02I-800J0D01*
G37*
G36*
G01X325406Y1213582D02*
G02I-800J0D01*
G37*
G36*
G01X321666Y1221062D02*
G02I-800J0D01*
G37*
G36*
G01X314185Y1209842D02*
G02I-800J0D01*
G37*
G36*
G01X321666Y1206102D02*
G02I-800J0D01*
G37*
G36*
G01Y1213582D02*
G02I-800J0D01*
G37*
G36*
G01X325406Y1221062D02*
G02I-800J0D01*
G37*
G36*
G01Y1206102D02*
G02I-800J0D01*
G37*
G36*
G01X314185Y1217322D02*
G02I-800J0D01*
G37*
G36*
G01X317925Y1236023D02*
G02I-800J0D01*
G37*
G36*
G01X314185Y1224803D02*
G02I-800J0D01*
G37*
G36*
G01X325406Y1228543D02*
G02I-800J0D01*
G37*
G36*
G01X317925Y1232283D02*
G02I-800J0D01*
G37*
G36*
G01X314185Y1228543D02*
G02I-800J0D01*
G37*
G36*
G01X321666D02*
G02I-800J0D01*
G37*
G36*
G01X325406Y1239763D02*
G02I-800J0D01*
G37*
G36*
G01X314185Y1247243D02*
G02I-800J0D01*
G37*
G36*
G01X321666D02*
G02I-800J0D01*
G37*
G36*
G01X317925Y1250984D02*
G02I-800J0D01*
G37*
G36*
G01X321666Y1239763D02*
G02I-800J0D01*
G37*
G36*
G01X314185Y1243503D02*
G02I-800J0D01*
G37*
G36*
G01X325406Y1247243D02*
G02I-800J0D01*
G37*
G36*
G01X317925Y1254724D02*
G02I-800J0D01*
G37*
G36*
G01X602965Y1191141D02*
G02I-800J0D01*
G37*
G36*
G01Y1198621D02*
G02I-800J0D01*
G37*
G36*
G01Y1221062D02*
G02I-800J0D01*
G37*
G36*
G01Y1206102D02*
G02I-800J0D01*
G37*
G36*
G01Y1213582D02*
G02I-800J0D01*
G37*
G36*
G01Y1228543D02*
G02I-800J0D01*
G37*
G36*
G01Y1247243D02*
G02I-800J0D01*
G37*
G36*
G01Y1239763D02*
G02I-800J0D01*
G37*
G36*
G01X614186Y1187401D02*
G02I-800J0D01*
G37*
G36*
G01X610446D02*
G02I-800J0D01*
G37*
G36*
G01X621666D02*
G02I-800J0D01*
G37*
G36*
G01X606705Y1191141D02*
G02I-800J0D01*
G37*
G36*
G01X614186Y1194881D02*
G02I-800J0D01*
G37*
G36*
G01X606705Y1198621D02*
G02I-800J0D01*
G37*
G36*
G01X610446Y1194881D02*
G02I-800J0D01*
G37*
G36*
G01Y1202362D02*
G02I-800J0D01*
G37*
G36*
G01X614186D02*
G02I-800J0D01*
G37*
G36*
G01X621666D02*
G02I-800J0D01*
G37*
G36*
G01Y1194881D02*
G02I-800J0D01*
G37*
G36*
G01X614186Y1217322D02*
G02I-800J0D01*
G37*
G36*
G01X606705Y1221062D02*
G02I-800J0D01*
G37*
G36*
G01X610446Y1217322D02*
G02I-800J0D01*
G37*
G36*
G01Y1209842D02*
G02I-800J0D01*
G37*
G36*
G01X606705Y1206102D02*
G02I-800J0D01*
G37*
G36*
G01Y1213582D02*
G02I-800J0D01*
G37*
G36*
G01X621666Y1209842D02*
G02I-800J0D01*
G37*
G36*
G01X614186D02*
G02I-800J0D01*
G37*
G36*
G01X621666Y1217322D02*
G02I-800J0D01*
G37*
G36*
G01X606705Y1228543D02*
G02I-800J0D01*
G37*
G36*
G01X621666D02*
G02I-800J0D01*
G37*
G36*
G01Y1224803D02*
G02I-800J0D01*
G37*
G36*
G01X610446Y1232283D02*
G02I-800J0D01*
G37*
G36*
G01X617926Y1236023D02*
G02I-800J0D01*
G37*
G36*
G01X614186Y1228543D02*
G02I-800J0D01*
G37*
G36*
G01X617926Y1232283D02*
G02I-800J0D01*
G37*
G36*
G01X610446Y1236023D02*
G02I-800J0D01*
G37*
G36*
G01X614186Y1224803D02*
G02I-800J0D01*
G37*
G36*
G01X606705Y1247243D02*
G02I-800J0D01*
G37*
G36*
G01X617926Y1250984D02*
G02I-800J0D01*
G37*
G36*
G01X621666Y1243503D02*
G02I-800J0D01*
G37*
G36*
G01Y1247243D02*
G02I-800J0D01*
G37*
G36*
G01X614186D02*
G02I-800J0D01*
G37*
G36*
G01Y1243503D02*
G02I-800J0D01*
G37*
G36*
G01X610446Y1250984D02*
G02I-800J0D01*
G37*
G36*
G01X606705Y1239763D02*
G02I-800J0D01*
G37*
G36*
G01X610446Y1254724D02*
G02I-800J0D01*
G37*
G36*
G01X617926D02*
G02I-800J0D01*
G37*
G36*
G01X632886Y1075196D02*
G02I-800J0D01*
G37*
G36*
G01Y1078936D02*
G02I-800J0D01*
G37*
G36*
G01X636627Y1086417D02*
G02I-800J0D01*
G37*
G36*
G01Y1082677D02*
G02I-800J0D01*
G37*
G36*
G01X632886Y1097637D02*
G02I-800J0D01*
G37*
G36*
G01X636627Y1105117D02*
G02I-800J0D01*
G37*
G36*
G01X632886Y1093897D02*
G02I-800J0D01*
G37*
G36*
G01X636627Y1101376D02*
G02I-800J0D01*
G37*
G36*
G01X625406Y1187401D02*
G02I-800J0D01*
G37*
G36*
G01X629146Y1191141D02*
G02I-800J0D01*
G37*
G36*
G01X625406Y1194881D02*
G02I-800J0D01*
G37*
G36*
G01X632886Y1191141D02*
G02I-800J0D01*
G37*
G36*
G01X629146Y1198621D02*
G02I-800J0D01*
G37*
G36*
G01X625406Y1202362D02*
G02I-800J0D01*
G37*
G36*
G01X632886Y1198621D02*
G02I-800J0D01*
G37*
G36*
G01X629146Y1206102D02*
G02I-800J0D01*
G37*
G36*
G01X632886D02*
G02I-800J0D01*
G37*
G36*
G01X625406Y1217322D02*
G02I-800J0D01*
G37*
G36*
G01X629146Y1213582D02*
G02I-800J0D01*
G37*
G36*
G01X632886D02*
G02I-800J0D01*
G37*
G36*
G01X625406Y1209842D02*
G02I-800J0D01*
G37*
G36*
G01X629146Y1224803D02*
G02I-800J0D01*
G37*
G36*
G01Y1228543D02*
G02I-800J0D01*
G37*
G36*
G01X636627D02*
G02I-800J0D01*
G37*
G36*
G01X632886Y1232283D02*
G02I-800J0D01*
G37*
G36*
G01Y1236023D02*
G02I-800J0D01*
G37*
G36*
G01X625406Y1232283D02*
G02I-800J0D01*
G37*
G36*
G01Y1236023D02*
G02I-800J0D01*
G37*
G36*
G01X636627Y1224803D02*
G02I-800J0D01*
G37*
G36*
G01X625406Y1250984D02*
G02I-800J0D01*
G37*
G36*
G01X636627Y1243503D02*
G02I-800J0D01*
G37*
G36*
G01X632886Y1250984D02*
G02I-800J0D01*
G37*
G36*
G01X636627Y1247243D02*
G02I-800J0D01*
G37*
G36*
G01X629146Y1243503D02*
G02I-800J0D01*
G37*
G36*
G01Y1247243D02*
G02I-800J0D01*
G37*
G36*
G01X625406Y1254724D02*
G02I-800J0D01*
G37*
G36*
G01X632886D02*
G02I-800J0D01*
G37*
G36*
G01X640367Y1075196D02*
G02I-800J0D01*
G37*
G36*
G01X647847D02*
G02I-800J0D01*
G37*
G36*
G01X644107Y1086417D02*
G02I-800J0D01*
G37*
G36*
G01Y1082677D02*
G02I-800J0D01*
G37*
G36*
G01X647847Y1078936D02*
G02I-800J0D01*
G37*
G36*
G01X640367D02*
G02I-800J0D01*
G37*
G36*
G01X651587Y1082677D02*
G02I-800J0D01*
G37*
G36*
G01Y1086417D02*
G02I-800J0D01*
G37*
G36*
G01Y1105117D02*
G02I-800J0D01*
G37*
G36*
G01X647847Y1093897D02*
G02I-800J0D01*
G37*
G36*
G01X640367Y1097637D02*
G02I-800J0D01*
G37*
G36*
G01X644107Y1105117D02*
G02I-800J0D01*
G37*
G36*
G01X647847Y1097637D02*
G02I-800J0D01*
G37*
G36*
G01X640367Y1093897D02*
G02I-800J0D01*
G37*
G36*
G01X644107Y1101376D02*
G02I-800J0D01*
G37*
G36*
G01X651587D02*
G02I-800J0D01*
G37*
G36*
G01X640367Y1236023D02*
G02I-800J0D01*
G37*
G36*
G01X647847D02*
G02I-800J0D01*
G37*
G36*
G01X640367Y1232283D02*
G02I-800J0D01*
G37*
G36*
G01X644107Y1224803D02*
G02I-800J0D01*
G37*
G36*
G01X647847Y1232283D02*
G02I-800J0D01*
G37*
G36*
G01X644107Y1228543D02*
G02I-800J0D01*
G37*
G36*
G01X651587D02*
G02I-800J0D01*
G37*
G36*
G01Y1224803D02*
G02I-800J0D01*
G37*
G36*
G01X640367Y1250984D02*
G02I-800J0D01*
G37*
G36*
G01X651587Y1247243D02*
G02I-800J0D01*
G37*
G36*
G01Y1243503D02*
G02I-800J0D01*
G37*
G36*
G01X647847Y1250984D02*
G02I-800J0D01*
G37*
G36*
G01X644107Y1247243D02*
G02I-800J0D01*
G37*
G36*
G01Y1243503D02*
G02I-800J0D01*
G37*
G36*
G01X640367Y1254724D02*
G02I-800J0D01*
G37*
G36*
G01X647847D02*
G02I-800J0D01*
G37*
G36*
G01X662808Y1075196D02*
G02I-800J0D01*
G37*
G36*
G01X655327D02*
G02I-800J0D01*
G37*
G36*
G01X670288D02*
G02I-800J0D01*
G37*
G36*
G01X662808Y1078936D02*
G02I-800J0D01*
G37*
G36*
G01X666548Y1082677D02*
G02I-800J0D01*
G37*
G36*
G01X659068D02*
G02I-800J0D01*
G37*
G36*
G01X655327Y1078936D02*
G02I-800J0D01*
G37*
G36*
G01X666548Y1086417D02*
G02I-800J0D01*
G37*
G36*
G01X659068D02*
G02I-800J0D01*
G37*
G36*
G01X670288Y1078936D02*
G02I-800J0D01*
G37*
G36*
G01X662808Y1097637D02*
G02I-800J0D01*
G37*
G36*
G01X655327Y1093897D02*
G02I-800J0D01*
G37*
G36*
G01X670288D02*
G02I-800J0D01*
G37*
G36*
G01X666548Y1105117D02*
G02I-800J0D01*
G37*
G36*
G01X655327Y1097637D02*
G02I-800J0D01*
G37*
G36*
G01X662808Y1093897D02*
G02I-800J0D01*
G37*
G36*
G01X670288Y1097637D02*
G02I-800J0D01*
G37*
G36*
G01X666548Y1101376D02*
G02I-800J0D01*
G37*
G36*
G01X659068Y1105117D02*
G02I-800J0D01*
G37*
G36*
G01Y1101376D02*
G02I-800J0D01*
G37*
G36*
G01X670288Y1232283D02*
G02I-800J0D01*
G37*
G36*
G01X655327Y1236023D02*
G02I-800J0D01*
G37*
G36*
G01X662808Y1232283D02*
G02I-800J0D01*
G37*
G36*
G01X666548Y1224803D02*
G02I-800J0D01*
G37*
G36*
G01X662808Y1236023D02*
G02I-800J0D01*
G37*
G36*
G01X659068Y1224803D02*
G02I-800J0D01*
G37*
G36*
G01X666548Y1228543D02*
G02I-800J0D01*
G37*
G36*
G01X659068D02*
G02I-800J0D01*
G37*
G36*
G01X670288Y1236023D02*
G02I-800J0D01*
G37*
G36*
G01X655327Y1232283D02*
G02I-800J0D01*
G37*
G36*
G01X666548Y1247243D02*
G02I-800J0D01*
G37*
G36*
G01X670288Y1250984D02*
G02I-800J0D01*
G37*
G36*
G01X659068Y1247243D02*
G02I-800J0D01*
G37*
G36*
G01X662808Y1250984D02*
G02I-800J0D01*
G37*
G36*
G01X666548Y1243503D02*
G02I-800J0D01*
G37*
G36*
G01X659068D02*
G02I-800J0D01*
G37*
G36*
G01X655327Y1250984D02*
G02I-800J0D01*
G37*
G36*
G01X662808Y1254724D02*
G02I-800J0D01*
G37*
G36*
G01X670288D02*
G02I-800J0D01*
G37*
G36*
G01X655327D02*
G02I-800J0D01*
G37*
G36*
G01X677768Y1075196D02*
G02I-800J0D01*
G37*
G36*
G01X685249D02*
G02I-800J0D01*
G37*
G36*
G01X677768Y1078936D02*
G02I-800J0D01*
G37*
G36*
G01X681509Y1086417D02*
G02I-800J0D01*
G37*
G36*
G01X685249Y1078936D02*
G02I-800J0D01*
G37*
G36*
G01X674028Y1086417D02*
G02I-800J0D01*
G37*
G36*
G01Y1082677D02*
G02I-800J0D01*
G37*
G36*
G01X681509D02*
G02I-800J0D01*
G37*
G36*
G01X674028Y1105117D02*
G02I-800J0D01*
G37*
G36*
G01X685249Y1093897D02*
G02I-800J0D01*
G37*
G36*
G01X677768D02*
G02I-800J0D01*
G37*
G36*
G01X685249Y1097637D02*
G02I-800J0D01*
G37*
G36*
G01X677768D02*
G02I-800J0D01*
G37*
G36*
G01X681508Y1105117D02*
G02I-800J0D01*
G37*
G36*
G01X674028Y1101376D02*
G02I-800J0D01*
G37*
G36*
G01X681508D02*
G02I-800J0D01*
G37*
G36*
G01X677768Y1236023D02*
G02I-800J0D01*
G37*
G36*
G01X685249Y1232283D02*
G02I-800J0D01*
G37*
G36*
G01X674028Y1228543D02*
G02I-800J0D01*
G37*
G36*
G01X681509Y1224803D02*
G02I-800J0D01*
G37*
G36*
G01X685249Y1236023D02*
G02I-800J0D01*
G37*
G36*
G01X677768Y1232283D02*
G02I-800J0D01*
G37*
G36*
G01X674028Y1224803D02*
G02I-800J0D01*
G37*
G36*
G01X681509Y1228543D02*
G02I-800J0D01*
G37*
G36*
G01X674028Y1243503D02*
G02I-800J0D01*
G37*
G36*
G01X681509Y1247243D02*
G02I-800J0D01*
G37*
G36*
G01X674028D02*
G02I-800J0D01*
G37*
G36*
G01X685249Y1250984D02*
G02I-800J0D01*
G37*
G36*
G01X677768D02*
G02I-800J0D01*
G37*
G36*
G01X681509Y1243503D02*
G02I-800J0D01*
G37*
G36*
G01X685249Y1254724D02*
G02I-800J0D01*
G37*
G36*
G01X677768D02*
G02I-800J0D01*
G37*
G36*
G01X700208Y1075196D02*
G02I-800J0D01*
G37*
G36*
G01X692728Y1075195D02*
G02I-800J0D01*
G37*
G36*
G01X688989Y1086417D02*
G02I-800J0D01*
G37*
G36*
G01Y1082677D02*
G02I-800J0D01*
G37*
G36*
G01X692728Y1078935D02*
G02I-800J0D01*
G37*
G36*
G01X700208Y1078936D02*
G02I-800J0D01*
G37*
G36*
G01X696468Y1086416D02*
G02I-800J0D01*
G37*
G36*
G01Y1082676D02*
G02I-800J0D01*
G37*
G36*
G01X688989Y1105117D02*
G02I-800J0D01*
G37*
G36*
G01X696469Y1101376D02*
G02I-800J0D01*
G37*
G36*
G01X700208Y1097637D02*
G02I-800J0D01*
G37*
G36*
G01X696469Y1105117D02*
G02I-800J0D01*
G37*
G36*
G01X692728Y1093897D02*
G02I-800J0D01*
G37*
G36*
G01Y1097637D02*
G02I-800J0D01*
G37*
G36*
G01X700208Y1093897D02*
G02I-800J0D01*
G37*
G36*
G01X688989Y1101376D02*
G02I-800J0D01*
G37*
G36*
G01Y1228543D02*
G02I-800J0D01*
G37*
G36*
G01X692729Y1236023D02*
G02I-800J0D01*
G37*
G36*
G01X700209Y1232283D02*
G02I-800J0D01*
G37*
G36*
G01X688989Y1224803D02*
G02I-800J0D01*
G37*
G36*
G01X700209Y1236023D02*
G02I-800J0D01*
G37*
G36*
G01X692729Y1232283D02*
G02I-800J0D01*
G37*
G36*
G01X696469Y1228543D02*
G02I-800J0D01*
G37*
G36*
G01Y1224803D02*
G02I-800J0D01*
G37*
G36*
G01X692729Y1250984D02*
G02I-800J0D01*
G37*
G36*
G01X688989Y1247243D02*
G02I-800J0D01*
G37*
G36*
G01Y1243503D02*
G02I-800J0D01*
G37*
G36*
G01X696469Y1247243D02*
G02I-800J0D01*
G37*
G36*
G01X700209Y1250984D02*
G02I-800J0D01*
G37*
G36*
G01X696469Y1243503D02*
G02I-800J0D01*
G37*
G36*
G01X700209Y1254724D02*
G02I-800J0D01*
G37*
G36*
G01X692729D02*
G02I-800J0D01*
G37*
G36*
G01X707689Y1075196D02*
G02I-800J0D01*
G37*
G36*
G01X715169D02*
G02I-800J0D01*
G37*
G36*
G01X707689Y1078936D02*
G02I-800J0D01*
G37*
G36*
G01X718909Y1086417D02*
G02I-800J0D01*
G37*
G36*
G01X715169Y1078936D02*
G02I-800J0D01*
G37*
G36*
G01X703948Y1082677D02*
G02I-800J0D01*
G37*
G36*
G01X711429Y1086416D02*
G02I-800J0D01*
G37*
G36*
G01X703948Y1086417D02*
G02I-800J0D01*
G37*
G36*
G01X718909Y1082677D02*
G02I-800J0D01*
G37*
G36*
G01X711429Y1082676D02*
G02I-800J0D01*
G37*
G36*
G01X715169Y1097637D02*
G02I-800J0D01*
G37*
G36*
G01X707689Y1093897D02*
G02I-800J0D01*
G37*
G36*
G01X703949Y1105117D02*
G02I-800J0D01*
G37*
G36*
G01X718910D02*
G02I-800J0D01*
G37*
G36*
G01Y1101376D02*
G02I-800J0D01*
G37*
G36*
G01X711430Y1105117D02*
G02I-800J0D01*
G37*
G36*
G01X715169Y1093897D02*
G02I-800J0D01*
G37*
G36*
G01X707689Y1097637D02*
G02I-800J0D01*
G37*
G36*
G01X703949Y1101376D02*
G02I-800J0D01*
G37*
G36*
G01X711430D02*
G02I-800J0D01*
G37*
G36*
G01X707690Y1236023D02*
G02I-800J0D01*
G37*
G36*
G01X718910Y1228543D02*
G02I-800J0D01*
G37*
G36*
G01X715170Y1236023D02*
G02I-800J0D01*
G37*
G36*
G01X711430Y1228543D02*
G02I-800J0D01*
G37*
G36*
G01X703949D02*
G02I-800J0D01*
G37*
G36*
G01X715170Y1232283D02*
G02I-800J0D01*
G37*
G36*
G01X703949Y1224803D02*
G02I-800J0D01*
G37*
G36*
G01X718910D02*
G02I-800J0D01*
G37*
G36*
G01X711430D02*
G02I-800J0D01*
G37*
G36*
G01X707690Y1232283D02*
G02I-800J0D01*
G37*
G36*
G01X718910Y1243503D02*
G02I-800J0D01*
G37*
G36*
G01Y1247243D02*
G02I-800J0D01*
G37*
G36*
G01X707690Y1250984D02*
G02I-800J0D01*
G37*
G36*
G01X703949Y1243503D02*
G02I-800J0D01*
G37*
G36*
G01X715170Y1250984D02*
G02I-800J0D01*
G37*
G36*
G01X711430Y1247243D02*
G02I-800J0D01*
G37*
G36*
G01Y1243503D02*
G02I-800J0D01*
G37*
G36*
G01X703949Y1247243D02*
G02I-800J0D01*
G37*
G36*
G01X715170Y1254724D02*
G02I-800J0D01*
G37*
G36*
G01X707690D02*
G02I-800J0D01*
G37*
G36*
G01X722649Y1075196D02*
G02I-800J0D01*
G37*
G36*
G01X730130D02*
G02I-800J0D01*
G37*
G36*
G01X726389Y1086416D02*
G02I-800J0D01*
G37*
G36*
G01X733869Y1086417D02*
G02I-800J0D01*
G37*
G36*
G01X722649Y1078936D02*
G02I-800J0D01*
G37*
G36*
G01X730130D02*
G02I-800J0D01*
G37*
G36*
G01X733869Y1082677D02*
G02I-800J0D01*
G37*
G36*
G01X726389Y1082676D02*
G02I-800J0D01*
G37*
G36*
G01X726390Y1101376D02*
G02I-800J0D01*
G37*
G36*
G01X733871Y1105117D02*
G02I-800J0D01*
G37*
G36*
G01X726390D02*
G02I-800J0D01*
G37*
G36*
G01X722649Y1097637D02*
G02I-800J0D01*
G37*
G36*
G01Y1093897D02*
G02I-800J0D01*
G37*
G36*
G01X730130Y1097637D02*
G02I-800J0D01*
G37*
G36*
G01X733871Y1101376D02*
G02I-800J0D01*
G37*
G36*
G01X730130Y1093897D02*
G02I-800J0D01*
G37*
G36*
G01X726390Y1228543D02*
G02I-800J0D01*
G37*
G36*
G01X733871D02*
G02I-800J0D01*
G37*
G36*
G01X722650Y1236023D02*
G02I-800J0D01*
G37*
G36*
G01X733871Y1224803D02*
G02I-800J0D01*
G37*
G36*
G01X722650Y1232283D02*
G02I-800J0D01*
G37*
G36*
G01X726390Y1224803D02*
G02I-800J0D01*
G37*
G36*
G01X730131Y1236023D02*
G02I-800J0D01*
G37*
G36*
G01Y1232283D02*
G02I-800J0D01*
G37*
G36*
G01Y1250984D02*
G02I-800J0D01*
G37*
G36*
G01X733871Y1247243D02*
G02I-800J0D01*
G37*
G36*
G01X722650Y1250984D02*
G02I-800J0D01*
G37*
G36*
G01X726390Y1243503D02*
G02I-800J0D01*
G37*
G36*
G01X733871D02*
G02I-800J0D01*
G37*
G36*
G01X726390Y1247243D02*
G02I-800J0D01*
G37*
G36*
G01X722650Y1254724D02*
G02I-800J0D01*
G37*
G36*
G01X730131D02*
G02I-800J0D01*
G37*
G36*
G01X737610Y1075196D02*
G02I-800J0D01*
G37*
G36*
G01X745090D02*
G02I-800J0D01*
G37*
G36*
G01Y1078936D02*
G02I-800J0D01*
G37*
G36*
G01X748830Y1086417D02*
G02I-800J0D01*
G37*
G36*
G01X741350Y1086416D02*
G02I-800J0D01*
G37*
G36*
G01Y1082676D02*
G02I-800J0D01*
G37*
G36*
G01X737610Y1078936D02*
G02I-800J0D01*
G37*
G36*
G01X748830Y1082677D02*
G02I-800J0D01*
G37*
G36*
G01X737610Y1097637D02*
G02I-800J0D01*
G37*
G36*
G01X748831Y1105117D02*
G02I-800J0D01*
G37*
G36*
G01X745090Y1093897D02*
G02I-800J0D01*
G37*
G36*
G01X741351Y1105117D02*
G02I-800J0D01*
G37*
G36*
G01X745090Y1097637D02*
G02I-800J0D01*
G37*
G36*
G01X737610Y1093897D02*
G02I-800J0D01*
G37*
G36*
G01X741351Y1101376D02*
G02I-800J0D01*
G37*
G36*
G01X748831D02*
G02I-800J0D01*
G37*
G36*
G01X745091Y1236023D02*
G02I-800J0D01*
G37*
G36*
G01X737611Y1232283D02*
G02I-800J0D01*
G37*
G36*
G01X745091D02*
G02I-800J0D01*
G37*
G36*
G01X737611Y1236023D02*
G02I-800J0D01*
G37*
G36*
G01X741351Y1224803D02*
G02I-800J0D01*
G37*
G36*
G01Y1228543D02*
G02I-800J0D01*
G37*
G36*
G01X748831Y1224803D02*
G02I-800J0D01*
G37*
G36*
G01Y1228543D02*
G02I-800J0D01*
G37*
G36*
G01X741351Y1243503D02*
G02I-800J0D01*
G37*
G36*
G01Y1247243D02*
G02I-800J0D01*
G37*
G36*
G01X745091Y1250984D02*
G02I-800J0D01*
G37*
G36*
G01X737611D02*
G02I-800J0D01*
G37*
G36*
G01X748831Y1247243D02*
G02I-800J0D01*
G37*
G36*
G01Y1243503D02*
G02I-800J0D01*
G37*
G36*
G01X745091Y1254724D02*
G02I-800J0D01*
G37*
G36*
G01X737611D02*
G02I-800J0D01*
G37*
G36*
G01X752571Y1075196D02*
G02I-800J0D01*
G37*
G36*
G01X767531D02*
G02I-800J0D01*
G37*
G36*
G01X760051D02*
G02I-800J0D01*
G37*
G36*
G01X763791Y1086417D02*
G02I-800J0D01*
G37*
G36*
G01X767531Y1078936D02*
G02I-800J0D01*
G37*
G36*
G01X756311Y1086416D02*
G02I-800J0D01*
G37*
G36*
G01X760051Y1078936D02*
G02I-800J0D01*
G37*
G36*
G01X756311Y1082676D02*
G02I-800J0D01*
G37*
G36*
G01X763791Y1082677D02*
G02I-800J0D01*
G37*
G36*
G01X752571Y1078936D02*
G02I-800J0D01*
G37*
G36*
G01Y1097637D02*
G02I-800J0D01*
G37*
G36*
G01X763792Y1101376D02*
G02I-800J0D01*
G37*
G36*
G01Y1105117D02*
G02I-800J0D01*
G37*
G36*
G01X756312D02*
G02I-800J0D01*
G37*
G36*
G01X760051Y1097637D02*
G02I-800J0D01*
G37*
G36*
G01Y1093897D02*
G02I-800J0D01*
G37*
G36*
G01X767531Y1097637D02*
G02I-800J0D01*
G37*
G36*
G01X756312Y1101376D02*
G02I-800J0D01*
G37*
G36*
G01X767531Y1093897D02*
G02I-800J0D01*
G37*
G36*
G01X752571D02*
G02I-800J0D01*
G37*
G36*
G01X756312Y1123818D02*
G02I-800J0D01*
G37*
G36*
G01X760052Y1112598D02*
G02I-800J0D01*
G37*
G36*
G01X752571Y1123818D02*
G02I-800J0D01*
G37*
G36*
G01X763792Y1112598D02*
G02I-800J0D01*
G37*
G36*
G01X756312Y1116338D02*
G02I-800J0D01*
G37*
G36*
G01X752571D02*
G02I-800J0D01*
G37*
G36*
G01X760052Y1120078D02*
G02I-800J0D01*
G37*
G36*
G01X763792D02*
G02I-800J0D01*
G37*
G36*
G01X752571Y1131299D02*
G02I-800J0D01*
G37*
G36*
G01X763792Y1135039D02*
G02I-800J0D01*
G37*
G36*
G01X756312Y1131299D02*
G02I-800J0D01*
G37*
G36*
G01X763792Y1127559D02*
G02I-800J0D01*
G37*
G36*
G01X760052Y1135039D02*
G02I-800J0D01*
G37*
G36*
G01Y1127559D02*
G02I-800J0D01*
G37*
G36*
G01X763792Y1202362D02*
G02I-800J0D01*
G37*
G36*
G01X756312Y1198621D02*
G02I-800J0D01*
G37*
G36*
G01X760052Y1202362D02*
G02I-800J0D01*
G37*
G36*
G01X752572Y1198621D02*
G02I-800J0D01*
G37*
G36*
G01X763792Y1217322D02*
G02I-800J0D01*
G37*
G36*
G01X752572Y1213582D02*
G02I-800J0D01*
G37*
G36*
G01X763792Y1209842D02*
G02I-800J0D01*
G37*
G36*
G01X756312Y1213582D02*
G02I-800J0D01*
G37*
G36*
G01X752572Y1206102D02*
G02I-800J0D01*
G37*
G36*
G01X760052Y1217322D02*
G02I-800J0D01*
G37*
G36*
G01Y1209842D02*
G02I-800J0D01*
G37*
G36*
G01X756312Y1206102D02*
G02I-800J0D01*
G37*
G36*
G01Y1228543D02*
G02I-800J0D01*
G37*
G36*
G01X752572Y1236023D02*
G02I-800J0D01*
G37*
G36*
G01X763792Y1228543D02*
G02I-800J0D01*
G37*
G36*
G01X752572Y1232283D02*
G02I-800J0D01*
G37*
G36*
G01X767532D02*
G02I-800J0D01*
G37*
G36*
G01Y1236023D02*
G02I-800J0D01*
G37*
G36*
G01X760052Y1232283D02*
G02I-800J0D01*
G37*
G36*
G01X763792Y1224803D02*
G02I-800J0D01*
G37*
G36*
G01X760052Y1236023D02*
G02I-800J0D01*
G37*
G36*
G01X756312Y1224803D02*
G02I-800J0D01*
G37*
G36*
G01X767532Y1250984D02*
G02I-800J0D01*
G37*
G36*
G01X756312Y1243503D02*
G02I-800J0D01*
G37*
G36*
G01X763792D02*
G02I-800J0D01*
G37*
G36*
G01Y1247243D02*
G02I-800J0D01*
G37*
G36*
G01X752572Y1250984D02*
G02I-800J0D01*
G37*
G36*
G01X760052D02*
G02I-800J0D01*
G37*
G36*
G01X756312Y1247243D02*
G02I-800J0D01*
G37*
G36*
G01X752572Y1254724D02*
G02I-800J0D01*
G37*
G36*
G01X760052D02*
G02I-800J0D01*
G37*
G36*
G01X767532D02*
G02I-800J0D01*
G37*
G36*
G01X775011Y1075196D02*
G02I-800J0D01*
G37*
G36*
G01X782493Y1090157D02*
G02I-800J0D01*
G37*
G36*
G01X778753D02*
G02I-800J0D01*
G37*
G36*
G01X782493Y1082676D02*
G02I-800J0D01*
G37*
G36*
G01X775011Y1078936D02*
G02I-800J0D01*
G37*
G36*
G01X771271Y1086417D02*
G02I-800J0D01*
G37*
G36*
G01Y1082677D02*
G02I-800J0D01*
G37*
G36*
G01X778753Y1082676D02*
G02I-800J0D01*
G37*
G36*
G01X771272Y1101377D02*
G02I-800J0D01*
G37*
G36*
G01X782493D02*
G02I-800J0D01*
G37*
G36*
G01X778753D02*
G02I-800J0D01*
G37*
G36*
G01X775012Y1097637D02*
G02I-800J0D01*
G37*
G36*
G01X771272Y1105117D02*
G02I-800J0D01*
G37*
G36*
G01X775012Y1093897D02*
G02I-800J0D01*
G37*
G36*
G01Y1112598D02*
G02I-800J0D01*
G37*
G36*
G01X771272D02*
G02I-800J0D01*
G37*
G36*
G01X782493Y1123818D02*
G02I-800J0D01*
G37*
G36*
G01X778753D02*
G02I-800J0D01*
G37*
G36*
G01X782493Y1116338D02*
G02I-800J0D01*
G37*
G36*
G01X778753Y1108858D02*
G02I-800J0D01*
G37*
G36*
G01X771272Y1120078D02*
G02I-800J0D01*
G37*
G36*
G01X782493Y1108858D02*
G02I-800J0D01*
G37*
G36*
G01X778753Y1116338D02*
G02I-800J0D01*
G37*
G36*
G01X775012Y1120078D02*
G02I-800J0D01*
G37*
G36*
G01X771272Y1127558D02*
G02I-800J0D01*
G37*
G36*
G01Y1135039D02*
G02I-800J0D01*
G37*
G36*
G01X782493Y1131299D02*
G02I-800J0D01*
G37*
G36*
G01X775012Y1127558D02*
G02I-800J0D01*
G37*
G36*
G01Y1135039D02*
G02I-800J0D01*
G37*
G36*
G01X778753Y1131299D02*
G02I-800J0D01*
G37*
G36*
G01X782493Y1198621D02*
G02I-800J0D01*
G37*
G36*
G01X775012Y1202362D02*
G02I-800J0D01*
G37*
G36*
G01X771272D02*
G02I-800J0D01*
G37*
G36*
G01X778753Y1198621D02*
G02I-800J0D01*
G37*
G36*
G01Y1206102D02*
G02I-800J0D01*
G37*
G36*
G01X771272Y1209842D02*
G02I-800J0D01*
G37*
G36*
G01X782493Y1213582D02*
G02I-800J0D01*
G37*
G36*
G01X775012Y1209842D02*
G02I-800J0D01*
G37*
G36*
G01X778753Y1221062D02*
G02I-800J0D01*
G37*
G36*
G01X782493D02*
G02I-800J0D01*
G37*
G36*
G01Y1206102D02*
G02I-800J0D01*
G37*
G36*
G01X771272Y1217322D02*
G02I-800J0D01*
G37*
G36*
G01X775012D02*
G02I-800J0D01*
G37*
G36*
G01X778753Y1213582D02*
G02I-800J0D01*
G37*
G36*
G01X771272Y1228543D02*
G02I-800J0D01*
G37*
G36*
G01X782493D02*
G02I-800J0D01*
G37*
G36*
G01X771272Y1224803D02*
G02I-800J0D01*
G37*
G36*
G01X778753Y1228543D02*
G02I-800J0D01*
G37*
G36*
G01X775012Y1232283D02*
G02I-800J0D01*
G37*
G36*
G01Y1236023D02*
G02I-800J0D01*
G37*
G36*
G01X778753Y1239763D02*
G02I-800J0D01*
G37*
G36*
G01X782493D02*
G02I-800J0D01*
G37*
G36*
G01X778753Y1247243D02*
G02I-800J0D01*
G37*
G36*
G01X771272Y1243503D02*
G02I-800J0D01*
G37*
G36*
G01X782493Y1247243D02*
G02I-800J0D01*
G37*
G36*
G01X771272D02*
G02I-800J0D01*
G37*
G36*
G01X775012Y1250984D02*
G02I-800J0D01*
G37*
G36*
G01Y1254724D02*
G02I-800J0D01*
G37*
G36*
G01X940026Y1577634D02*
G03X940910Y1577268I884J885D01*
G01X956342D01*
G02X956484Y1577209I0J-200D01*
G01X959830Y1573863D01*
G02X959889Y1573721I-141J-142D01*
G01Y1543680D01*
G03X960255Y1542796I1251J0D01*
G01X964295Y1538756D01*
G03X965179Y1538390I884J885D01*
G01X1019906D01*
G02X1020048Y1538331I0J-200D01*
G01X1031515Y1526864D01*
G02X1031574Y1526722I-141J-142D01*
G01Y1492904D01*
G02X1031515Y1492762I-200J0D01*
G01X1031368Y1492615D01*
G02X1031226Y1492556I-142J141D01*
G01X947183D01*
G02X947041Y1492615I0J200D01*
G01X944876Y1494780D01*
G03X943992Y1495146I-884J-885D01*
G01X933579D01*
G03X932695Y1494780I0J-1251D01*
G01X917141Y1479226D01*
G03X916775Y1478342I885J-884D01*
G01Y1465020D01*
G02X916716Y1464878I-200J0D01*
G01X914188Y1462350D01*
G03X913822Y1461466I885J-884D01*
G01Y1460928D01*
G02X913763Y1460786I-200J0D01*
G01X913527Y1460550D01*
G03X913161Y1459666I885J-884D01*
G01Y1446448D01*
G02X913102Y1446306I-200J0D01*
G01X912955Y1446159D01*
G02X912813Y1446100I-142J141D01*
G01X900559D01*
G02X900417Y1446159I0J200D01*
G01X900270Y1446306D01*
G02X900211Y1446448I141J142D01*
G01Y1459640D01*
G03X899845Y1460524I-1251J0D01*
G01X899532Y1460837D01*
G02X899473Y1460979I141J142D01*
G01Y1462024D01*
G03X899107Y1462908I-1251J0D01*
G01X894403Y1467612D01*
G02X894344Y1467754I141J142D01*
G01Y1473096D01*
G03X893978Y1473980I-1251J0D01*
G01X888953Y1479005D01*
G03X888069Y1479371I-884J-885D01*
G01X880504D01*
G03X879620Y1479005I0J-1251D01*
G01X872265Y1471650D01*
G03X871899Y1470766I885J-884D01*
G01Y1460991D01*
G02X871840Y1460849I-200J0D01*
G01X871502Y1460511D01*
G03X871136Y1459627I885J-884D01*
G01Y1446423D01*
G02X871077Y1446281I-200J0D01*
G01X870968Y1446172D01*
G02X870826Y1446113I-142J141D01*
G01X858702D01*
G02X858560Y1446172I0J200D01*
G01X858139Y1446593D01*
G02X858080Y1446735I141J142D01*
G01Y1459524D01*
G03X857714Y1460408I-1251J0D01*
G01X853660Y1464462D01*
G03X852776Y1464828I-884J-885D01*
G01X828441D01*
G03X827557Y1464462I0J-1251D01*
G01X827039Y1463944D01*
G03X826673Y1463060I885J-884D01*
G01Y1461847D01*
G02X826614Y1461705I-200J0D01*
G01X826571Y1461662D01*
G02X826429Y1461603I-142J141D01*
G01X825036D01*
G03X824152Y1461237I0J-1251D01*
G01X821533Y1458618D01*
G02X821391Y1458559I-142J141D01*
G01X820451D01*
G03X819567Y1458193I0J-1251D01*
G01X819360Y1457986D01*
G03X818994Y1457102I885J-884D01*
G01Y1446462D01*
G02X818935Y1446320I-200J0D01*
G01X818826Y1446211D01*
G02X818684Y1446152I-142J141D01*
G01X806393D01*
G02X806251Y1446211I0J200D01*
G01X806063Y1446399D01*
G02X806004Y1446541I141J142D01*
G01Y1459828D01*
G02X806063Y1459970I200J0D01*
G01X806195Y1460102D01*
G03X806561Y1460986I-885J884D01*
G01Y1474310D01*
G02X806615Y1474447I200J0D01*
G03X806950Y1475299I-916J852D01*
G01Y1523715D01*
G02X807009Y1523857I200J0D01*
G01X816830Y1533678D01*
G03X817196Y1534562I-885J884D01*
G01Y1620853D01*
G02X817255Y1620995I200J0D01*
G01X822528Y1626268D01*
G02X822670Y1626327I142J-141D01*
G01X927565D01*
G02X927707Y1626268I0J-200D01*
G01X932114Y1621861D01*
G02X932173Y1621719I-141J-142D01*
G01Y1586005D01*
G03X932539Y1585121I1251J0D01*
G01X940026Y1577634D01*
G37*
G36*
G01X953110Y1480583D02*
G03X953130Y1480563I894J874D01*
G02X953192Y1480419I-138J-145D01*
G01Y1451442D01*
G02X953133Y1451300I-200J0D01*
G01X952668Y1450835D01*
G02X952526Y1450776I-142J141D01*
G01X930592D01*
G02X930450Y1450835I0J200D01*
G01X929621Y1451664D01*
G02X929562Y1451806I141J142D01*
G01Y1480891D01*
G02X929621Y1481033I200J0D01*
G01X930418Y1481830D01*
G02X930560Y1481889I142J-141D01*
G01X951737D01*
G02X951894Y1481812I-1J-200D01*
G03X951995Y1481698I984J770D01*
G01X953110Y1480583D01*
G37*
G36*
G01X955751Y1485453D02*
X957168Y1486870D01*
G02X957310Y1486929I142J-141D01*
G01X1045732D01*
G02X1045874Y1486870I0J-200D01*
G01X1046659Y1486085D01*
G02X1046718Y1485943I-141J-142D01*
G01Y1452303D01*
G02X1046659Y1452161I-200J0D01*
G01X1045333Y1450835D01*
G02X1045191Y1450776I-142J141D01*
G01X956304D01*
G02X956162Y1450835I0J200D01*
G01X955751Y1451246D01*
G02X955692Y1451388I141J142D01*
G01Y1485311D01*
G02X955751Y1485453I200J0D01*
G37*
G36*
G01X1060051Y1198621D02*
G02I-800J0D01*
G37*
G36*
G01Y1191141D02*
G02I-800J0D01*
G37*
G36*
G01Y1221062D02*
G02I-800J0D01*
G37*
G36*
G01Y1206102D02*
G02I-800J0D01*
G37*
G36*
G01Y1213582D02*
G02I-800J0D01*
G37*
G36*
G01Y1228543D02*
G02I-800J0D01*
G37*
G36*
G01Y1247243D02*
G02I-800J0D01*
G37*
G36*
G01Y1239763D02*
G02I-800J0D01*
G37*
G36*
G01X1071272Y1187401D02*
G02I-800J0D01*
G37*
G36*
G01X1067532D02*
G02I-800J0D01*
G37*
G36*
G01X1063791Y1198621D02*
G02I-800J0D01*
G37*
G36*
G01X1067532Y1194881D02*
G02I-800J0D01*
G37*
G36*
G01X1063791Y1191141D02*
G02I-800J0D01*
G37*
G36*
G01X1071272Y1194881D02*
G02I-800J0D01*
G37*
G36*
G01Y1202362D02*
G02I-800J0D01*
G37*
G36*
G01X1067532D02*
G02I-800J0D01*
G37*
G36*
G01X1071272Y1217322D02*
G02I-800J0D01*
G37*
G36*
G01X1067532D02*
G02I-800J0D01*
G37*
G36*
G01X1063791Y1221062D02*
G02I-800J0D01*
G37*
G36*
G01Y1206102D02*
G02I-800J0D01*
G37*
G36*
G01X1071272Y1209842D02*
G02I-800J0D01*
G37*
G36*
G01X1063791Y1213582D02*
G02I-800J0D01*
G37*
G36*
G01X1067532Y1209842D02*
G02I-800J0D01*
G37*
G36*
G01X1071272Y1228543D02*
G02I-800J0D01*
G37*
G36*
G01X1067532Y1236023D02*
G02I-800J0D01*
G37*
G36*
G01Y1232283D02*
G02I-800J0D01*
G37*
G36*
G01X1075012Y1236023D02*
G02I-800J0D01*
G37*
G36*
G01Y1232283D02*
G02I-800J0D01*
G37*
G36*
G01X1071272Y1224803D02*
G02I-800J0D01*
G37*
G36*
G01X1063791Y1228543D02*
G02I-800J0D01*
G37*
G36*
G01X1075012Y1250984D02*
G02I-800J0D01*
G37*
G36*
G01X1071272Y1247243D02*
G02I-800J0D01*
G37*
G36*
G01X1063791D02*
G02I-800J0D01*
G37*
G36*
G01X1071272Y1243503D02*
G02I-800J0D01*
G37*
G36*
G01X1063791Y1239763D02*
G02I-800J0D01*
G37*
G36*
G01X1067532Y1250984D02*
G02I-800J0D01*
G37*
G36*
G01Y1254724D02*
G02I-800J0D01*
G37*
G36*
G01X1075012D02*
G02I-800J0D01*
G37*
G36*
G01X1089972Y1075196D02*
G02I-800J0D01*
G37*
G36*
G01Y1078936D02*
G02I-800J0D01*
G37*
G36*
G01Y1097637D02*
G02I-800J0D01*
G37*
G36*
G01Y1093897D02*
G02I-800J0D01*
G37*
G36*
G01X1078752Y1187401D02*
G02I-800J0D01*
G37*
G36*
G01X1082492D02*
G02I-800J0D01*
G37*
G36*
G01X1078752Y1194881D02*
G02I-800J0D01*
G37*
G36*
G01Y1202362D02*
G02I-800J0D01*
G37*
G36*
G01X1089972Y1191141D02*
G02I-800J0D01*
G37*
G36*
G01Y1198621D02*
G02I-800J0D01*
G37*
G36*
G01X1082492Y1202362D02*
G02I-800J0D01*
G37*
G36*
G01X1086232Y1198621D02*
G02I-800J0D01*
G37*
G36*
G01X1082492Y1194881D02*
G02I-800J0D01*
G37*
G36*
G01X1086232Y1191141D02*
G02I-800J0D01*
G37*
G36*
G01X1089972Y1206102D02*
G02I-800J0D01*
G37*
G36*
G01X1078752Y1209842D02*
G02I-800J0D01*
G37*
G36*
G01X1082492D02*
G02I-800J0D01*
G37*
G36*
G01Y1217322D02*
G02I-800J0D01*
G37*
G36*
G01X1089972Y1213582D02*
G02I-800J0D01*
G37*
G36*
G01X1078752Y1217322D02*
G02I-800J0D01*
G37*
G36*
G01X1086232Y1206102D02*
G02I-800J0D01*
G37*
G36*
G01Y1213582D02*
G02I-800J0D01*
G37*
G36*
G01X1089972Y1232283D02*
G02I-800J0D01*
G37*
G36*
G01X1082492D02*
G02I-800J0D01*
G37*
G36*
G01Y1236023D02*
G02I-800J0D01*
G37*
G36*
G01X1089972D02*
G02I-800J0D01*
G37*
G36*
G01X1078752Y1224803D02*
G02I-800J0D01*
G37*
G36*
G01Y1228543D02*
G02I-800J0D01*
G37*
G36*
G01X1086232Y1224803D02*
G02I-800J0D01*
G37*
G36*
G01Y1228543D02*
G02I-800J0D01*
G37*
G36*
G01X1078752Y1243503D02*
G02I-800J0D01*
G37*
G36*
G01X1082492Y1250984D02*
G02I-800J0D01*
G37*
G36*
G01X1078752Y1247243D02*
G02I-800J0D01*
G37*
G36*
G01X1086232Y1243503D02*
G02I-800J0D01*
G37*
G36*
G01X1089972Y1250984D02*
G02I-800J0D01*
G37*
G36*
G01X1086232Y1247243D02*
G02I-800J0D01*
G37*
G36*
G01X1082492Y1254724D02*
G02I-800J0D01*
G37*
G36*
G01X1089972D02*
G02I-800J0D01*
G37*
G36*
G01X1097453Y1075196D02*
G02I-800J0D01*
G37*
G36*
G01X1104933D02*
G02I-800J0D01*
G37*
G36*
G01X1101193Y1082677D02*
G02I-800J0D01*
G37*
G36*
G01X1104933Y1078936D02*
G02I-800J0D01*
G37*
G36*
G01X1108673Y1082677D02*
G02I-800J0D01*
G37*
G36*
G01Y1086417D02*
G02I-800J0D01*
G37*
G36*
G01X1093713Y1082677D02*
G02I-800J0D01*
G37*
G36*
G01X1101193Y1086417D02*
G02I-800J0D01*
G37*
G36*
G01X1093713D02*
G02I-800J0D01*
G37*
G36*
G01X1097453Y1078936D02*
G02I-800J0D01*
G37*
G36*
G01X1093713Y1105116D02*
G02I-800J0D01*
G37*
G36*
G01X1104933Y1097637D02*
G02I-800J0D01*
G37*
G36*
G01X1097453D02*
G02I-800J0D01*
G37*
G36*
G01X1101193Y1105116D02*
G02I-800J0D01*
G37*
G36*
G01X1104933Y1093897D02*
G02I-800J0D01*
G37*
G36*
G01X1101193Y1101376D02*
G02I-800J0D01*
G37*
G36*
G01X1097453Y1093897D02*
G02I-800J0D01*
G37*
G36*
G01X1093713Y1101376D02*
G02I-800J0D01*
G37*
G36*
G01X1108673Y1105116D02*
G02I-800J0D01*
G37*
G36*
G01Y1101376D02*
G02I-800J0D01*
G37*
G36*
G01X1101193Y1228543D02*
G02I-800J0D01*
G37*
G36*
G01X1104933Y1236023D02*
G02I-800J0D01*
G37*
G36*
G01X1093713Y1224803D02*
G02I-800J0D01*
G37*
G36*
G01X1104933Y1232283D02*
G02I-800J0D01*
G37*
G36*
G01X1108673Y1224803D02*
G02I-800J0D01*
G37*
G36*
G01X1097453Y1236023D02*
G02I-800J0D01*
G37*
G36*
G01X1101193Y1224803D02*
G02I-800J0D01*
G37*
G36*
G01X1108673Y1228543D02*
G02I-800J0D01*
G37*
G36*
G01X1097453Y1232283D02*
G02I-800J0D01*
G37*
G36*
G01X1093713Y1228543D02*
G02I-800J0D01*
G37*
G36*
G01Y1247243D02*
G02I-800J0D01*
G37*
G36*
G01X1097453Y1250984D02*
G02I-800J0D01*
G37*
G36*
G01X1093713Y1243503D02*
G02I-800J0D01*
G37*
G36*
G01X1108673D02*
G02I-800J0D01*
G37*
G36*
G01X1101193D02*
G02I-800J0D01*
G37*
G36*
G01X1108673Y1247243D02*
G02I-800J0D01*
G37*
G36*
G01X1101193D02*
G02I-800J0D01*
G37*
G36*
G01X1104933Y1250984D02*
G02I-800J0D01*
G37*
G36*
G01X1097453Y1254724D02*
G02I-800J0D01*
G37*
G36*
G01X1104933D02*
G02I-800J0D01*
G37*
G36*
G01X1112413Y1075196D02*
G02I-800J0D01*
G37*
G36*
G01X1119894D02*
G02I-800J0D01*
G37*
G36*
G01X1123634Y1086417D02*
G02I-800J0D01*
G37*
G36*
G01X1119894Y1078936D02*
G02I-800J0D01*
G37*
G36*
G01X1116154Y1082677D02*
G02I-800J0D01*
G37*
G36*
G01X1112413Y1078936D02*
G02I-800J0D01*
G37*
G36*
G01X1116154Y1086417D02*
G02I-800J0D01*
G37*
G36*
G01X1123634Y1082677D02*
G02I-800J0D01*
G37*
G36*
G01X1119894Y1097637D02*
G02I-800J0D01*
G37*
G36*
G01X1116154Y1101376D02*
G02I-800J0D01*
G37*
G36*
G01X1112413Y1093897D02*
G02I-800J0D01*
G37*
G36*
G01Y1097637D02*
G02I-800J0D01*
G37*
G36*
G01X1123634Y1105116D02*
G02I-800J0D01*
G37*
G36*
G01X1119894Y1093897D02*
G02I-800J0D01*
G37*
G36*
G01X1123634Y1101376D02*
G02I-800J0D01*
G37*
G36*
G01X1116154Y1105116D02*
G02I-800J0D01*
G37*
G36*
G01X1123634Y1224803D02*
G02I-800J0D01*
G37*
G36*
G01X1119894Y1232283D02*
G02I-800J0D01*
G37*
G36*
G01X1116154Y1228543D02*
G02I-800J0D01*
G37*
G36*
G01X1112413Y1232283D02*
G02I-800J0D01*
G37*
G36*
G01X1119894Y1236023D02*
G02I-800J0D01*
G37*
G36*
G01X1116154Y1224803D02*
G02I-800J0D01*
G37*
G36*
G01X1112413Y1236023D02*
G02I-800J0D01*
G37*
G36*
G01X1123634Y1228543D02*
G02I-800J0D01*
G37*
G36*
G01Y1243503D02*
G02I-800J0D01*
G37*
G36*
G01X1119894Y1250984D02*
G02I-800J0D01*
G37*
G36*
G01X1123634Y1247243D02*
G02I-800J0D01*
G37*
G36*
G01X1116154Y1243503D02*
G02I-800J0D01*
G37*
G36*
G01Y1247243D02*
G02I-800J0D01*
G37*
G36*
G01X1112413Y1250984D02*
G02I-800J0D01*
G37*
G36*
G01Y1254724D02*
G02I-800J0D01*
G37*
G36*
G01X1119894D02*
G02I-800J0D01*
G37*
G36*
G01X1127374Y1075196D02*
G02I-800J0D01*
G37*
G36*
G01X1134854D02*
G02I-800J0D01*
G37*
G36*
G01Y1078936D02*
G02I-800J0D01*
G37*
G36*
G01X1127374D02*
G02I-800J0D01*
G37*
G36*
G01X1131114Y1086417D02*
G02I-800J0D01*
G37*
G36*
G01Y1082677D02*
G02I-800J0D01*
G37*
G36*
G01X1138595Y1086417D02*
G02I-800J0D01*
G37*
G36*
G01Y1082677D02*
G02I-800J0D01*
G37*
G36*
G01X1127374Y1093897D02*
G02I-800J0D01*
G37*
G36*
G01X1131114Y1105116D02*
G02I-800J0D01*
G37*
G36*
G01X1134854Y1093897D02*
G02I-800J0D01*
G37*
G36*
G01X1131114Y1101376D02*
G02I-800J0D01*
G37*
G36*
G01X1134854Y1097637D02*
G02I-800J0D01*
G37*
G36*
G01X1138594Y1105116D02*
G02I-800J0D01*
G37*
G36*
G01X1127374Y1097637D02*
G02I-800J0D01*
G37*
G36*
G01X1138594Y1101376D02*
G02I-800J0D01*
G37*
G36*
G01X1134854Y1236023D02*
G02I-800J0D01*
G37*
G36*
G01X1138595Y1228543D02*
G02I-800J0D01*
G37*
G36*
G01X1134854Y1232283D02*
G02I-800J0D01*
G37*
G36*
G01X1127374D02*
G02I-800J0D01*
G37*
G36*
G01Y1236023D02*
G02I-800J0D01*
G37*
G36*
G01X1138595Y1224803D02*
G02I-800J0D01*
G37*
G36*
G01X1131114Y1228543D02*
G02I-800J0D01*
G37*
G36*
G01Y1224803D02*
G02I-800J0D01*
G37*
G36*
G01X1138595Y1243503D02*
G02I-800J0D01*
G37*
G36*
G01X1131114Y1247243D02*
G02I-800J0D01*
G37*
G36*
G01X1127374Y1250984D02*
G02I-800J0D01*
G37*
G36*
G01X1138595Y1247243D02*
G02I-800J0D01*
G37*
G36*
G01X1131114Y1243503D02*
G02I-800J0D01*
G37*
G36*
G01X1134854Y1250984D02*
G02I-800J0D01*
G37*
G36*
G01X1127374Y1254724D02*
G02I-800J0D01*
G37*
G36*
G01X1134854D02*
G02I-800J0D01*
G37*
G36*
G01X1142335Y1075196D02*
G02I-800J0D01*
G37*
G36*
G01X1157294D02*
G02I-800J0D01*
G37*
G36*
G01X1149814Y1075195D02*
G02I-800J0D01*
G37*
G36*
G01X1146075Y1086417D02*
G02I-800J0D01*
G37*
G36*
G01Y1082677D02*
G02I-800J0D01*
G37*
G36*
G01X1142335Y1078936D02*
G02I-800J0D01*
G37*
G36*
G01X1149814Y1078935D02*
G02I-800J0D01*
G37*
G36*
G01X1157294Y1078936D02*
G02I-800J0D01*
G37*
G36*
G01X1153554Y1086416D02*
G02I-800J0D01*
G37*
G36*
G01Y1082676D02*
G02I-800J0D01*
G37*
G36*
G01X1146075Y1105116D02*
G02I-800J0D01*
G37*
G36*
G01X1142335Y1093897D02*
G02I-800J0D01*
G37*
G36*
G01X1146075Y1101376D02*
G02I-800J0D01*
G37*
G36*
G01X1142335Y1097637D02*
G02I-800J0D01*
G37*
G36*
G01X1149814D02*
G02I-800J0D01*
G37*
G36*
G01X1157294Y1093897D02*
G02I-800J0D01*
G37*
G36*
G01X1153555Y1101376D02*
G02I-800J0D01*
G37*
G36*
G01X1157294Y1097637D02*
G02I-800J0D01*
G37*
G36*
G01X1149814Y1093897D02*
G02I-800J0D01*
G37*
G36*
G01X1153555Y1105116D02*
G02I-800J0D01*
G37*
G36*
G01X1149815Y1236023D02*
G02I-800J0D01*
G37*
G36*
G01Y1232283D02*
G02I-800J0D01*
G37*
G36*
G01X1153555Y1228543D02*
G02I-800J0D01*
G37*
G36*
G01X1146075Y1224803D02*
G02I-800J0D01*
G37*
G36*
G01X1157295Y1232283D02*
G02I-800J0D01*
G37*
G36*
G01Y1236023D02*
G02I-800J0D01*
G37*
G36*
G01X1142335D02*
G02I-800J0D01*
G37*
G36*
G01X1146075Y1228543D02*
G02I-800J0D01*
G37*
G36*
G01X1153555Y1224803D02*
G02I-800J0D01*
G37*
G36*
G01X1142335Y1232283D02*
G02I-800J0D01*
G37*
G36*
G01Y1250984D02*
G02I-800J0D01*
G37*
G36*
G01X1146075Y1247243D02*
G02I-800J0D01*
G37*
G36*
G01X1153555Y1243503D02*
G02I-800J0D01*
G37*
G36*
G01X1146075D02*
G02I-800J0D01*
G37*
G36*
G01X1153555Y1247243D02*
G02I-800J0D01*
G37*
G36*
G01X1149815Y1250984D02*
G02I-800J0D01*
G37*
G36*
G01X1157295D02*
G02I-800J0D01*
G37*
G36*
G01X1142335Y1254724D02*
G02I-800J0D01*
G37*
G36*
G01X1149815D02*
G02I-800J0D01*
G37*
G36*
G01X1157295D02*
G02I-800J0D01*
G37*
G36*
G01X1164775Y1075196D02*
G02I-800J0D01*
G37*
G36*
G01X1172255D02*
G02I-800J0D01*
G37*
G36*
G01X1161034Y1086417D02*
G02I-800J0D01*
G37*
G36*
G01X1168515Y1086416D02*
G02I-800J0D01*
G37*
G36*
G01X1164775Y1078936D02*
G02I-800J0D01*
G37*
G36*
G01X1161034Y1082677D02*
G02I-800J0D01*
G37*
G36*
G01X1172255Y1078936D02*
G02I-800J0D01*
G37*
G36*
G01X1168515Y1082676D02*
G02I-800J0D01*
G37*
G36*
G01X1161035Y1105116D02*
G02I-800J0D01*
G37*
G36*
G01Y1101376D02*
G02I-800J0D01*
G37*
G36*
G01X1172255Y1093897D02*
G02I-800J0D01*
G37*
G36*
G01X1168516Y1105116D02*
G02I-800J0D01*
G37*
G36*
G01X1172255Y1097637D02*
G02I-800J0D01*
G37*
G36*
G01X1164775Y1093897D02*
G02I-800J0D01*
G37*
G36*
G01Y1097637D02*
G02I-800J0D01*
G37*
G36*
G01X1168516Y1101376D02*
G02I-800J0D01*
G37*
G36*
G01X1161035Y1224803D02*
G02I-800J0D01*
G37*
G36*
G01X1164776Y1232283D02*
G02I-800J0D01*
G37*
G36*
G01X1168516Y1224803D02*
G02I-800J0D01*
G37*
G36*
G01X1161035Y1228543D02*
G02I-800J0D01*
G37*
G36*
G01X1172256Y1232283D02*
G02I-800J0D01*
G37*
G36*
G01X1164776Y1236023D02*
G02I-800J0D01*
G37*
G36*
G01X1172256D02*
G02I-800J0D01*
G37*
G36*
G01X1168516Y1228543D02*
G02I-800J0D01*
G37*
G36*
G01X1172256Y1250984D02*
G02I-800J0D01*
G37*
G36*
G01X1168516Y1247243D02*
G02I-800J0D01*
G37*
G36*
G01X1164776Y1250984D02*
G02I-800J0D01*
G37*
G36*
G01X1161035Y1247243D02*
G02I-800J0D01*
G37*
G36*
G01Y1243503D02*
G02I-800J0D01*
G37*
G36*
G01X1168516D02*
G02I-800J0D01*
G37*
G36*
G01X1172256Y1254724D02*
G02I-800J0D01*
G37*
G36*
G01X1164776D02*
G02I-800J0D01*
G37*
G36*
G01X1179735Y1075196D02*
G02I-800J0D01*
G37*
G36*
G01X1187216D02*
G02I-800J0D01*
G37*
G36*
G01X1175995Y1086417D02*
G02I-800J0D01*
G37*
G36*
G01X1183475Y1086416D02*
G02I-800J0D01*
G37*
G36*
G01X1175995Y1082677D02*
G02I-800J0D01*
G37*
G36*
G01X1179735Y1078936D02*
G02I-800J0D01*
G37*
G36*
G01X1183475Y1082676D02*
G02I-800J0D01*
G37*
G36*
G01X1187216Y1078936D02*
G02I-800J0D01*
G37*
G36*
G01X1179735Y1097637D02*
G02I-800J0D01*
G37*
G36*
G01X1187216Y1093897D02*
G02I-800J0D01*
G37*
G36*
G01X1183476Y1105116D02*
G02I-800J0D01*
G37*
G36*
G01X1175996D02*
G02I-800J0D01*
G37*
G36*
G01X1179735Y1093897D02*
G02I-800J0D01*
G37*
G36*
G01X1183476Y1101376D02*
G02I-800J0D01*
G37*
G36*
G01X1175996D02*
G02I-800J0D01*
G37*
G36*
G01X1187216Y1097637D02*
G02I-800J0D01*
G37*
G36*
G01X1183476Y1228543D02*
G02I-800J0D01*
G37*
G36*
G01X1187217Y1236023D02*
G02I-800J0D01*
G37*
G36*
G01X1179736D02*
G02I-800J0D01*
G37*
G36*
G01X1187217Y1232283D02*
G02I-800J0D01*
G37*
G36*
G01X1175996Y1228543D02*
G02I-800J0D01*
G37*
G36*
G01X1179736Y1232283D02*
G02I-800J0D01*
G37*
G36*
G01X1183476Y1224803D02*
G02I-800J0D01*
G37*
G36*
G01X1175996D02*
G02I-800J0D01*
G37*
G36*
G01Y1243503D02*
G02I-800J0D01*
G37*
G36*
G01X1183476Y1247243D02*
G02I-800J0D01*
G37*
G36*
G01X1179736Y1250984D02*
G02I-800J0D01*
G37*
G36*
G01X1187217D02*
G02I-800J0D01*
G37*
G36*
G01X1183476Y1243503D02*
G02I-800J0D01*
G37*
G36*
G01X1175996Y1247243D02*
G02I-800J0D01*
G37*
G36*
G01X1179736Y1254724D02*
G02I-800J0D01*
G37*
G36*
G01X1187217D02*
G02I-800J0D01*
G37*
G36*
G01X1194696Y1075196D02*
G02I-800J0D01*
G37*
G36*
G01X1202176D02*
G02I-800J0D01*
G37*
G36*
G01X1190955Y1086417D02*
G02I-800J0D01*
G37*
G36*
G01X1205916Y1082677D02*
G02I-800J0D01*
G37*
G36*
G01X1190955D02*
G02I-800J0D01*
G37*
G36*
G01X1198436Y1082676D02*
G02I-800J0D01*
G37*
G36*
G01X1194696Y1078936D02*
G02I-800J0D01*
G37*
G36*
G01X1205916Y1086417D02*
G02I-800J0D01*
G37*
G36*
G01X1202176Y1078936D02*
G02I-800J0D01*
G37*
G36*
G01X1198436Y1086416D02*
G02I-800J0D01*
G37*
G36*
G01X1202176Y1093897D02*
G02I-800J0D01*
G37*
G36*
G01X1194696Y1097637D02*
G02I-800J0D01*
G37*
G36*
G01X1198437Y1105116D02*
G02I-800J0D01*
G37*
G36*
G01X1205917D02*
G02I-800J0D01*
G37*
G36*
G01X1198437Y1101376D02*
G02I-800J0D01*
G37*
G36*
G01X1205917D02*
G02I-800J0D01*
G37*
G36*
G01X1190957D02*
G02I-800J0D01*
G37*
G36*
G01X1194696Y1093897D02*
G02I-800J0D01*
G37*
G36*
G01X1202176Y1097637D02*
G02I-800J0D01*
G37*
G36*
G01X1190957Y1105116D02*
G02I-800J0D01*
G37*
G36*
G01X1198437Y1224803D02*
G02I-800J0D01*
G37*
G36*
G01X1194697Y1236023D02*
G02I-800J0D01*
G37*
G36*
G01X1190957Y1228543D02*
G02I-800J0D01*
G37*
G36*
G01X1202177Y1236023D02*
G02I-800J0D01*
G37*
G36*
G01X1190957Y1224803D02*
G02I-800J0D01*
G37*
G36*
G01X1194697Y1232283D02*
G02I-800J0D01*
G37*
G36*
G01X1198437Y1228543D02*
G02I-800J0D01*
G37*
G36*
G01X1202177Y1232283D02*
G02I-800J0D01*
G37*
G36*
G01X1205917Y1228543D02*
G02I-800J0D01*
G37*
G36*
G01Y1224803D02*
G02I-800J0D01*
G37*
G36*
G01X1190957Y1243503D02*
G02I-800J0D01*
G37*
G36*
G01X1202177Y1250984D02*
G02I-800J0D01*
G37*
G36*
G01X1198437Y1247243D02*
G02I-800J0D01*
G37*
G36*
G01X1194697Y1250984D02*
G02I-800J0D01*
G37*
G36*
G01X1198437Y1243503D02*
G02I-800J0D01*
G37*
G36*
G01X1190957Y1247243D02*
G02I-800J0D01*
G37*
G36*
G01X1205917Y1243503D02*
G02I-800J0D01*
G37*
G36*
G01Y1247243D02*
G02I-800J0D01*
G37*
G36*
G01X1202177Y1254724D02*
G02I-800J0D01*
G37*
G36*
G01X1194697D02*
G02I-800J0D01*
G37*
G36*
G01X1217137Y1075196D02*
G02I-800J0D01*
G37*
G36*
G01X1209657D02*
G02I-800J0D01*
G37*
G36*
G01X1213397Y1082676D02*
G02I-800J0D01*
G37*
G36*
G01Y1086416D02*
G02I-800J0D01*
G37*
G36*
G01X1220877Y1086417D02*
G02I-800J0D01*
G37*
G36*
G01X1209657Y1078936D02*
G02I-800J0D01*
G37*
G36*
G01X1217137D02*
G02I-800J0D01*
G37*
G36*
G01X1220877Y1082677D02*
G02I-800J0D01*
G37*
G36*
G01X1220878Y1105116D02*
G02I-800J0D01*
G37*
G36*
G01X1217137Y1093897D02*
G02I-800J0D01*
G37*
G36*
G01X1213398Y1101376D02*
G02I-800J0D01*
G37*
G36*
G01Y1105116D02*
G02I-800J0D01*
G37*
G36*
G01X1209657Y1093897D02*
G02I-800J0D01*
G37*
G36*
G01X1217137Y1097637D02*
G02I-800J0D01*
G37*
G36*
G01X1220878Y1101376D02*
G02I-800J0D01*
G37*
G36*
G01X1209657Y1097637D02*
G02I-800J0D01*
G37*
G36*
G01X1213398Y1123818D02*
G02I-800J0D01*
G37*
G36*
G01X1209658Y1116338D02*
G02I-800J0D01*
G37*
G36*
G01X1213398D02*
G02I-800J0D01*
G37*
G36*
G01X1217138Y1120078D02*
G02I-800J0D01*
G37*
G36*
G01Y1112598D02*
G02I-800J0D01*
G37*
G36*
G01X1209658Y1123818D02*
G02I-800J0D01*
G37*
G36*
G01X1220878Y1112598D02*
G02I-800J0D01*
G37*
G36*
G01Y1120078D02*
G02I-800J0D01*
G37*
G36*
G01X1217138Y1127559D02*
G02I-800J0D01*
G37*
G36*
G01Y1135039D02*
G02I-800J0D01*
G37*
G36*
G01X1213398Y1131299D02*
G02I-800J0D01*
G37*
G36*
G01X1209658D02*
G02I-800J0D01*
G37*
G36*
G01X1220878Y1135039D02*
G02I-800J0D01*
G37*
G36*
G01Y1127559D02*
G02I-800J0D01*
G37*
G36*
G01X1213398Y1198621D02*
G02I-800J0D01*
G37*
G36*
G01X1209658D02*
G02I-800J0D01*
G37*
G36*
G01X1217138Y1202362D02*
G02I-800J0D01*
G37*
G36*
G01X1220878D02*
G02I-800J0D01*
G37*
G36*
G01Y1217322D02*
G02I-800J0D01*
G37*
G36*
G01Y1209842D02*
G02I-800J0D01*
G37*
G36*
G01X1213398Y1206102D02*
G02I-800J0D01*
G37*
G36*
G01X1217138Y1217322D02*
G02I-800J0D01*
G37*
G36*
G01X1213398Y1213582D02*
G02I-800J0D01*
G37*
G36*
G01X1209658Y1206102D02*
G02I-800J0D01*
G37*
G36*
G01Y1213582D02*
G02I-800J0D01*
G37*
G36*
G01X1217138Y1209842D02*
G02I-800J0D01*
G37*
G36*
G01X1220878Y1224803D02*
G02I-800J0D01*
G37*
G36*
G01X1213398Y1228543D02*
G02I-800J0D01*
G37*
G36*
G01X1209658Y1232283D02*
G02I-800J0D01*
G37*
G36*
G01X1217138Y1236023D02*
G02I-800J0D01*
G37*
G36*
G01Y1232283D02*
G02I-800J0D01*
G37*
G36*
G01X1213398Y1224803D02*
G02I-800J0D01*
G37*
G36*
G01X1220878Y1228543D02*
G02I-800J0D01*
G37*
G36*
G01X1209658Y1236023D02*
G02I-800J0D01*
G37*
G36*
G01X1213398Y1243503D02*
G02I-800J0D01*
G37*
G36*
G01X1220878Y1247243D02*
G02I-800J0D01*
G37*
G36*
G01Y1243503D02*
G02I-800J0D01*
G37*
G36*
G01X1213398Y1247243D02*
G02I-800J0D01*
G37*
G36*
G01X1209658Y1250984D02*
G02I-800J0D01*
G37*
G36*
G01X1217138D02*
G02I-800J0D01*
G37*
G36*
G01X1209658Y1254724D02*
G02I-800J0D01*
G37*
G36*
G01X1217138D02*
G02I-800J0D01*
G37*
G36*
G01X1232097Y1075196D02*
G02I-800J0D01*
G37*
G36*
G01X1224617D02*
G02I-800J0D01*
G37*
G36*
G01X1235839Y1090157D02*
G02I-800J0D01*
G37*
G36*
G01X1232097Y1078936D02*
G02I-800J0D01*
G37*
G36*
G01X1235839Y1082676D02*
G02I-800J0D01*
G37*
G36*
G01X1228357Y1086417D02*
G02I-800J0D01*
G37*
G36*
G01X1224617Y1078936D02*
G02I-800J0D01*
G37*
G36*
G01X1228357Y1082677D02*
G02I-800J0D01*
G37*
G36*
G01X1228358Y1101377D02*
G02I-800J0D01*
G37*
G36*
G01X1232098Y1093897D02*
G02I-800J0D01*
G37*
G36*
G01X1235839Y1101377D02*
G02I-800J0D01*
G37*
G36*
G01X1228358Y1105117D02*
G02I-800J0D01*
G37*
G36*
G01X1224617Y1093897D02*
G02I-800J0D01*
G37*
G36*
G01Y1097637D02*
G02I-800J0D01*
G37*
G36*
G01X1232098D02*
G02I-800J0D01*
G37*
G36*
G01X1228358Y1112598D02*
G02I-800J0D01*
G37*
G36*
G01X1235839Y1123818D02*
G02I-800J0D01*
G37*
G36*
G01X1232098Y1120078D02*
G02I-800J0D01*
G37*
G36*
G01Y1112598D02*
G02I-800J0D01*
G37*
G36*
G01X1235839Y1108858D02*
G02I-800J0D01*
G37*
G36*
G01Y1116338D02*
G02I-800J0D01*
G37*
G36*
G01X1228358Y1120078D02*
G02I-800J0D01*
G37*
G36*
G01X1232098Y1135039D02*
G02I-800J0D01*
G37*
G36*
G01X1228358Y1127558D02*
G02I-800J0D01*
G37*
G36*
G01X1235839Y1131299D02*
G02I-800J0D01*
G37*
G36*
G01X1232098Y1127558D02*
G02I-800J0D01*
G37*
G36*
G01X1228358Y1135039D02*
G02I-800J0D01*
G37*
G36*
G01X1232098Y1202362D02*
G02I-800J0D01*
G37*
G36*
G01X1235839Y1198621D02*
G02I-800J0D01*
G37*
G36*
G01X1228358Y1202362D02*
G02I-800J0D01*
G37*
G36*
G01X1235839Y1213582D02*
G02I-800J0D01*
G37*
G36*
G01X1232098Y1209842D02*
G02I-800J0D01*
G37*
G36*
G01X1228358D02*
G02I-800J0D01*
G37*
G36*
G01X1235839Y1221062D02*
G02I-800J0D01*
G37*
G36*
G01X1232098Y1217322D02*
G02I-800J0D01*
G37*
G36*
G01X1235839Y1206102D02*
G02I-800J0D01*
G37*
G36*
G01X1228358Y1217322D02*
G02I-800J0D01*
G37*
G36*
G01X1232098Y1232283D02*
G02I-800J0D01*
G37*
G36*
G01X1228358Y1228543D02*
G02I-800J0D01*
G37*
G36*
G01Y1224803D02*
G02I-800J0D01*
G37*
G36*
G01X1224618Y1236023D02*
G02I-800J0D01*
G37*
G36*
G01X1232098D02*
G02I-800J0D01*
G37*
G36*
G01X1235839Y1228543D02*
G02I-800J0D01*
G37*
G36*
G01X1224618Y1232283D02*
G02I-800J0D01*
G37*
G36*
G01X1228358Y1247243D02*
G02I-800J0D01*
G37*
G36*
G01X1224618Y1250984D02*
G02I-800J0D01*
G37*
G36*
G01X1235839Y1239763D02*
G02I-800J0D01*
G37*
G36*
G01X1228358Y1243503D02*
G02I-800J0D01*
G37*
G36*
G01X1232098Y1250984D02*
G02I-800J0D01*
G37*
G36*
G01X1235839Y1247243D02*
G02I-800J0D01*
G37*
G36*
G01X1232098Y1254724D02*
G02I-800J0D01*
G37*
G36*
G01X1224618D02*
G02I-800J0D01*
G37*
G36*
G01X1239579Y1090157D02*
G02I-800J0D01*
G37*
G36*
G01Y1082676D02*
G02I-800J0D01*
G37*
G36*
G01Y1101377D02*
G02I-800J0D01*
G37*
G36*
G01Y1108858D02*
G02I-800J0D01*
G37*
G36*
G01Y1116338D02*
G02I-800J0D01*
G37*
G36*
G01Y1123818D02*
G02I-800J0D01*
G37*
G36*
G01Y1131299D02*
G02I-800J0D01*
G37*
G36*
G01Y1198621D02*
G02I-800J0D01*
G37*
G36*
G01Y1221062D02*
G02I-800J0D01*
G37*
G36*
G01Y1206102D02*
G02I-800J0D01*
G37*
G36*
G01Y1213582D02*
G02I-800J0D01*
G37*
G36*
G01Y1228543D02*
G02I-800J0D01*
G37*
G36*
G01Y1247243D02*
G02I-800J0D01*
G37*
G36*
G01Y1239763D02*
G02I-800J0D01*
G37*
G36*
G01X1524619Y1187401D02*
G02I-800J0D01*
G37*
G36*
G01X1528359D02*
G02I-800J0D01*
G37*
G36*
G01X1517138Y1198621D02*
G02I-800J0D01*
G37*
G36*
G01X1524619Y1194881D02*
G02I-800J0D01*
G37*
G36*
G01X1520878Y1198621D02*
G02I-800J0D01*
G37*
G36*
G01X1524619Y1202362D02*
G02I-800J0D01*
G37*
G36*
G01X1517138Y1191141D02*
G02I-800J0D01*
G37*
G36*
G01X1528359Y1202362D02*
G02I-800J0D01*
G37*
G36*
G01Y1194881D02*
G02I-800J0D01*
G37*
G36*
G01X1520878Y1191141D02*
G02I-800J0D01*
G37*
G36*
G01Y1221062D02*
G02I-800J0D01*
G37*
G36*
G01X1517138Y1213582D02*
G02I-800J0D01*
G37*
G36*
G01Y1206102D02*
G02I-800J0D01*
G37*
G36*
G01X1520878D02*
G02I-800J0D01*
G37*
G36*
G01X1528359Y1217322D02*
G02I-800J0D01*
G37*
G36*
G01X1524619Y1209842D02*
G02I-800J0D01*
G37*
G36*
G01X1517138Y1221062D02*
G02I-800J0D01*
G37*
G36*
G01X1528359Y1209842D02*
G02I-800J0D01*
G37*
G36*
G01X1524619Y1217322D02*
G02I-800J0D01*
G37*
G36*
G01X1520878Y1213582D02*
G02I-800J0D01*
G37*
G36*
G01X1528359Y1228543D02*
G02I-800J0D01*
G37*
G36*
G01X1517138D02*
G02I-800J0D01*
G37*
G36*
G01X1524619Y1232283D02*
G02I-800J0D01*
G37*
G36*
G01X1520878Y1228543D02*
G02I-800J0D01*
G37*
G36*
G01X1524619Y1236023D02*
G02I-800J0D01*
G37*
G36*
G01X1528359Y1224803D02*
G02I-800J0D01*
G37*
G36*
G01X1517138Y1239763D02*
G02I-800J0D01*
G37*
G36*
G01X1520878D02*
G02I-800J0D01*
G37*
G36*
G01Y1247243D02*
G02I-800J0D01*
G37*
G36*
G01X1517138D02*
G02I-800J0D01*
G37*
G36*
G01X1528359Y1243503D02*
G02I-800J0D01*
G37*
G36*
G01Y1247243D02*
G02I-800J0D01*
G37*
G36*
G01X1524619Y1250984D02*
G02I-800J0D01*
G37*
G36*
G01Y1254724D02*
G02I-800J0D01*
G37*
G36*
G01X1547059Y1075196D02*
G02I-800J0D01*
G37*
G36*
G01Y1078936D02*
G02I-800J0D01*
G37*
G36*
G01Y1097637D02*
G02I-800J0D01*
G37*
G36*
G01Y1093897D02*
G02I-800J0D01*
G37*
G36*
G01X1535839Y1187401D02*
G02I-800J0D01*
G37*
G36*
G01X1539579D02*
G02I-800J0D01*
G37*
G36*
G01X1543319Y1191141D02*
G02I-800J0D01*
G37*
G36*
G01X1539579Y1202362D02*
G02I-800J0D01*
G37*
G36*
G01X1535839Y1194881D02*
G02I-800J0D01*
G37*
G36*
G01X1543319Y1198621D02*
G02I-800J0D01*
G37*
G36*
G01X1547059D02*
G02I-800J0D01*
G37*
G36*
G01Y1191141D02*
G02I-800J0D01*
G37*
G36*
G01X1535839Y1202362D02*
G02I-800J0D01*
G37*
G36*
G01X1539579Y1194881D02*
G02I-800J0D01*
G37*
G36*
G01X1543319Y1213582D02*
G02I-800J0D01*
G37*
G36*
G01Y1206102D02*
G02I-800J0D01*
G37*
G36*
G01X1547059Y1213582D02*
G02I-800J0D01*
G37*
G36*
G01X1535839Y1209842D02*
G02I-800J0D01*
G37*
G36*
G01Y1217322D02*
G02I-800J0D01*
G37*
G36*
G01X1547059Y1206102D02*
G02I-800J0D01*
G37*
G36*
G01X1539579Y1209842D02*
G02I-800J0D01*
G37*
G36*
G01Y1217322D02*
G02I-800J0D01*
G37*
G36*
G01X1547059Y1232283D02*
G02I-800J0D01*
G37*
G36*
G01X1535839Y1224803D02*
G02I-800J0D01*
G37*
G36*
G01X1539579Y1236023D02*
G02I-800J0D01*
G37*
G36*
G01X1532099Y1232283D02*
G02I-800J0D01*
G37*
G36*
G01X1543319Y1228543D02*
G02I-800J0D01*
G37*
G36*
G01X1535839D02*
G02I-800J0D01*
G37*
G36*
G01X1547059Y1236023D02*
G02I-800J0D01*
G37*
G36*
G01X1543319Y1224803D02*
G02I-800J0D01*
G37*
G36*
G01X1532099Y1236023D02*
G02I-800J0D01*
G37*
G36*
G01X1539579Y1232283D02*
G02I-800J0D01*
G37*
G36*
G01X1547059Y1250984D02*
G02I-800J0D01*
G37*
G36*
G01X1543319Y1243503D02*
G02I-800J0D01*
G37*
G36*
G01Y1247243D02*
G02I-800J0D01*
G37*
G36*
G01X1539579Y1250984D02*
G02I-800J0D01*
G37*
G36*
G01X1535839Y1243503D02*
G02I-800J0D01*
G37*
G36*
G01X1532099Y1250984D02*
G02I-800J0D01*
G37*
G36*
G01X1535839Y1247243D02*
G02I-800J0D01*
G37*
G36*
G01X1547059Y1254724D02*
G02I-800J0D01*
G37*
G36*
G01X1539579D02*
G02I-800J0D01*
G37*
G36*
G01X1532099D02*
G02I-800J0D01*
G37*
G36*
G01X1554540Y1075196D02*
G02I-800J0D01*
G37*
G36*
G01X1562020D02*
G02I-800J0D01*
G37*
G36*
G01X1558280Y1082677D02*
G02I-800J0D01*
G37*
G36*
G01X1554540Y1078936D02*
G02I-800J0D01*
G37*
G36*
G01X1562020D02*
G02I-800J0D01*
G37*
G36*
G01X1550800Y1086417D02*
G02I-800J0D01*
G37*
G36*
G01Y1082677D02*
G02I-800J0D01*
G37*
G36*
G01X1558280Y1086417D02*
G02I-800J0D01*
G37*
G36*
G01Y1101376D02*
G02I-800J0D01*
G37*
G36*
G01X1562020Y1093897D02*
G02I-800J0D01*
G37*
G36*
G01X1558280Y1105116D02*
G02I-800J0D01*
G37*
G36*
G01X1562020Y1097637D02*
G02I-800J0D01*
G37*
G36*
G01X1550800Y1101376D02*
G02I-800J0D01*
G37*
G36*
G01Y1105116D02*
G02I-800J0D01*
G37*
G36*
G01X1554540Y1093897D02*
G02I-800J0D01*
G37*
G36*
G01Y1097637D02*
G02I-800J0D01*
G37*
G36*
G01Y1232283D02*
G02I-800J0D01*
G37*
G36*
G01X1550800Y1228543D02*
G02I-800J0D01*
G37*
G36*
G01X1554540Y1236023D02*
G02I-800J0D01*
G37*
G36*
G01X1550800Y1224803D02*
G02I-800J0D01*
G37*
G36*
G01X1558280Y1228543D02*
G02I-800J0D01*
G37*
G36*
G01X1562020Y1236023D02*
G02I-800J0D01*
G37*
G36*
G01Y1232283D02*
G02I-800J0D01*
G37*
G36*
G01X1558280Y1224803D02*
G02I-800J0D01*
G37*
G36*
G01X1562020Y1250984D02*
G02I-800J0D01*
G37*
G36*
G01X1550800Y1243503D02*
G02I-800J0D01*
G37*
G36*
G01X1558280Y1247243D02*
G02I-800J0D01*
G37*
G36*
G01X1550800D02*
G02I-800J0D01*
G37*
G36*
G01X1558280Y1243503D02*
G02I-800J0D01*
G37*
G36*
G01X1554540Y1250984D02*
G02I-800J0D01*
G37*
G36*
G01X1562020Y1254724D02*
G02I-800J0D01*
G37*
G36*
G01X1554540D02*
G02I-800J0D01*
G37*
G36*
G01X1576981Y1075196D02*
G02I-800J0D01*
G37*
G36*
G01X1569500D02*
G02I-800J0D01*
G37*
G36*
G01Y1078936D02*
G02I-800J0D01*
G37*
G36*
G01X1573241Y1086417D02*
G02I-800J0D01*
G37*
G36*
G01X1565760Y1082677D02*
G02I-800J0D01*
G37*
G36*
G01Y1086417D02*
G02I-800J0D01*
G37*
G36*
G01X1573241Y1082677D02*
G02I-800J0D01*
G37*
G36*
G01X1576981Y1078936D02*
G02I-800J0D01*
G37*
G36*
G01X1565760Y1105116D02*
G02I-800J0D01*
G37*
G36*
G01X1576981Y1097637D02*
G02I-800J0D01*
G37*
G36*
G01X1569500D02*
G02I-800J0D01*
G37*
G36*
G01X1576981Y1093897D02*
G02I-800J0D01*
G37*
G36*
G01X1569500D02*
G02I-800J0D01*
G37*
G36*
G01X1573241Y1101376D02*
G02I-800J0D01*
G37*
G36*
G01Y1105116D02*
G02I-800J0D01*
G37*
G36*
G01X1565760Y1101376D02*
G02I-800J0D01*
G37*
G36*
G01X1573241Y1228543D02*
G02I-800J0D01*
G37*
G36*
G01X1569500Y1236023D02*
G02I-800J0D01*
G37*
G36*
G01X1565760Y1224803D02*
G02I-800J0D01*
G37*
G36*
G01X1576981Y1236023D02*
G02I-800J0D01*
G37*
G36*
G01X1573241Y1224803D02*
G02I-800J0D01*
G37*
G36*
G01X1565760Y1228543D02*
G02I-800J0D01*
G37*
G36*
G01X1576981Y1232283D02*
G02I-800J0D01*
G37*
G36*
G01X1569500D02*
G02I-800J0D01*
G37*
G36*
G01X1573241Y1247243D02*
G02I-800J0D01*
G37*
G36*
G01X1565760Y1243503D02*
G02I-800J0D01*
G37*
G36*
G01Y1247243D02*
G02I-800J0D01*
G37*
G36*
G01X1576981Y1250984D02*
G02I-800J0D01*
G37*
G36*
G01X1573241Y1243503D02*
G02I-800J0D01*
G37*
G36*
G01X1569500Y1250984D02*
G02I-800J0D01*
G37*
G36*
G01Y1254724D02*
G02I-800J0D01*
G37*
G36*
G01X1576981D02*
G02I-800J0D01*
G37*
G36*
G01X1584461Y1075196D02*
G02I-800J0D01*
G37*
G36*
G01X1591941D02*
G02I-800J0D01*
G37*
G36*
G01X1595682Y1082677D02*
G02I-800J0D01*
G37*
G36*
G01X1580721D02*
G02I-800J0D01*
G37*
G36*
G01X1584461Y1078936D02*
G02I-800J0D01*
G37*
G36*
G01X1595682Y1086417D02*
G02I-800J0D01*
G37*
G36*
G01X1588201Y1082677D02*
G02I-800J0D01*
G37*
G36*
G01X1580721Y1086417D02*
G02I-800J0D01*
G37*
G36*
G01X1588201D02*
G02I-800J0D01*
G37*
G36*
G01X1591941Y1078936D02*
G02I-800J0D01*
G37*
G36*
G01X1595681Y1105116D02*
G02I-800J0D01*
G37*
G36*
G01X1591941Y1097637D02*
G02I-800J0D01*
G37*
G36*
G01X1584461Y1093897D02*
G02I-800J0D01*
G37*
G36*
G01X1595681Y1101376D02*
G02I-800J0D01*
G37*
G36*
G01X1584461Y1097637D02*
G02I-800J0D01*
G37*
G36*
G01X1588201Y1105116D02*
G02I-800J0D01*
G37*
G36*
G01X1580721Y1101376D02*
G02I-800J0D01*
G37*
G36*
G01X1591941Y1093897D02*
G02I-800J0D01*
G37*
G36*
G01X1588201Y1101376D02*
G02I-800J0D01*
G37*
G36*
G01X1580721Y1105116D02*
G02I-800J0D01*
G37*
G36*
G01X1595682Y1224803D02*
G02I-800J0D01*
G37*
G36*
G01X1591941Y1232283D02*
G02I-800J0D01*
G37*
G36*
G01X1584461Y1236023D02*
G02I-800J0D01*
G37*
G36*
G01X1580721Y1228543D02*
G02I-800J0D01*
G37*
G36*
G01X1584461Y1232283D02*
G02I-800J0D01*
G37*
G36*
G01X1595682Y1228543D02*
G02I-800J0D01*
G37*
G36*
G01X1580721Y1224803D02*
G02I-800J0D01*
G37*
G36*
G01X1588201Y1228543D02*
G02I-800J0D01*
G37*
G36*
G01Y1224803D02*
G02I-800J0D01*
G37*
G36*
G01X1591941Y1236023D02*
G02I-800J0D01*
G37*
G36*
G01X1580721Y1247243D02*
G02I-800J0D01*
G37*
G36*
G01X1588201D02*
G02I-800J0D01*
G37*
G36*
G01Y1243503D02*
G02I-800J0D01*
G37*
G36*
G01X1595682D02*
G02I-800J0D01*
G37*
G36*
G01X1580721D02*
G02I-800J0D01*
G37*
G36*
G01X1595682Y1247243D02*
G02I-800J0D01*
G37*
G36*
G01X1584461Y1250984D02*
G02I-800J0D01*
G37*
G36*
G01X1591941D02*
G02I-800J0D01*
G37*
G36*
G01X1584461Y1254724D02*
G02I-800J0D01*
G37*
G36*
G01X1591941D02*
G02I-800J0D01*
G37*
G36*
G01X1606901Y1075195D02*
G02I-800J0D01*
G37*
G36*
G01X1599422Y1075196D02*
G02I-800J0D01*
G37*
G36*
G01X1610641Y1086416D02*
G02I-800J0D01*
G37*
G36*
G01X1606901Y1078935D02*
G02I-800J0D01*
G37*
G36*
G01X1610641Y1082676D02*
G02I-800J0D01*
G37*
G36*
G01X1603162Y1082677D02*
G02I-800J0D01*
G37*
G36*
G01Y1086417D02*
G02I-800J0D01*
G37*
G36*
G01X1599422Y1078936D02*
G02I-800J0D01*
G37*
G36*
G01X1606901Y1093897D02*
G02I-800J0D01*
G37*
G36*
G01X1603162Y1101376D02*
G02I-800J0D01*
G37*
G36*
G01X1599422Y1097637D02*
G02I-800J0D01*
G37*
G36*
G01Y1093897D02*
G02I-800J0D01*
G37*
G36*
G01X1603162Y1105116D02*
G02I-800J0D01*
G37*
G36*
G01X1610642Y1101376D02*
G02I-800J0D01*
G37*
G36*
G01Y1105116D02*
G02I-800J0D01*
G37*
G36*
G01X1606901Y1097637D02*
G02I-800J0D01*
G37*
G36*
G01X1599422Y1236023D02*
G02I-800J0D01*
G37*
G36*
G01X1606902D02*
G02I-800J0D01*
G37*
G36*
G01X1610642Y1228543D02*
G02I-800J0D01*
G37*
G36*
G01X1606902Y1232283D02*
G02I-800J0D01*
G37*
G36*
G01X1603162Y1224803D02*
G02I-800J0D01*
G37*
G36*
G01X1610642D02*
G02I-800J0D01*
G37*
G36*
G01X1603162Y1228543D02*
G02I-800J0D01*
G37*
G36*
G01X1599422Y1232283D02*
G02I-800J0D01*
G37*
G36*
G01Y1250984D02*
G02I-800J0D01*
G37*
G36*
G01X1610642Y1247243D02*
G02I-800J0D01*
G37*
G36*
G01X1606902Y1250984D02*
G02I-800J0D01*
G37*
G36*
G01X1610642Y1243503D02*
G02I-800J0D01*
G37*
G36*
G01X1603162Y1247243D02*
G02I-800J0D01*
G37*
G36*
G01Y1243503D02*
G02I-800J0D01*
G37*
G36*
G01X1599422Y1254724D02*
G02I-800J0D01*
G37*
G36*
G01X1606902D02*
G02I-800J0D01*
G37*
G36*
G01X1614381Y1075196D02*
G02I-800J0D01*
G37*
G36*
G01X1621862D02*
G02I-800J0D01*
G37*
G36*
G01X1614381Y1078936D02*
G02I-800J0D01*
G37*
G36*
G01X1625602Y1082676D02*
G02I-800J0D01*
G37*
G36*
G01X1618121Y1082677D02*
G02I-800J0D01*
G37*
G36*
G01X1621862Y1078936D02*
G02I-800J0D01*
G37*
G36*
G01X1618121Y1086417D02*
G02I-800J0D01*
G37*
G36*
G01X1625602Y1086416D02*
G02I-800J0D01*
G37*
G36*
G01X1621862Y1093897D02*
G02I-800J0D01*
G37*
G36*
G01X1618122Y1105116D02*
G02I-800J0D01*
G37*
G36*
G01Y1101376D02*
G02I-800J0D01*
G37*
G36*
G01X1614381Y1093897D02*
G02I-800J0D01*
G37*
G36*
G01Y1097637D02*
G02I-800J0D01*
G37*
G36*
G01X1625603Y1101376D02*
G02I-800J0D01*
G37*
G36*
G01Y1105116D02*
G02I-800J0D01*
G37*
G36*
G01X1621862Y1097637D02*
G02I-800J0D01*
G37*
G36*
G01X1618122Y1228543D02*
G02I-800J0D01*
G37*
G36*
G01X1625603Y1224803D02*
G02I-800J0D01*
G37*
G36*
G01X1618122D02*
G02I-800J0D01*
G37*
G36*
G01X1621863Y1236023D02*
G02I-800J0D01*
G37*
G36*
G01X1614382D02*
G02I-800J0D01*
G37*
G36*
G01X1621863Y1232283D02*
G02I-800J0D01*
G37*
G36*
G01X1625603Y1228543D02*
G02I-800J0D01*
G37*
G36*
G01X1614382Y1232283D02*
G02I-800J0D01*
G37*
G36*
G01X1625603Y1247243D02*
G02I-800J0D01*
G37*
G36*
G01Y1243503D02*
G02I-800J0D01*
G37*
G36*
G01X1614382Y1250984D02*
G02I-800J0D01*
G37*
G36*
G01X1618122Y1243503D02*
G02I-800J0D01*
G37*
G36*
G01Y1247243D02*
G02I-800J0D01*
G37*
G36*
G01X1621863Y1250984D02*
G02I-800J0D01*
G37*
G36*
G01Y1254724D02*
G02I-800J0D01*
G37*
G36*
G01X1614382D02*
G02I-800J0D01*
G37*
G36*
G01X1636822Y1075196D02*
G02I-800J0D01*
G37*
G36*
G01X1644303D02*
G02I-800J0D01*
G37*
G36*
G01X1629342D02*
G02I-800J0D01*
G37*
G36*
G01X1633082Y1082677D02*
G02I-800J0D01*
G37*
G36*
G01X1644303Y1078936D02*
G02I-800J0D01*
G37*
G36*
G01X1629342D02*
G02I-800J0D01*
G37*
G36*
G01X1640562Y1086416D02*
G02I-800J0D01*
G37*
G36*
G01X1633082Y1086417D02*
G02I-800J0D01*
G37*
G36*
G01X1636822Y1078936D02*
G02I-800J0D01*
G37*
G36*
G01X1640562Y1082676D02*
G02I-800J0D01*
G37*
G36*
G01X1640563Y1101376D02*
G02I-800J0D01*
G37*
G36*
G01X1629342Y1093897D02*
G02I-800J0D01*
G37*
G36*
G01X1636822D02*
G02I-800J0D01*
G37*
G36*
G01X1640563Y1105116D02*
G02I-800J0D01*
G37*
G36*
G01X1633083D02*
G02I-800J0D01*
G37*
G36*
G01Y1101376D02*
G02I-800J0D01*
G37*
G36*
G01X1636822Y1097637D02*
G02I-800J0D01*
G37*
G36*
G01X1644303D02*
G02I-800J0D01*
G37*
G36*
G01Y1093897D02*
G02I-800J0D01*
G37*
G36*
G01X1629342Y1097637D02*
G02I-800J0D01*
G37*
G36*
G01X1633083Y1228543D02*
G02I-800J0D01*
G37*
G36*
G01X1629343Y1236023D02*
G02I-800J0D01*
G37*
G36*
G01Y1232283D02*
G02I-800J0D01*
G37*
G36*
G01X1640563Y1224803D02*
G02I-800J0D01*
G37*
G36*
G01X1636823Y1236023D02*
G02I-800J0D01*
G37*
G36*
G01X1644304Y1232283D02*
G02I-800J0D01*
G37*
G36*
G01X1633083Y1224803D02*
G02I-800J0D01*
G37*
G36*
G01X1644304Y1236023D02*
G02I-800J0D01*
G37*
G36*
G01X1636823Y1232283D02*
G02I-800J0D01*
G37*
G36*
G01X1640563Y1228543D02*
G02I-800J0D01*
G37*
G36*
G01X1633083Y1243503D02*
G02I-800J0D01*
G37*
G36*
G01X1640563D02*
G02I-800J0D01*
G37*
G36*
G01X1636823Y1250984D02*
G02I-800J0D01*
G37*
G36*
G01X1633083Y1247243D02*
G02I-800J0D01*
G37*
G36*
G01X1644304Y1250984D02*
G02I-800J0D01*
G37*
G36*
G01X1629343D02*
G02I-800J0D01*
G37*
G36*
G01X1640563Y1247243D02*
G02I-800J0D01*
G37*
G36*
G01X1636823Y1254724D02*
G02I-800J0D01*
G37*
G36*
G01X1629343D02*
G02I-800J0D01*
G37*
G36*
G01X1644304D02*
G02I-800J0D01*
G37*
G36*
G01X1651783Y1075196D02*
G02I-800J0D01*
G37*
G36*
G01X1659263D02*
G02I-800J0D01*
G37*
G36*
G01X1655523Y1086416D02*
G02I-800J0D01*
G37*
G36*
G01Y1082676D02*
G02I-800J0D01*
G37*
G36*
G01X1651783Y1078936D02*
G02I-800J0D01*
G37*
G36*
G01X1648042Y1082677D02*
G02I-800J0D01*
G37*
G36*
G01Y1086417D02*
G02I-800J0D01*
G37*
G36*
G01X1659263Y1078936D02*
G02I-800J0D01*
G37*
G36*
G01Y1097637D02*
G02I-800J0D01*
G37*
G36*
G01X1648044Y1101376D02*
G02I-800J0D01*
G37*
G36*
G01X1659263Y1093897D02*
G02I-800J0D01*
G37*
G36*
G01X1655524Y1105116D02*
G02I-800J0D01*
G37*
G36*
G01X1651783Y1093897D02*
G02I-800J0D01*
G37*
G36*
G01X1648044Y1105116D02*
G02I-800J0D01*
G37*
G36*
G01X1655524Y1101376D02*
G02I-800J0D01*
G37*
G36*
G01X1651783Y1097637D02*
G02I-800J0D01*
G37*
G36*
G01X1655524Y1228543D02*
G02I-800J0D01*
G37*
G36*
G01X1648044D02*
G02I-800J0D01*
G37*
G36*
G01X1659264Y1232283D02*
G02I-800J0D01*
G37*
G36*
G01X1655524Y1224803D02*
G02I-800J0D01*
G37*
G36*
G01X1659264Y1236023D02*
G02I-800J0D01*
G37*
G36*
G01X1651784D02*
G02I-800J0D01*
G37*
G36*
G01X1648044Y1224803D02*
G02I-800J0D01*
G37*
G36*
G01X1651784Y1232283D02*
G02I-800J0D01*
G37*
G36*
G01X1655524Y1243503D02*
G02I-800J0D01*
G37*
G36*
G01X1651784Y1250984D02*
G02I-800J0D01*
G37*
G36*
G01X1648044Y1247243D02*
G02I-800J0D01*
G37*
G36*
G01X1655524D02*
G02I-800J0D01*
G37*
G36*
G01X1648044Y1243503D02*
G02I-800J0D01*
G37*
G36*
G01X1659264Y1250984D02*
G02I-800J0D01*
G37*
G36*
G01X1651784Y1254724D02*
G02I-800J0D01*
G37*
G36*
G01X1659264D02*
G02I-800J0D01*
G37*
G36*
G01X1674224Y1075196D02*
G02I-800J0D01*
G37*
G36*
G01X1666744D02*
G02I-800J0D01*
G37*
G36*
G01X1663003Y1086417D02*
G02I-800J0D01*
G37*
G36*
G01Y1082677D02*
G02I-800J0D01*
G37*
G36*
G01X1670484Y1086416D02*
G02I-800J0D01*
G37*
G36*
G01X1666744Y1078936D02*
G02I-800J0D01*
G37*
G36*
G01X1674224D02*
G02I-800J0D01*
G37*
G36*
G01X1670484Y1082676D02*
G02I-800J0D01*
G37*
G36*
G01X1666744Y1093897D02*
G02I-800J0D01*
G37*
G36*
G01X1663004Y1105116D02*
G02I-800J0D01*
G37*
G36*
G01X1670485D02*
G02I-800J0D01*
G37*
G36*
G01X1674224Y1097637D02*
G02I-800J0D01*
G37*
G36*
G01X1670485Y1101376D02*
G02I-800J0D01*
G37*
G36*
G01X1674224Y1093897D02*
G02I-800J0D01*
G37*
G36*
G01X1666744Y1097637D02*
G02I-800J0D01*
G37*
G36*
G01X1663004Y1101376D02*
G02I-800J0D01*
G37*
G36*
G01X1674225Y1112598D02*
G02I-800J0D01*
G37*
G36*
G01X1666745Y1123818D02*
G02I-800J0D01*
G37*
G36*
G01X1674225Y1120078D02*
G02I-800J0D01*
G37*
G36*
G01X1670485Y1123818D02*
G02I-800J0D01*
G37*
G36*
G01X1666745Y1116338D02*
G02I-800J0D01*
G37*
G36*
G01X1670485D02*
G02I-800J0D01*
G37*
G36*
G01X1666745Y1131299D02*
G02I-800J0D01*
G37*
G36*
G01X1670485D02*
G02I-800J0D01*
G37*
G36*
G01X1674225Y1127559D02*
G02I-800J0D01*
G37*
G36*
G01Y1135039D02*
G02I-800J0D01*
G37*
G36*
G01Y1202362D02*
G02I-800J0D01*
G37*
G36*
G01X1666745Y1198621D02*
G02I-800J0D01*
G37*
G36*
G01X1670485D02*
G02I-800J0D01*
G37*
G36*
G01X1666745Y1206102D02*
G02I-800J0D01*
G37*
G36*
G01X1670485Y1213582D02*
G02I-800J0D01*
G37*
G36*
G01X1674225Y1209842D02*
G02I-800J0D01*
G37*
G36*
G01X1670485Y1206102D02*
G02I-800J0D01*
G37*
G36*
G01X1666745Y1213582D02*
G02I-800J0D01*
G37*
G36*
G01X1674225Y1217322D02*
G02I-800J0D01*
G37*
G36*
G01Y1236023D02*
G02I-800J0D01*
G37*
G36*
G01X1663004Y1228543D02*
G02I-800J0D01*
G37*
G36*
G01X1670485D02*
G02I-800J0D01*
G37*
G36*
G01X1674225Y1232283D02*
G02I-800J0D01*
G37*
G36*
G01X1666745D02*
G02I-800J0D01*
G37*
G36*
G01Y1236023D02*
G02I-800J0D01*
G37*
G36*
G01X1663004Y1224803D02*
G02I-800J0D01*
G37*
G36*
G01X1670485D02*
G02I-800J0D01*
G37*
G36*
G01X1674225Y1250984D02*
G02I-800J0D01*
G37*
G36*
G01X1663004Y1247243D02*
G02I-800J0D01*
G37*
G36*
G01Y1243503D02*
G02I-800J0D01*
G37*
G36*
G01X1666745Y1250984D02*
G02I-800J0D01*
G37*
G36*
G01X1670485Y1247243D02*
G02I-800J0D01*
G37*
G36*
G01Y1243503D02*
G02I-800J0D01*
G37*
G36*
G01X1666745Y1254724D02*
G02I-800J0D01*
G37*
G36*
G01X1674225D02*
G02I-800J0D01*
G37*
G36*
G01X1681704Y1075196D02*
G02I-800J0D01*
G37*
G36*
G01X1689184D02*
G02I-800J0D01*
G37*
G36*
G01X1692926Y1090157D02*
G02I-800J0D01*
G37*
G36*
G01Y1082676D02*
G02I-800J0D01*
G37*
G36*
G01X1685444Y1082677D02*
G02I-800J0D01*
G37*
G36*
G01Y1086417D02*
G02I-800J0D01*
G37*
G36*
G01X1681704Y1078936D02*
G02I-800J0D01*
G37*
G36*
G01X1689184D02*
G02I-800J0D01*
G37*
G36*
G01X1677964Y1086417D02*
G02I-800J0D01*
G37*
G36*
G01Y1082677D02*
G02I-800J0D01*
G37*
G36*
G01X1692926Y1101377D02*
G02I-800J0D01*
G37*
G36*
G01X1685445D02*
G02I-800J0D01*
G37*
G36*
G01X1677965Y1105116D02*
G02I-800J0D01*
G37*
G36*
G01X1681704Y1097637D02*
G02I-800J0D01*
G37*
G36*
G01X1677965Y1101376D02*
G02I-800J0D01*
G37*
G36*
G01X1689185Y1097637D02*
G02I-800J0D01*
G37*
G36*
G01X1685445Y1105117D02*
G02I-800J0D01*
G37*
G36*
G01X1681704Y1093897D02*
G02I-800J0D01*
G37*
G36*
G01X1689185D02*
G02I-800J0D01*
G37*
G36*
G01X1677965Y1120078D02*
G02I-800J0D01*
G37*
G36*
G01Y1112598D02*
G02I-800J0D01*
G37*
G36*
G01X1692926Y1116338D02*
G02I-800J0D01*
G37*
G36*
G01Y1108858D02*
G02I-800J0D01*
G37*
G36*
G01X1685445Y1120078D02*
G02I-800J0D01*
G37*
G36*
G01X1689185D02*
G02I-800J0D01*
G37*
G36*
G01X1685445Y1112598D02*
G02I-800J0D01*
G37*
G36*
G01X1692926Y1123818D02*
G02I-800J0D01*
G37*
G36*
G01X1689185Y1112598D02*
G02I-800J0D01*
G37*
G36*
G01X1677965Y1135039D02*
G02I-800J0D01*
G37*
G36*
G01Y1127559D02*
G02I-800J0D01*
G37*
G36*
G01X1685445Y1135039D02*
G02I-800J0D01*
G37*
G36*
G01Y1127558D02*
G02I-800J0D01*
G37*
G36*
G01X1692926Y1131299D02*
G02I-800J0D01*
G37*
G36*
G01X1689185Y1127558D02*
G02I-800J0D01*
G37*
G36*
G01Y1135039D02*
G02I-800J0D01*
G37*
G36*
G01X1685445Y1202362D02*
G02I-800J0D01*
G37*
G36*
G01X1692926Y1198621D02*
G02I-800J0D01*
G37*
G36*
G01X1689185Y1202362D02*
G02I-800J0D01*
G37*
G36*
G01X1677965D02*
G02I-800J0D01*
G37*
G36*
G01X1692926Y1213582D02*
G02I-800J0D01*
G37*
G36*
G01X1685445Y1217322D02*
G02I-800J0D01*
G37*
G36*
G01Y1209842D02*
G02I-800J0D01*
G37*
G36*
G01X1692926Y1206102D02*
G02I-800J0D01*
G37*
G36*
G01X1677965Y1209842D02*
G02I-800J0D01*
G37*
G36*
G01X1692926Y1221062D02*
G02I-800J0D01*
G37*
G36*
G01X1689185Y1209842D02*
G02I-800J0D01*
G37*
G36*
G01X1677965Y1217322D02*
G02I-800J0D01*
G37*
G36*
G01X1689185D02*
G02I-800J0D01*
G37*
G36*
G01X1677965Y1228543D02*
G02I-800J0D01*
G37*
G36*
G01X1681705Y1236023D02*
G02I-800J0D01*
G37*
G36*
G01Y1232283D02*
G02I-800J0D01*
G37*
G36*
G01X1692926Y1228543D02*
G02I-800J0D01*
G37*
G36*
G01X1685445Y1224803D02*
G02I-800J0D01*
G37*
G36*
G01Y1228543D02*
G02I-800J0D01*
G37*
G36*
G01X1677965Y1224803D02*
G02I-800J0D01*
G37*
G36*
G01X1689185Y1232283D02*
G02I-800J0D01*
G37*
G36*
G01Y1236023D02*
G02I-800J0D01*
G37*
G36*
G01X1685445Y1243503D02*
G02I-800J0D01*
G37*
G36*
G01X1677965D02*
G02I-800J0D01*
G37*
G36*
G01X1692926Y1247243D02*
G02I-800J0D01*
G37*
G36*
G01X1685445D02*
G02I-800J0D01*
G37*
G36*
G01X1677965D02*
G02I-800J0D01*
G37*
G36*
G01X1689185Y1250984D02*
G02I-800J0D01*
G37*
G36*
G01X1692926Y1239763D02*
G02I-800J0D01*
G37*
G36*
G01X1681705Y1250984D02*
G02I-800J0D01*
G37*
G36*
G01X1689185Y1254724D02*
G02I-800J0D01*
G37*
G36*
G01X1681705D02*
G02I-800J0D01*
G37*
G36*
G01X1696666Y1090157D02*
G02I-800J0D01*
G37*
G36*
G01Y1082676D02*
G02I-800J0D01*
G37*
G36*
G01Y1101377D02*
G02I-800J0D01*
G37*
G36*
G01Y1123818D02*
G02I-800J0D01*
G37*
G36*
G01Y1116338D02*
G02I-800J0D01*
G37*
G36*
G01Y1108858D02*
G02I-800J0D01*
G37*
G36*
G01Y1131299D02*
G02I-800J0D01*
G37*
G36*
G01Y1198621D02*
G02I-800J0D01*
G37*
G36*
G01Y1221062D02*
G02I-800J0D01*
G37*
G36*
G01Y1213582D02*
G02I-800J0D01*
G37*
G36*
G01Y1206102D02*
G02I-800J0D01*
G37*
G36*
G01Y1228543D02*
G02I-800J0D01*
G37*
G36*
G01Y1239763D02*
G02I-800J0D01*
G37*
G36*
G01Y1247243D02*
G02I-800J0D01*
G37*
%LPD*%
G75*
G54D15*
X7271Y70981D03*
X11011Y79720D03*
X8786Y88425D03*
X14264Y94236D03*
X10292D03*
X12786Y87903D03*
X18000Y90000D03*
X18298Y102141D03*
X8000Y102500D03*
X10131Y115473D03*
X15143Y115581D03*
X14996Y133034D03*
X11442Y132719D03*
X19855Y133000D03*
X9082Y135789D03*
X19855Y141362D03*
X11999Y141415D03*
X15948Y141267D03*
X10966Y162073D03*
Y159073D03*
X16909Y153263D03*
X12247Y166341D03*
X17313Y166937D03*
X21909Y153263D03*
X22335Y166721D03*
X16709Y175943D03*
X19572Y219470D03*
Y221970D03*
X10259Y218085D03*
X13059D03*
X19638Y226320D03*
X16859Y216385D03*
X19572Y216970D03*
X22599Y228646D03*
X18206Y244571D03*
X15586Y249108D03*
X13715Y259381D03*
X8970Y254871D03*
X18206Y264571D03*
X7036Y272371D03*
X8335Y280663D03*
X14807Y282181D03*
X15586Y269108D03*
X15499Y288542D03*
X17033Y1006819D03*
X14357Y1009906D03*
X20216Y1009748D03*
X14197Y1014205D03*
Y1017759D03*
X20197Y1014205D03*
Y1017759D03*
X12599Y1438143D03*
X16304Y1468196D03*
X15889Y1494254D03*
X10089D03*
X6489Y1501334D03*
X19745Y1508846D03*
X7983Y1529035D03*
Y1525635D03*
X19735Y1530499D03*
X19859Y1520657D03*
X6951Y1538547D03*
X18879Y1534334D03*
X10367Y1553080D03*
X32350Y67562D03*
X28442Y55340D03*
X32350Y59562D03*
Y63562D03*
X26588Y97667D03*
X35442D03*
X35048Y103411D03*
X35688Y111255D03*
Y114655D03*
X22439Y102495D03*
X35207Y106561D03*
X28388Y121742D03*
X35688Y125428D03*
X28388Y132515D03*
Y118342D03*
X35688Y128828D03*
X28388Y135915D03*
X22935Y162073D03*
Y159073D03*
X26565Y177448D03*
X32507Y180517D03*
X30567Y195176D03*
X28067D03*
X25567D03*
X33067D03*
X29585Y199248D03*
X32585D03*
X29921Y206806D03*
X32585Y202048D03*
X25648Y210509D03*
X28148D03*
X29585Y201748D03*
X27421Y206806D03*
X27340Y230556D03*
X36185Y230117D03*
X31595Y227824D03*
X32201Y238714D03*
X23844Y239299D03*
X21556Y232971D03*
X31682Y246874D03*
X33902Y244297D03*
X26325Y262078D03*
X25549Y256394D03*
X31682Y266874D03*
X29116Y281129D03*
X37117Y279991D03*
X25549Y276394D03*
X34845Y291756D03*
X26629Y295619D03*
X35650Y491982D03*
Y495982D03*
X30177Y534211D03*
X34359Y541135D03*
X34732Y534909D03*
X25819Y527726D03*
Y548726D03*
X34425Y546553D03*
X34448Y552726D03*
X25819Y544726D03*
X30123Y611071D03*
X27686Y621311D03*
X36494Y616905D03*
X36306Y622285D03*
X27686Y629311D03*
Y625311D03*
X36692Y633724D03*
X36575Y627713D03*
X35293Y662952D03*
X35250Y671508D03*
X34565Y699082D03*
X36529Y1006321D03*
X30479Y1006509D03*
X24456Y1006401D03*
X32093Y1009748D03*
X26155Y1009985D03*
X29197Y1014205D03*
X32197Y1017759D03*
X26197D03*
X35197Y1014205D03*
X21196Y1065529D03*
Y1063029D03*
X36089Y1062601D03*
Y1065101D03*
X35925Y1075663D03*
X33425D03*
X28996Y1065529D03*
X23796D03*
X26396D03*
Y1063029D03*
X23796D03*
X28996D03*
X28606Y1082678D03*
X23406D03*
X26006D03*
Y1080178D03*
X23406D03*
X28606D03*
X20806Y1082678D03*
Y1080178D03*
X21321Y1098769D03*
X26521D03*
X29121D03*
X23921D03*
Y1101335D03*
X29121D03*
X26521D03*
X21321D03*
X32574Y1111633D03*
X29874D03*
X27274D03*
X24674D03*
Y1121333D03*
X27274D03*
X29874D03*
X32574D03*
X24674Y1130333D03*
X21974D03*
X21209Y1138705D03*
X23709D03*
X31631Y1198651D03*
X29860Y1438552D03*
X23603Y1449735D03*
X29880Y1441702D03*
X35825Y1464845D03*
X33189Y1501373D03*
X22381Y1554152D03*
X26231Y1554167D03*
X45988Y90512D03*
X51550Y90615D03*
X48476Y180812D03*
X48643Y442919D03*
X48596Y451419D03*
X45643Y472905D03*
X41643Y473419D03*
X49643Y472905D03*
Y464419D03*
X41643Y464919D03*
X48390Y485128D03*
X51239Y485138D03*
X40009Y481467D03*
X43948Y492108D03*
X44563Y482165D03*
X39801Y504825D03*
X42301D03*
X44801D03*
X43804Y500202D03*
X45256Y495993D03*
X45293Y522569D03*
X39742Y517401D03*
X42242D03*
X44742D03*
X46993Y529169D03*
X41408Y531882D03*
X43908D03*
X45293Y525369D03*
X46408Y531882D03*
X38358Y531948D03*
X52869Y537958D03*
X46643Y555194D03*
X52869Y540458D03*
X43843Y555194D03*
X46643Y571194D03*
X43843D03*
Y563194D03*
X46643D03*
X51000Y581222D03*
X45400D03*
X48200D03*
X51000Y591215D03*
X45400D03*
X48200D03*
X51172Y607762D03*
X48372D03*
X45572D03*
Y610562D03*
X48372D03*
X51172D03*
X40362Y610548D03*
X54192Y633473D03*
X42172Y633716D03*
X49192Y628078D03*
X47179Y633736D03*
X37847Y662910D03*
X39549Y682108D03*
X36910D03*
X37804Y671508D03*
X40165Y699082D03*
X37365D03*
X49249Y837718D03*
X52349D03*
X46049D03*
X53549Y843118D03*
X52077Y905295D03*
X48429Y916430D03*
X47264Y919649D03*
X48683Y1006510D03*
X42470Y1006738D03*
X50541Y1009589D03*
X44999Y1009510D03*
X38823Y1009273D03*
X47197Y1014205D03*
X41197D03*
X44197Y1017759D03*
X38197D03*
X48704Y1017982D03*
X43889Y1062601D03*
X38689D03*
X41289D03*
Y1065101D03*
X38689D03*
X43889D03*
X47314Y1072228D03*
X41172Y1079064D03*
X46166Y1093757D03*
X39659Y1105100D03*
X42259D03*
X44859D03*
X47559D03*
X48585Y1123867D03*
X47559Y1114800D03*
X44859D03*
X42259D03*
X39659D03*
X48547Y1133688D03*
X51047D03*
X55188Y1205179D03*
X51023Y1201416D03*
X48842Y1211109D03*
X53479Y1216256D03*
X43198Y1254055D03*
X45698D03*
X48198D03*
X45698Y1251555D03*
X43198D03*
X48198D03*
X47621Y1343672D03*
X39225Y1464845D03*
X48089Y1501387D03*
X39095Y1501361D03*
X47074Y1555923D03*
X40951Y1555932D03*
X64785Y79993D03*
Y82593D03*
Y85193D03*
Y74793D03*
Y77393D03*
X64829Y92874D03*
X55871Y99961D03*
X55921Y95236D03*
X66856Y104249D03*
Y107649D03*
X66478Y162368D03*
X63878D03*
X69261Y211695D03*
Y208695D03*
X65189Y210713D03*
Y213213D03*
Y208213D03*
X54733Y212978D03*
Y215478D03*
Y207978D03*
Y210478D03*
X65189Y215713D03*
X57987Y258880D03*
X60562Y264180D03*
X58062D03*
X66956Y267526D03*
Y270026D03*
X54167Y457339D03*
X56667D03*
X65737Y445603D03*
X57857Y446071D03*
X56667Y459839D03*
X54167D03*
Y462339D03*
X56667D03*
X62224Y473045D03*
X67670Y464818D03*
X58224Y465004D03*
X63154Y462371D03*
X55124Y478625D03*
X53739Y485138D03*
X56239D03*
X56824Y482425D03*
X55124Y475825D03*
X62700Y491214D03*
X66403Y495487D03*
X62700Y493714D03*
X66403Y492987D03*
X68202Y537877D03*
X56572Y539731D03*
X68202Y542877D03*
Y545377D03*
Y540377D03*
X61330Y544895D03*
X56572Y542231D03*
X64130Y541895D03*
Y544895D03*
X61630Y541895D03*
X68188Y548358D03*
X64408Y582747D03*
X63859Y590801D03*
X67684Y597232D03*
X63684Y597130D03*
X67684Y605637D03*
X61854Y617853D03*
Y620653D03*
X53972Y607762D03*
Y610562D03*
X59684Y605443D03*
X63684D03*
X66530Y625013D03*
X58181Y627908D03*
X64692Y642184D03*
X56049Y827218D03*
X68649D03*
X69049Y847718D03*
X65549Y850718D03*
X68598Y859415D03*
X68778Y873821D03*
X63969Y869475D03*
X63930Y874694D03*
X68100Y910122D03*
X71528Y913190D03*
X64632Y901500D03*
X59962Y910251D03*
X53197Y1014205D03*
Y1017759D03*
X55699Y1072761D03*
X61588Y1074481D03*
X62109Y1087656D03*
Y1084656D03*
Y1079656D03*
Y1091656D03*
X60269Y1198820D03*
X63094Y1207604D03*
X55596Y1210466D03*
X68245Y1212054D03*
X58443Y1272257D03*
X54843Y1501625D03*
X60227Y1514751D03*
X60277Y1528395D03*
X55862Y1541791D03*
X65478Y1541980D03*
X60303Y1534436D03*
X60747Y1555890D03*
X64747D03*
X60864Y1583484D03*
X58064D03*
X55264D03*
X69816Y1592527D03*
X60554Y1615152D03*
X73110Y98551D03*
X77804Y95879D03*
X76005Y114623D03*
Y111223D03*
X76660Y103783D03*
X76005Y125396D03*
Y128796D03*
X75194Y141247D03*
X71422Y147540D03*
X82661Y143740D03*
X80041Y148277D03*
X73578Y165393D03*
Y162793D03*
Y170493D03*
Y167993D03*
X80502Y177616D03*
X81083Y172190D03*
X72575Y181426D03*
X75786Y181366D03*
X78581Y181009D03*
X83756Y168697D03*
X84844Y191941D03*
X75400Y184012D03*
X72783Y184221D03*
X72061Y208695D03*
X71761Y211695D03*
X76819Y213859D03*
Y211359D03*
X80522Y213132D03*
Y215632D03*
X80766Y256303D03*
X75438Y265701D03*
X85541Y266114D03*
X80525Y265896D03*
X72256Y267526D03*
X69756D03*
Y270026D03*
X72256D03*
X83014Y281982D03*
X77073Y281716D03*
X71130Y462152D03*
Y459652D03*
Y464652D03*
X73630Y459652D03*
Y462152D03*
Y464652D03*
X78033Y491133D03*
X71461Y498151D03*
Y495151D03*
X73961D03*
X78033Y498633D03*
Y496133D03*
Y493633D03*
X73961Y498151D03*
X78133Y553297D03*
Y555897D03*
X75688Y548358D03*
X73188D03*
X70688D03*
X78133Y558497D03*
Y566597D03*
Y563697D03*
Y561097D03*
X72128Y570686D03*
X74923Y570478D03*
X75340Y576484D03*
X74983Y573689D03*
X72337Y573303D03*
X78733Y578405D03*
X84159Y578986D03*
X83684Y596729D03*
X72515Y596089D03*
X77734Y596782D03*
X81740Y619758D03*
Y616958D03*
Y614158D03*
X69670Y619513D03*
Y616713D03*
Y613913D03*
X79684Y605443D03*
X82648Y670679D03*
X73914Y660107D03*
X79043Y667391D03*
X84845Y659857D03*
X84314Y686107D03*
X82562Y680037D03*
X78735Y683426D03*
X72149Y827318D03*
X74349Y824718D03*
Y821918D03*
X74700Y842890D03*
X84367Y878286D03*
X76528Y878533D03*
X74028Y889065D03*
X83079Y888515D03*
X72035Y898346D03*
X80339Y897943D03*
X76203Y897910D03*
X80593Y946082D03*
X78167Y949261D03*
X76332Y953421D03*
X87632Y1007522D03*
X70059Y1075656D03*
X70302Y1067656D03*
X77734Y1095676D03*
X70947Y1201565D03*
Y1205835D03*
X71006Y1228684D03*
X71020Y1224323D03*
X74909Y1593009D03*
X71910Y1625009D03*
X78291Y1625743D03*
X83689Y1624736D03*
X82291Y1633801D03*
X78291D03*
X70291D03*
X86407Y132509D03*
Y118335D03*
Y121735D03*
Y135909D03*
X91224Y141247D03*
X92337Y144172D03*
X95711Y143518D03*
X94811Y152373D03*
X97961Y152562D03*
X103456Y157370D03*
X98826Y172665D03*
X98763Y178560D03*
X98653Y183834D03*
X99639Y186629D03*
X98943Y200864D03*
X92898Y192490D03*
X98173Y190185D03*
X89353Y206767D03*
X86853D03*
X91853D03*
X98966Y207037D03*
X99032Y212455D03*
X89483Y221708D03*
X86983D03*
X86398Y224421D03*
X88098Y231021D03*
Y228221D03*
X96333Y221642D03*
X91983Y221708D03*
X103841Y228631D03*
X93649Y236189D03*
X91149D03*
X88649D03*
X91090Y248765D03*
X88590D03*
X93590D03*
X97747Y265897D03*
X100247D03*
X94087Y270695D03*
X91287D03*
X88787D03*
Y268195D03*
X91287D03*
X94087D03*
X98255Y374510D03*
X100120Y377898D03*
X100066Y381976D03*
X86788Y581659D03*
X87684Y605443D03*
X95973Y655660D03*
X92897Y658359D03*
X95917Y658374D03*
X95539Y664443D03*
X86289Y822088D03*
X86367Y848086D03*
X90000Y871389D03*
X103770Y868206D03*
X103692Y900295D03*
X91387Y905295D03*
X100058Y977651D03*
X99836Y980330D03*
X103836Y988813D03*
X100200Y988800D03*
X95836Y988813D03*
X85706Y998507D03*
X94398Y1006648D03*
X101025Y1009655D03*
X94586Y1023900D03*
X91765Y1018307D03*
X88007Y1013678D03*
X88479Y1023731D03*
X88287Y1026537D03*
X97609Y1018469D03*
X90450Y1033542D03*
X93496Y1547768D03*
X107364Y116594D03*
X118307Y110784D03*
X113307D03*
X107364Y119594D03*
X117886Y124663D03*
X112864Y124879D03*
X107798Y124283D03*
X119230Y138838D03*
X106205Y161306D03*
X107540Y176665D03*
Y168665D03*
Y196665D03*
Y192665D03*
X107653Y186778D03*
X107572Y204864D03*
Y208864D03*
X112621Y218085D03*
X115421D03*
X103213Y219379D03*
X117948Y249108D03*
X109329Y248371D03*
X111993Y710102D03*
X120250Y758841D03*
X113505Y796856D03*
X109591Y796905D03*
X102355Y874267D03*
X102947Y877196D03*
X102320Y891043D03*
X110887Y884000D03*
X103972Y977609D03*
X103836Y980330D03*
X111836Y988813D03*
X119836D03*
X115836D03*
X107836D03*
X103825Y1009655D03*
X105971Y1025745D03*
X114770Y1016827D03*
X110409Y1024094D03*
X114770Y1029427D03*
X110970Y1030672D03*
X101970D03*
X104970D03*
X107970D03*
X102761Y1096233D03*
X108971Y1109564D03*
X103124D03*
Y1122164D03*
X108971D03*
X103124Y1134764D03*
X108971D03*
X103124Y1147364D03*
X108971D03*
X103124Y1172564D03*
X108971D03*
X103124Y1159964D03*
X108971D03*
X103861Y1182703D03*
X118533Y1207737D03*
X112048Y1214372D03*
X107803Y1218169D03*
X128950Y97667D03*
X133200Y95111D03*
X124606Y102495D03*
X119333Y116594D03*
X130750Y132515D03*
Y121742D03*
Y118342D03*
X119333Y119594D03*
X122867Y125107D03*
X130750Y135915D03*
X124340Y142862D03*
X131481Y143762D03*
X125381Y148717D03*
X131947Y199248D03*
X127929Y195176D03*
X130429D03*
X132929D03*
X134947Y199248D03*
X128010Y210509D03*
X130510D03*
X132283Y206806D03*
X129783D03*
X131947Y201748D03*
X122000Y226320D03*
X119221Y216385D03*
X121934Y216970D03*
Y219470D03*
Y221970D03*
X129702Y230556D03*
X133957Y227824D03*
X124961Y228646D03*
X128687Y242078D03*
X123918Y232971D03*
X134044Y246874D03*
X120568Y244571D03*
X127911Y256394D03*
X126131Y359511D03*
X125753Y365856D03*
X119099Y755052D03*
X118467Y796785D03*
X122437Y860775D03*
X125698Y857515D03*
X122432Y857540D03*
X129666Y857514D03*
X133424Y857303D03*
X122887Y888000D03*
X123387Y892000D03*
X135836Y988813D03*
X131836D03*
X123836D03*
X127836D03*
X120617Y1029427D03*
Y1016827D03*
X133579Y1097469D03*
X124925Y1102091D03*
X130380Y1105091D03*
X124880D03*
X124925Y1114691D03*
Y1127291D03*
X124880Y1117691D03*
X130380D03*
X124925Y1139891D03*
X124880Y1130291D03*
X130380D03*
X130434Y1144964D03*
X124474Y1142997D03*
X130380Y1155491D03*
X124880D03*
X124925Y1152491D03*
X124474Y1168197D03*
X130434Y1170164D03*
X124925Y1165091D03*
Y1177691D03*
X131000Y1180266D03*
X124765Y1180691D03*
X135757Y1221407D03*
X135448Y1229402D03*
Y1234921D03*
X126433Y1230407D03*
X129250Y1227650D03*
X137410Y103411D03*
X137804Y97667D03*
X148600Y90650D03*
X148350Y95236D03*
X138050Y111255D03*
Y114655D03*
X137569Y106561D03*
X138050Y128828D03*
Y125428D03*
X135429Y195176D03*
X134947Y202048D03*
X138547Y230117D03*
X134563Y238714D03*
X138664Y241699D03*
X148061Y378600D03*
X148692Y391001D03*
X148061Y382600D03*
X148692Y394401D03*
Y405174D03*
X140690Y401513D03*
Y398113D03*
X148692Y408574D03*
X138290Y412287D03*
X148692Y419347D03*
Y422747D03*
X138290Y415687D03*
Y426460D03*
X148692Y433521D03*
X138290Y429860D03*
X148692Y436921D03*
X138290Y440633D03*
X148176Y458711D03*
X138290Y444033D03*
X148940Y455921D03*
X145376Y458711D03*
X138290Y469387D03*
Y472787D03*
X147520Y463600D03*
X148692Y476499D03*
X138290Y483560D03*
X148692Y490673D03*
X138290Y486960D03*
X148692Y479899D03*
Y494073D03*
Y524033D03*
Y520633D03*
X138290Y516921D03*
Y513521D03*
Y531094D03*
X148692Y538206D03*
Y534806D03*
X138290Y527694D03*
X142024Y552466D03*
X147925Y603600D03*
Y619600D03*
Y623600D03*
X149469Y634190D03*
X152658Y645389D03*
X136862Y857244D03*
X147836Y988813D03*
X139836D03*
X151836D03*
X143836D03*
X142026Y1012354D03*
X136571Y1009354D03*
X136526Y1012354D03*
X136571Y1021954D03*
X142026Y1024954D03*
X136526D03*
X144640Y1039439D03*
X150952Y1040115D03*
X146595Y1053457D03*
X136432Y1224472D03*
X167191Y92874D03*
X153912Y90615D03*
X158283Y95236D03*
X158233Y99961D03*
X166240Y162368D03*
X157095Y210478D03*
Y207978D03*
Y215478D03*
Y212978D03*
X160424Y264180D03*
X162924D03*
X160349Y258880D03*
X164496Y309405D03*
X150703Y453682D03*
X159836Y988813D03*
X155836Y997860D03*
X160733Y1056594D03*
X153693Y1051037D03*
X160547Y1049283D03*
X160627Y1053561D03*
X160807Y1043955D03*
X166188Y1066551D03*
X163191Y1065313D03*
X159228Y1065613D03*
X165649Y1159350D03*
Y1151870D03*
X167147Y77393D03*
Y74793D03*
Y85193D03*
Y82593D03*
Y79993D03*
X175472Y98551D03*
X178367Y111223D03*
Y114623D03*
X179022Y103783D03*
X169218Y107649D03*
Y104249D03*
X178367Y128796D03*
Y125396D03*
X173784Y147540D03*
X177556Y141247D03*
X185023Y143740D03*
X182403Y148277D03*
X175940Y162793D03*
Y165393D03*
X168840Y162368D03*
X175940Y167993D03*
Y170493D03*
X178148Y181366D03*
X180943Y181009D03*
X174937Y181426D03*
X182864Y177616D03*
X183445Y172190D03*
X175145Y184221D03*
X177762Y184012D03*
X171623Y211695D03*
X182884Y213132D03*
X179181Y211359D03*
Y213859D03*
X174123Y211695D03*
X167551Y208213D03*
Y213213D03*
Y210713D03*
X171623Y208695D03*
X174423D03*
X167551Y215713D03*
X182884Y215632D03*
X177800Y265701D03*
X182887Y265896D03*
X174618Y267526D03*
Y270026D03*
X169318Y267526D03*
X172118D03*
Y270026D03*
X169318D03*
X179435Y281716D03*
X170215Y311671D03*
X175615Y550907D03*
X173115D03*
X175615Y553407D03*
X173115D03*
X174923Y545263D03*
Y541863D03*
X177385Y566929D03*
X171339Y572070D03*
X172686Y569928D03*
X175033Y570962D03*
X174776Y568475D03*
X177099Y569426D03*
X169389Y1155610D03*
X191568Y76587D03*
Y72615D03*
X193007Y100625D03*
X186026Y97475D03*
X185957Y106186D03*
X197380Y112083D03*
X188769Y118335D03*
Y121735D03*
Y132509D03*
Y135909D03*
X193586Y141247D03*
X198073Y143518D03*
X197173Y152373D03*
X201015Y183834D03*
X201125Y178560D03*
X186118Y168697D03*
X201188Y172665D03*
X187206Y191941D03*
X195260Y192490D03*
X200535Y190185D03*
X201305Y200864D03*
X189215Y206767D03*
X191715D03*
X194215D03*
X201394Y212455D03*
X201328Y207037D03*
X194345Y221708D03*
X198695Y221642D03*
X190460Y228221D03*
Y231021D03*
X191845Y221708D03*
X188760Y224421D03*
X189345Y221708D03*
X191011Y236189D03*
X193511D03*
X196011D03*
X190952Y248765D03*
X193452D03*
X195952D03*
X183128Y256303D03*
X187903Y266114D03*
X196449Y268195D03*
X193649D03*
X196449Y270695D03*
X193649D03*
X191149D03*
Y268195D03*
X185376Y281982D03*
X185328Y545528D03*
X194063Y577716D03*
X191125Y610400D03*
X203248Y55513D03*
X199473Y68581D03*
X205848Y60513D03*
X208645Y60369D03*
X199486Y80581D03*
X214389Y86012D03*
X203616Y88801D03*
X214389Y94374D03*
X206533Y94351D03*
X210482Y94279D03*
X209530Y86046D03*
X205976Y85731D03*
X209726Y116594D03*
X201669Y103621D03*
X215669Y110784D03*
X209726Y119594D03*
X210160Y124283D03*
X215226Y124879D03*
X208567Y161306D03*
X200323Y152562D03*
X205818Y157370D03*
X209902Y176665D03*
Y168665D03*
X202001Y186629D03*
X209902Y196665D03*
Y192665D03*
X210015Y186778D03*
X209934Y204864D03*
Y208864D03*
X214983Y218085D03*
X205575Y219379D03*
X206203Y228631D03*
X211691Y248371D03*
X200109Y265897D03*
X202609D03*
X212980Y390995D03*
X204675Y382109D03*
X212980Y405168D03*
Y394395D03*
X205680Y401482D03*
Y398082D03*
X212980Y408568D03*
Y419341D03*
Y422741D03*
X205680Y415655D03*
Y412255D03*
Y426428D03*
Y440602D03*
Y429828D03*
X212980Y433515D03*
Y436915D03*
X205680Y444002D03*
X212980Y469381D03*
Y472781D03*
X205680Y490641D03*
Y479868D03*
X212980Y483554D03*
X205680Y476468D03*
X212980Y486954D03*
X205680Y494041D03*
Y524002D03*
X212980Y516915D03*
Y513515D03*
X205680Y520602D03*
Y534775D03*
X212980Y527688D03*
X205680Y538175D03*
X212980Y531088D03*
X204674Y551683D03*
Y558917D03*
Y561420D03*
X200495Y577937D03*
X208500Y595500D03*
X203500Y606929D03*
X208000Y604567D03*
X203460Y618400D03*
X203741Y612592D03*
X209158Y610072D03*
X209094Y616317D03*
X208540Y621591D03*
X205941Y668934D03*
X201115Y695581D03*
X203046Y693716D03*
X213969Y1447453D03*
Y1461853D03*
Y1458453D03*
Y1450853D03*
X231312Y97667D03*
X221695Y116594D03*
X226968Y102495D03*
X220669Y110784D03*
X221695Y119594D03*
X225229Y125107D03*
X220248Y124663D03*
X226702Y142862D03*
X227743Y148717D03*
X221592Y138838D03*
X230291Y195176D03*
X230372Y210509D03*
X224362Y226320D03*
X224296Y216970D03*
Y219470D03*
Y221970D03*
X221583Y216385D03*
X217783Y218085D03*
X232064Y230556D03*
X227323Y228646D03*
X231049Y242078D03*
X226280Y232971D03*
X220310Y249108D03*
X222930Y244571D03*
X233417Y253198D03*
X230842Y313888D03*
X233258Y359186D03*
X228267Y396718D03*
X221375Y455024D03*
X220349Y465622D03*
X225500Y530000D03*
X225000Y540500D03*
X224000Y547075D03*
X224200Y549800D03*
X223500Y568000D03*
X224104Y562800D03*
X224040Y558800D03*
X221693Y594982D03*
X222289Y590895D03*
X220333Y617930D03*
X220255Y629749D03*
X217906Y1430452D03*
Y1427052D03*
X219525Y1440028D03*
X216125D03*
X227249Y1447453D03*
Y1450853D03*
Y1458453D03*
Y1461853D03*
X224780Y1478149D03*
X217985Y1483055D03*
X225765Y1471985D03*
X233313Y1476699D03*
X221899Y1488800D03*
X218021Y1494724D03*
X222843Y1498442D03*
X217614Y1489671D03*
X233180Y1486442D03*
X233166Y1491454D03*
X226135Y1502442D03*
X230758Y1505046D03*
X226971Y1514578D03*
X227552Y1530675D03*
X232622Y1531104D03*
X226971Y1522578D03*
X219981Y1530797D03*
X223322Y1518578D03*
X222119Y1539941D03*
X227882Y1540816D03*
X233753Y1539752D03*
X239772Y103411D03*
X240166Y97667D03*
X235562Y95111D03*
X240412Y114655D03*
Y111255D03*
X239931Y106561D03*
X233112Y132515D03*
Y121742D03*
X240412Y125428D03*
X233112Y118342D03*
X240412Y128828D03*
X233112Y135915D03*
X233843Y143762D03*
X232791Y195176D03*
X235291D03*
X237309Y199248D03*
X234309D03*
X237791Y195176D03*
X237309Y202048D03*
X232872Y210509D03*
X234645Y206806D03*
X232145D03*
X234309Y201748D03*
X240909Y230117D03*
X236319Y227824D03*
X236925Y238714D03*
X236406Y246874D03*
X238626Y244297D03*
X234986Y336161D03*
X236264Y342494D03*
X245362Y546712D03*
Y542712D03*
X247536Y602689D03*
X247278Y618288D03*
X243278D03*
X240194Y643113D03*
X242102Y656321D03*
X250102D03*
X246102D03*
X245000Y678462D03*
X244267Y696911D03*
X235790Y754332D03*
X241204Y814841D03*
X237591Y815266D03*
X248556Y824003D03*
X246311Y819000D03*
X238400Y836900D03*
X234976Y1481676D03*
X243535Y1511473D03*
X245500Y1517033D03*
X237633Y1511909D03*
X244600Y1531700D03*
X240808Y1519942D03*
X235687Y1522578D03*
X237580Y1528604D03*
X245937Y1524237D03*
X239949Y1541327D03*
X244912Y1539389D03*
X250962Y90650D03*
X256274Y90615D03*
X260595Y99961D03*
X260645Y95236D03*
X250712D03*
X259457Y210478D03*
Y207978D03*
Y215478D03*
Y212978D03*
X262786Y264180D03*
X262711Y258880D03*
X257993Y307994D03*
X256475Y422088D03*
X252695Y442956D03*
X254512Y438323D03*
X261965Y458455D03*
X250336Y456386D03*
X254678Y445873D03*
X263301Y444232D03*
X262526Y451108D03*
X249125Y465874D03*
X264005Y467337D03*
Y470737D03*
X256705Y474424D03*
X264005Y484910D03*
X256705Y488597D03*
X264005Y481510D03*
X256705Y477824D03*
Y491997D03*
X264005Y514871D03*
X256705Y518558D03*
X264005Y511471D03*
X256705Y521958D03*
Y532731D03*
Y536131D03*
X264005Y525644D03*
Y529044D03*
Y561510D03*
X256705Y571997D03*
Y568597D03*
X264005Y564910D03*
X256705Y586171D03*
X264005Y575684D03*
Y579084D03*
X256705Y582771D03*
X264005Y589857D03*
X256705Y600344D03*
X264005Y593257D03*
Y604030D03*
X256705Y596944D03*
Y611117D03*
Y614517D03*
X264005Y607430D03*
X252688Y636364D03*
X248690Y678519D03*
X248090Y691114D03*
X254634Y698241D03*
X248506Y812042D03*
X256303Y812254D03*
X250700Y819900D03*
X254058Y819851D03*
X255289Y824340D03*
X252305Y831018D03*
X252100Y836800D03*
X250876Y1532782D03*
X255909Y1542043D03*
X250790Y1539759D03*
X269509Y77393D03*
Y74793D03*
Y85193D03*
Y82593D03*
Y79993D03*
X277834Y98551D03*
X269553Y92874D03*
X271580Y107649D03*
Y104249D03*
X276146Y147540D03*
X279918Y141247D03*
X268602Y162368D03*
X271202D03*
X278302Y162793D03*
Y165393D03*
Y167993D03*
Y170493D03*
X277299Y181426D03*
X280124Y184012D03*
X277507Y184221D03*
X269913Y210713D03*
X273985Y208695D03*
X276785D03*
X273985Y211695D03*
X276485D03*
X269913Y208213D03*
Y213213D03*
Y215713D03*
X265286Y264180D03*
X280162Y265701D03*
X276980Y267526D03*
Y270026D03*
X271680Y267526D03*
X274480D03*
Y270026D03*
X271680D03*
X281797Y281716D03*
X277575Y395084D03*
X274425Y381500D03*
X278784Y435158D03*
X278529Y440489D03*
X274949Y442606D03*
X278827Y444841D03*
X282230Y458572D03*
X265011Y453881D03*
X280220Y448493D03*
X274866Y446606D03*
X265011Y446595D03*
X275873Y463479D03*
X276344Y467367D03*
X274096Y820725D03*
X274697Y830951D03*
X275123Y847874D03*
X269700Y853100D03*
X275400Y864400D03*
X278400Y890839D03*
X275400Y899400D03*
X279261Y926339D03*
X278739Y936439D03*
X289797Y36735D03*
X290113Y23188D03*
X284666Y34068D03*
X289631Y28281D03*
X293930Y76587D03*
Y72615D03*
X295369Y100625D03*
X288388Y97475D03*
X280729Y111223D03*
Y114623D03*
X281384Y103783D03*
X288319Y106186D03*
X280729Y125396D03*
X291131Y121735D03*
X280729Y128796D03*
X291131Y118335D03*
Y132509D03*
Y135909D03*
X295948Y141247D03*
X287385Y143740D03*
X284765Y148277D03*
X285807Y172190D03*
X280510Y181366D03*
X283305Y181009D03*
X288480Y168697D03*
X285226Y177616D03*
X289568Y191941D03*
X297622Y192490D03*
X291577Y206767D03*
X294077D03*
X296577D03*
X285246Y213132D03*
X281543Y211359D03*
Y213859D03*
X296707Y221708D03*
X292822Y228221D03*
Y231021D03*
X294207Y221708D03*
X291122Y224421D03*
X291707Y221708D03*
X285246Y215632D03*
X293373Y236189D03*
X295873D03*
X293314Y248765D03*
X295814D03*
X285490Y256303D03*
X290265Y266114D03*
X285249Y265896D03*
X296011Y270695D03*
X293511D03*
Y268195D03*
X296011D03*
X287738Y281982D03*
X286940Y315039D03*
X297719Y339559D03*
X291396Y350223D03*
X292520Y384410D03*
X292358Y393858D03*
X298000Y391496D03*
X295699Y382047D03*
X296000Y403500D03*
X298000Y409000D03*
X294000Y398583D03*
X295253Y440869D03*
Y438269D03*
X292453D03*
Y440869D03*
Y435669D03*
Y430469D03*
Y433069D03*
X295253D03*
Y430469D03*
Y435669D03*
X293307Y451677D03*
X295807D03*
X293307Y454177D03*
X295807D03*
X295011Y460218D03*
Y463618D03*
X281980Y953926D03*
X312256Y37543D03*
X305610Y55513D03*
X301835Y68581D03*
X310817Y60393D03*
X307916Y60529D03*
X301848Y80581D03*
X305978Y88801D03*
X312844Y94279D03*
X308895Y94351D03*
X308338Y85731D03*
X311892Y86046D03*
X312088Y116594D03*
X299742Y112083D03*
X304031Y103621D03*
X312088Y119594D03*
X312522Y124283D03*
X300435Y143518D03*
X299535Y152373D03*
X310929Y161306D03*
X302685Y152562D03*
X308180Y157370D03*
X312264Y176665D03*
Y168665D03*
X303377Y183834D03*
X303550Y172665D03*
X303487Y178560D03*
X304363Y186629D03*
X302897Y190185D03*
X312264Y196665D03*
Y192665D03*
X303667Y200864D03*
X312377Y186778D03*
X300814Y192859D03*
X312296Y204864D03*
Y208864D03*
X303756Y212455D03*
X303690Y207037D03*
X301057Y221642D03*
X307937Y219379D03*
X308565Y228631D03*
X298373Y236189D03*
X298314Y248765D03*
X302471Y265897D03*
X304971D03*
X298811Y270695D03*
Y268195D03*
X315079Y314890D03*
X312263Y324518D03*
X301943Y328867D03*
X308952Y356875D03*
X312316Y356747D03*
X299000Y377912D03*
Y386500D03*
X299088Y397912D03*
X322847Y19806D03*
X321840Y14408D03*
X322113Y26187D03*
X316751Y86012D03*
Y94374D03*
X324057Y116594D03*
X318031Y110784D03*
X323031D03*
X324057Y119594D03*
X327591Y125107D03*
X322610Y124663D03*
X317588Y124879D03*
X329064Y142862D03*
X330105Y148717D03*
X323954Y138838D03*
X317345Y218085D03*
X320145D03*
X323945Y216385D03*
X326658Y216970D03*
Y219470D03*
X326724Y226320D03*
X326658Y221970D03*
X329685Y228646D03*
X328642Y232971D03*
X322672Y249108D03*
X325292Y244571D03*
X314053Y248371D03*
X327032Y303962D03*
X314855Y311740D03*
X318508Y324322D03*
X315944Y332584D03*
X316067Y347937D03*
X321416Y348015D03*
X317333Y353470D03*
X318500Y356519D03*
X315310Y356712D03*
X320993Y467306D03*
Y470706D03*
Y481479D03*
Y484879D03*
Y514839D03*
Y511439D03*
Y525613D03*
Y529013D03*
X318660Y539315D03*
X320785Y553287D03*
X327456Y550065D03*
X320993Y564879D03*
Y561479D03*
Y575652D03*
Y579052D03*
Y603999D03*
Y593225D03*
Y589825D03*
Y607399D03*
X321119Y622912D03*
X330905Y15806D03*
Y19806D03*
Y27806D03*
X333674Y97667D03*
X342134Y103411D03*
X342528Y97667D03*
X337924Y95111D03*
X342774Y111255D03*
Y114655D03*
X329330Y102495D03*
X342293Y106561D03*
X335474Y118342D03*
Y132515D03*
X342774Y125428D03*
X335474Y121742D03*
X342774Y128828D03*
X335474Y135915D03*
X336205Y143762D03*
X335153Y195176D03*
X332653D03*
X336671Y199248D03*
X337653Y195176D03*
X340153D03*
X339671Y199248D03*
X336671Y201748D03*
X334507Y206806D03*
X337007D03*
X335234Y210509D03*
X332734D03*
X339671Y202048D03*
X343271Y230117D03*
X338681Y227824D03*
X334426Y230556D03*
X339287Y238714D03*
X333411Y242078D03*
X338768Y246874D03*
X340988Y244297D03*
X332635Y256394D03*
X347058Y399918D03*
X339072Y416888D03*
Y419488D03*
Y422088D03*
X345050Y454334D03*
X331395Y474418D03*
Y488591D03*
Y477818D03*
Y491991D03*
Y518552D03*
Y521952D03*
Y536125D03*
Y532725D03*
X337078Y551381D03*
X335399Y544718D03*
X331395Y568591D03*
Y571991D03*
Y586165D03*
Y582765D03*
Y600338D03*
Y596938D03*
Y611111D03*
Y614511D03*
X333985Y1017945D03*
X341077Y1018056D03*
X339251Y1138130D03*
X336755Y1143489D03*
X340500Y1147500D03*
X335190Y1173065D03*
X341266Y1171956D03*
X330800Y1174500D03*
X343121Y1188412D03*
X342009Y1176100D03*
X339776Y1187962D03*
X335502Y1188222D03*
X339540Y1196894D03*
X358636Y90615D03*
X353324Y90650D03*
X362957Y99961D03*
X353074Y95236D03*
X359376Y290592D03*
X348351Y319372D03*
X348806Y315427D03*
X351132Y322202D03*
X349120Y336100D03*
X351136Y372334D03*
X350486Y377173D03*
X358491D03*
X347591Y391533D03*
X359486Y385123D03*
X349311Y385644D03*
X354486Y385123D03*
X357655Y405889D03*
Y408489D03*
X358248Y403300D03*
X353894Y406060D03*
X354155Y421489D03*
Y418889D03*
Y416289D03*
X350163Y412106D03*
X357655Y413689D03*
Y416289D03*
Y421489D03*
Y418889D03*
Y424089D03*
Y411089D03*
X358042Y432718D03*
X357655Y426689D03*
X358042Y435518D03*
X358754Y450091D03*
X356241Y447001D03*
X359241D03*
X353320Y454214D03*
X353663Y449045D03*
X353367Y459330D03*
X358754Y462060D03*
X353670Y473571D03*
Y481071D03*
Y478571D03*
Y476071D03*
X360242Y477053D03*
X357742D03*
X358207Y836462D03*
X346366Y1134729D03*
X361621D03*
X349748D03*
X357748D03*
X353748D03*
X352545Y1142666D03*
X360877Y1157404D03*
X354420Y1157544D03*
X352931Y1167768D03*
X357950D03*
X357057Y1179542D03*
X357796Y1188058D03*
X357083Y1185205D03*
X361792Y1187310D03*
X348432Y1187215D03*
X348125Y1180175D03*
X358368Y1201043D03*
X354398D03*
X350402D03*
X346387Y1199256D03*
X360523Y1192282D03*
X349276Y1217228D03*
X351940Y1219895D03*
X362332Y1230265D03*
X355215Y1223170D03*
X360273Y1228226D03*
X358062Y1226016D03*
X371871Y85193D03*
Y82593D03*
Y79993D03*
Y77393D03*
Y74793D03*
X371915Y92874D03*
X363007Y95236D03*
X373942Y104249D03*
Y107649D03*
X370964Y162368D03*
X373564D03*
X372275Y208213D03*
X379147Y208695D03*
X376347D03*
Y211695D03*
X372275Y210713D03*
Y213213D03*
X361819Y207978D03*
Y212978D03*
Y215478D03*
Y210478D03*
X372275Y215713D03*
X367648Y264180D03*
X365148D03*
X365073Y258880D03*
X374042Y270026D03*
X376842D03*
X374042Y267526D03*
X376842D03*
X371417Y353820D03*
X365559Y354300D03*
X377237Y371060D03*
X373264Y379429D03*
X378875Y379088D03*
X366526Y377173D03*
X370486D03*
X362486Y385123D03*
X366486D03*
X370160Y391569D03*
X368587Y401066D03*
X378927Y406739D03*
X367919Y439318D03*
X375919Y442118D03*
Y439318D03*
X367919Y442118D03*
X361754Y450091D03*
X367564Y456034D03*
Y461034D03*
X373546Y470001D03*
X376046D03*
X361754Y462060D03*
X373971Y489036D03*
X371832Y485580D03*
X374332D03*
X376832D03*
X366420Y479986D03*
Y477486D03*
X363686Y478668D03*
Y476168D03*
X376207Y492836D03*
Y495636D03*
X376881Y518564D03*
X363015Y710365D03*
X365887Y710329D03*
X372400Y746300D03*
X372300Y750000D03*
X373500Y767300D03*
X376300D03*
X370415Y766108D03*
X373703Y782555D03*
X365850Y773950D03*
X371436Y791188D03*
X365691Y815127D03*
X371507Y815303D03*
X362042Y814772D03*
X368067Y925136D03*
X370214Y943812D03*
X368626Y931346D03*
X368964Y937738D03*
X372858Y935136D03*
X366761Y934550D03*
X363893Y946863D03*
X379928Y949774D03*
X379245Y956643D03*
X378875Y961862D03*
X370214Y947812D03*
X370101Y953699D03*
X370214Y963812D03*
Y971812D03*
X378928Y967812D03*
X372501Y1123695D03*
X365748Y1134325D03*
X368657Y1150087D03*
X366133Y1170767D03*
X366429Y1185238D03*
X366222Y1180235D03*
X362402Y1201039D03*
X366402Y1200969D03*
X366521Y1208993D03*
X370202Y1314764D03*
Y1311364D03*
X383612Y33768D03*
X388612Y31168D03*
X387948Y27288D03*
X380196Y98551D03*
X390750Y97475D03*
X383091Y111223D03*
Y114623D03*
X383746Y103783D03*
X390681Y106186D03*
X393493Y118335D03*
X383091Y125396D03*
Y128796D03*
X393493Y132509D03*
Y121735D03*
Y135909D03*
X380664Y165393D03*
Y162793D03*
Y167993D03*
Y170493D03*
X387588Y177616D03*
X382872Y181366D03*
X379661Y181426D03*
X385667Y181009D03*
X390842Y168697D03*
X388169Y172190D03*
X391930Y191941D03*
X382486Y184012D03*
X379869Y184221D03*
X393939Y206767D03*
X383905Y211359D03*
X387608Y213132D03*
X378847Y211695D03*
X383905Y213859D03*
X394069Y221708D03*
X393484Y224421D03*
X387608Y215632D03*
X387852Y256303D03*
X387611Y265896D03*
X382524Y265701D03*
X392627Y266114D03*
X379342Y270026D03*
Y267526D03*
X384159Y281716D03*
X390100Y281982D03*
X391737Y377581D03*
X384173Y379028D03*
X381237Y371076D03*
X394237Y379591D03*
X391940Y383817D03*
Y388817D03*
Y386317D03*
X385864Y398278D03*
X383364D03*
X378927Y409539D03*
X381927D03*
Y407039D03*
X381591Y401981D03*
X384091D03*
X378210Y424067D03*
X380710D03*
X385710D03*
X383210D03*
X378445Y413611D03*
X380945D03*
X385945D03*
X383445D03*
X385584Y438293D03*
Y441093D03*
Y443893D03*
X393646Y474382D03*
X385634Y472020D03*
X393662Y470382D03*
X385694Y477318D03*
X385293Y466409D03*
X387141Y484882D03*
X385131Y487382D03*
X391470Y732865D03*
X380963Y731000D03*
X381875Y740341D03*
X379800Y769200D03*
X380331Y782627D03*
X380607Y786932D03*
X392415Y792725D03*
X389015D03*
X387958Y813700D03*
X381631Y814147D03*
X384666Y814103D03*
X383391Y804000D03*
X386589Y864408D03*
X383462Y860535D03*
X392584Y875845D03*
X382675Y870151D03*
X391614Y930676D03*
X384856Y947987D03*
X378119Y953696D03*
X392910Y948536D03*
X393998Y971780D03*
X378790Y1001083D03*
X380280Y1006071D03*
X383710Y1007283D03*
X382465Y1012430D03*
X378410Y1131573D03*
X380261Y1129692D03*
X385091Y1297453D03*
Y1300853D03*
X386415Y1321645D03*
X391691Y1326715D03*
X392234Y1369579D03*
Y1364501D03*
X391757Y1383480D03*
X391852Y1389931D03*
X393951Y1447455D03*
X381900Y1544800D03*
X389700Y1536900D03*
X391740Y1545629D03*
Y1540529D03*
X382017Y1559700D03*
X395296Y1561024D03*
X391740Y1550729D03*
Y1555829D03*
X410789Y22627D03*
X408680Y37530D03*
X396680Y37543D03*
X400714Y45448D03*
X404686D03*
X397731Y100625D03*
X402104Y112083D03*
X406393Y103621D03*
X405912Y172665D03*
X405739Y183834D03*
X405849Y178560D03*
X406725Y186629D03*
X399984Y192490D03*
X405259Y190185D03*
X406029Y200864D03*
X395942Y192300D03*
X398939Y206767D03*
X396439D03*
X406118Y212455D03*
X406052Y207037D03*
X395184Y228221D03*
X399069Y221708D03*
X396569D03*
X403419Y221642D03*
X395184Y231021D03*
X410299Y219379D03*
X410927Y228631D03*
X400735Y236189D03*
X398235D03*
X395735D03*
X400676Y248765D03*
X398176D03*
X395676D03*
X407333Y265897D03*
X404833D03*
X401173Y268195D03*
Y270695D03*
X398373Y268195D03*
X395873D03*
Y270695D03*
X398373D03*
X405843Y315158D03*
X403343D03*
X394883Y341777D03*
Y338377D03*
X410086Y336795D03*
X409655Y331589D03*
X410688Y344736D03*
X400993Y331589D03*
Y335589D03*
X400728Y353152D03*
X411007Y356743D03*
X406421Y387151D03*
Y382151D03*
Y384651D03*
X398453Y387702D03*
X401253D03*
X394653Y389402D03*
X395577Y438293D03*
Y441093D03*
Y443893D03*
X397315Y471560D03*
X405801Y475560D03*
X405301Y467560D03*
X397315Y475560D03*
X406200Y741300D03*
X397223Y796792D03*
X400023D03*
X397900Y789000D03*
X407000Y784700D03*
X404468Y864407D03*
X396306Y864409D03*
X406770Y869767D03*
X405466Y881299D03*
X397431Y870654D03*
X401108Y878487D03*
X401121Y929686D03*
X409121D03*
X401121Y932186D03*
X409121D03*
X405179Y959051D03*
X404971Y956256D03*
X402354Y956465D03*
X401968Y959111D03*
X399173Y959468D03*
X397252Y962861D03*
X404176Y977684D03*
Y975084D03*
Y969984D03*
Y972484D03*
X396671Y968287D03*
X406954Y982970D03*
X409554D03*
X404354D03*
X407547Y1058097D03*
X410047D03*
X405047D03*
X407547Y1060697D03*
X410047D03*
X405047D03*
X408989Y1082501D03*
X409015Y1087705D03*
Y1085205D03*
X408847Y1090956D03*
Y1093956D03*
X406895Y1107997D03*
X402695D03*
Y1110897D03*
X407780Y1113648D03*
X409231Y1118801D03*
X406995Y1110597D03*
X404895Y1112397D03*
X404795Y1109397D03*
X402695Y1113797D03*
X408961Y1162384D03*
Y1164884D03*
Y1167384D03*
Y1169884D03*
Y1172384D03*
X403263Y1160834D03*
X408961Y1174884D03*
X406319Y1186709D03*
Y1184209D03*
Y1181709D03*
Y1179209D03*
X404004Y1192621D03*
Y1190121D03*
X397063Y1221428D03*
X401063D03*
X405063D03*
X409063D03*
X397063Y1233428D03*
Y1229428D03*
Y1225428D03*
X401063Y1237428D03*
Y1233428D03*
Y1229428D03*
Y1225428D03*
X405063Y1237428D03*
Y1233428D03*
Y1229428D03*
Y1225428D03*
X409063Y1237428D03*
Y1233428D03*
Y1229428D03*
Y1225428D03*
X401063Y1241428D03*
X405063Y1245428D03*
Y1241428D03*
X409063Y1245428D03*
Y1241428D03*
X404324Y1271889D03*
Y1275889D03*
X407767Y1292198D03*
X403678Y1295426D03*
X398584Y1313443D03*
X401011Y1307258D03*
X402967Y1319815D03*
X409220Y1315516D03*
X404583Y1316131D03*
X404921Y1321819D03*
X408787Y1321795D03*
X399959Y1352153D03*
X408159Y1349072D03*
X404759D03*
X395112Y1395690D03*
X398340Y1399779D03*
X395770Y1389817D03*
X410172Y1402446D03*
X402489Y1417275D03*
X405889D03*
X407970Y1449751D03*
X404500Y1452500D03*
X395888Y1450022D03*
X395199Y1482223D03*
X395380Y1485778D03*
X397266Y1514647D03*
X398747Y1500959D03*
X395370Y1501022D03*
X397266Y1518047D03*
X408964Y1531149D03*
X394391Y1537786D03*
Y1535286D03*
X399373Y1555855D03*
X405496Y1561024D03*
X400396D03*
X410596D03*
X397461Y1569560D03*
X401461D03*
X416900Y33400D03*
X422473Y22627D03*
X422450Y30483D03*
X422378Y26534D03*
X414145Y27486D03*
X413904Y32569D03*
X426147Y147540D03*
X414626Y176665D03*
Y168665D03*
Y196665D03*
Y192665D03*
X414739Y186778D03*
X414658Y204864D03*
Y208864D03*
X423651Y307470D03*
X419177Y304470D03*
X415777D03*
X422988Y323627D03*
X415129Y325181D03*
X412671Y333418D03*
X412812Y330617D03*
X426830Y359026D03*
X426138Y355079D03*
X416574Y357528D03*
X421413Y359053D03*
X412318Y367903D03*
X420422Y367859D03*
X418997Y382210D03*
Y384710D03*
Y387210D03*
X422215Y424939D03*
Y427439D03*
X414924Y435321D03*
Y438121D03*
X412124Y435321D03*
Y438121D03*
X414924Y440921D03*
X412124D03*
X414924Y443721D03*
X412124D03*
X426647Y452987D03*
X421267Y452799D03*
X414910Y448931D03*
X415433Y459170D03*
X425673Y461607D03*
X424876Y471334D03*
X418801Y474513D03*
X414275Y492469D03*
X424731Y492704D03*
X414275Y497469D03*
Y499969D03*
X427693Y498943D03*
X424731Y497704D03*
Y495204D03*
Y500204D03*
X414275Y494969D03*
X419340Y549990D03*
X419140Y547390D03*
Y544790D03*
X419340Y552590D03*
Y555190D03*
X423963Y625778D03*
X426607Y712360D03*
Y709760D03*
X424993Y728291D03*
X423700Y795500D03*
X426300Y797400D03*
X421200Y786400D03*
X411267Y829193D03*
Y831693D03*
X416267D03*
X413767D03*
Y829193D03*
X416267D03*
X425062Y883981D03*
X417121Y929686D03*
X425121D03*
X417121Y932186D03*
X425121D03*
X411960Y962261D03*
X414560D03*
X417160D03*
X411276Y978109D03*
X416476D03*
X413876D03*
X415047Y1058097D03*
X412547D03*
X415047Y1060697D03*
X412547D03*
X411989Y1082501D03*
X412015Y1085205D03*
X414989Y1082501D03*
X415015Y1085205D03*
Y1088205D03*
X412015D03*
X412297Y1091227D03*
X425060Y1101917D03*
X420782Y1105552D03*
X423340Y1104335D03*
X424995Y1106897D03*
X416988Y1104792D03*
X418495Y1106867D03*
X414580Y1113648D03*
X412080D03*
X411461Y1162384D03*
Y1164884D03*
Y1167384D03*
Y1169884D03*
Y1172384D03*
X420619Y1179421D03*
Y1181921D03*
Y1184421D03*
Y1186921D03*
X411461Y1174884D03*
X422934Y1192621D03*
Y1190121D03*
X417469Y1192621D03*
Y1190121D03*
X413063Y1221428D03*
X417063D03*
X421063D03*
X425063D03*
X413063Y1237428D03*
Y1233428D03*
Y1229428D03*
Y1225428D03*
X417063Y1237428D03*
Y1233428D03*
Y1229428D03*
Y1225428D03*
X421063Y1237428D03*
Y1233428D03*
Y1229428D03*
Y1225428D03*
X425063Y1237428D03*
Y1233428D03*
Y1229428D03*
Y1225428D03*
X413063Y1245428D03*
Y1241428D03*
X417063Y1245428D03*
Y1241428D03*
X421063Y1245428D03*
Y1241428D03*
X425063Y1245428D03*
Y1241428D03*
X425702Y1257160D03*
X422702Y1260160D03*
Y1257160D03*
X425702Y1260160D03*
X419702Y1257160D03*
Y1260160D03*
X413526Y1288938D03*
X419977Y1288843D03*
X413640Y1292856D03*
X419545Y1317722D03*
X413127Y1318011D03*
X425283Y1364023D03*
X417305Y1359169D03*
X425855Y1360495D03*
X425912Y1357141D03*
X416029Y1371572D03*
X420636Y1383912D03*
X418610Y1371590D03*
X423400Y1394500D03*
X423200Y1397500D03*
X418430Y1394237D03*
X422729Y1400490D03*
X420925Y1390330D03*
X419045Y1398874D03*
X421300Y1415400D03*
X419100Y1402200D03*
X421200Y1417900D03*
X411000Y1463500D03*
Y1460500D03*
Y1457500D03*
Y1454500D03*
Y1451000D03*
X413934Y1477101D03*
X417334D03*
X415202Y1496118D03*
Y1499518D03*
X417153Y1516886D03*
X413753D03*
X419619Y1539978D03*
X421454Y1544625D03*
X422539Y1534361D03*
X426701Y1541947D03*
X418151Y1552470D03*
X417461Y1569584D03*
X429919Y141247D03*
X437386Y143740D03*
X434766Y148277D03*
X431525Y304470D03*
X434925D03*
X427051Y307470D03*
X441296Y325061D03*
X436666Y322583D03*
X427713Y321965D03*
X430361Y323187D03*
X443424Y332988D03*
X440538Y355372D03*
X428420Y353578D03*
X435886Y353867D03*
X431524Y370309D03*
X434924D03*
X428637Y408104D03*
X431437D03*
X434237D03*
X428354Y420375D03*
X431154D03*
X433954D03*
X438098Y442114D03*
X437835Y435101D03*
X432270Y431112D03*
X432440Y440101D03*
X432075Y452718D03*
X438086Y452601D03*
X438078Y447121D03*
X433673Y461607D03*
X429673D03*
X435789Y501525D03*
X427568Y502003D03*
X435831Y498923D03*
X438644Y500461D03*
X428740Y549990D03*
X442804Y546990D03*
Y544390D03*
X428740Y546990D03*
Y544390D03*
Y555190D03*
Y552590D03*
X431384D03*
Y555190D03*
Y544390D03*
Y546990D03*
Y549990D03*
X443144Y628667D03*
X441162Y638313D03*
X439290Y712399D03*
X436790D03*
X439290Y709799D03*
X436790D03*
X434290Y712399D03*
Y709799D03*
X429290D03*
X431790Y712399D03*
X429290D03*
X431790Y709799D03*
X429253Y759847D03*
X432303Y785067D03*
X434100Y797400D03*
X430600D03*
X443091Y1026266D03*
X432678Y1016186D03*
X429878D03*
X427078D03*
X427052Y1019384D03*
X429852D03*
X432652D03*
X433378Y1091816D03*
Y1089316D03*
X430878Y1084316D03*
Y1086816D03*
X433378D03*
Y1084316D03*
X436244Y1090288D03*
X433378Y1081816D03*
X430878D03*
X429677Y1106955D03*
X439023Y1107997D03*
X436244Y1093088D03*
X434823Y1107997D03*
X431476Y1115896D03*
X427810Y1110092D03*
X439908Y1113648D03*
X441359Y1116101D03*
Y1118801D03*
X439123Y1110597D03*
X434823Y1113797D03*
Y1110897D03*
X437023Y1112397D03*
X436923Y1109397D03*
X431476Y1118396D03*
X429348Y1129092D03*
X432838Y1128821D03*
X436789Y1167384D03*
Y1164884D03*
Y1162384D03*
Y1172384D03*
Y1169884D03*
X439289Y1167384D03*
Y1164884D03*
Y1162384D03*
X427231D03*
X429731D03*
Y1164884D03*
Y1167384D03*
Y1169884D03*
Y1172384D03*
X427231D03*
Y1169884D03*
Y1167384D03*
Y1164884D03*
X439289Y1172384D03*
Y1169884D03*
X437132Y1158266D03*
X433249Y1186709D03*
Y1184209D03*
Y1181709D03*
Y1179209D03*
X429731Y1174884D03*
X427231D03*
X436789D03*
X439289D03*
X430934Y1190121D03*
Y1192621D03*
X429063Y1221428D03*
X433063D03*
X429063Y1237428D03*
Y1233428D03*
Y1229428D03*
Y1225428D03*
X433063Y1237428D03*
Y1233428D03*
Y1229428D03*
Y1225428D03*
X429063Y1245428D03*
Y1241428D03*
X433063Y1245428D03*
Y1241428D03*
X440702Y1260160D03*
Y1257160D03*
X437702Y1260160D03*
Y1257160D03*
X428702D03*
X431702Y1260160D03*
Y1257160D03*
X434702Y1260160D03*
Y1257160D03*
X428702Y1260160D03*
X434424Y1286274D03*
X430527Y1289198D03*
X440906D03*
X431867Y1315696D03*
X431885Y1313115D03*
X439434Y1322369D03*
X429530Y1325051D03*
X445949Y141247D03*
X450436Y143518D03*
X449536Y152373D03*
X452686Y152562D03*
X458181Y157370D03*
X443508Y337713D03*
X446566Y337917D03*
X443480Y344014D03*
X450852Y372054D03*
X455885Y367702D03*
X448391Y382641D03*
X448323Y379643D03*
X451144Y468809D03*
X459414Y468689D03*
X459757Y463520D03*
X459461Y473805D03*
X459929Y491669D03*
X450942Y506449D03*
X448442D03*
X445942D03*
X460537Y501905D03*
X459952Y496842D03*
X459645Y509486D03*
X446025Y511512D03*
X448525D03*
X446025Y519699D03*
X448525D03*
X452404Y549790D03*
X443004Y549890D03*
X452404Y546990D03*
Y544390D03*
X443004Y555090D03*
X452404Y552390D03*
Y554990D03*
X443004Y552490D03*
X455009Y554912D03*
Y552312D03*
Y544312D03*
Y546912D03*
Y549712D03*
X447279Y637031D03*
X447921Y630789D03*
X453552Y631779D03*
X446987Y643360D03*
X456469Y638302D03*
X460498Y870334D03*
X458120Y974701D03*
X451460Y974695D03*
X450591Y1004766D03*
X453270Y1003763D03*
X459360Y1012325D03*
X443591Y1019766D03*
X459885Y1018860D03*
X451140Y1021793D03*
X447091Y1019766D03*
X450875Y1028416D03*
X443091Y1034266D03*
X452091Y1039880D03*
X459700Y1032266D03*
X455468Y1104335D03*
X457188Y1101917D03*
X452910Y1105552D03*
X457123Y1106897D03*
X449116Y1104792D03*
X450623Y1106867D03*
X444208Y1113648D03*
X446708D03*
X457559Y1169884D03*
Y1167384D03*
Y1164884D03*
Y1162384D03*
X455059D03*
Y1164884D03*
Y1167384D03*
Y1169884D03*
Y1172384D03*
X457559D03*
X455059Y1174884D03*
X457559D03*
X447549Y1179421D03*
Y1181921D03*
Y1184421D03*
Y1186921D03*
X449864Y1190121D03*
Y1192621D03*
X449702Y1260160D03*
Y1257160D03*
X443702Y1260160D03*
X446702D03*
Y1257160D03*
X443702D03*
X451304Y1297045D03*
X454385Y1301845D03*
Y1305245D03*
X444288Y1314391D03*
X462089Y116594D03*
X474058D03*
X473032Y110784D03*
X468032D03*
X462089Y119594D03*
X474058D03*
X477592Y125107D03*
X462523Y124283D03*
X467589Y124879D03*
X472611Y124663D03*
X473955Y138838D03*
X460930Y161306D03*
X467346Y218085D03*
X470146D03*
X473946Y216385D03*
X475293Y244571D03*
X472673Y249108D03*
X464054Y248371D03*
X460950Y328185D03*
Y324785D03*
X463950Y332659D03*
Y336059D03*
X460950Y343933D03*
Y340533D03*
X472810Y347995D03*
X472913Y360089D03*
X472608Y352495D03*
X467335Y359944D03*
X463950Y351807D03*
Y348407D03*
X472913Y369089D03*
Y373589D03*
X469530Y366754D03*
X472913Y387089D03*
Y391589D03*
Y382589D03*
Y378089D03*
X470796Y394592D03*
X464848Y464566D03*
X467848D03*
X465126Y460435D03*
X462126D03*
X473658Y470509D03*
Y475509D03*
X467848Y476535D03*
X464848D03*
X468558Y495669D03*
Y499669D03*
Y516609D03*
X464199Y510184D03*
X468850Y545586D03*
X469300Y799500D03*
X459245Y807152D03*
X473654Y821234D03*
X472399Y839566D03*
X463404Y846870D03*
X465492Y861970D03*
X471726Y883705D03*
X474540Y927341D03*
X471110Y921577D03*
X471876Y937236D03*
X471068Y930235D03*
X473992Y952546D03*
X475018Y992568D03*
X467345Y996480D03*
X459360Y1004680D03*
X464795Y1000647D03*
X462185Y1016825D03*
X459860Y1015825D03*
X464385Y1038534D03*
X471558Y1029482D03*
X471755Y1038665D03*
X470610Y1033783D03*
X475588Y1043055D03*
X473639Y1030952D03*
X459700Y1035716D03*
X470978Y1046591D03*
X474348Y1090171D03*
X462913Y1106365D03*
X474277Y1093048D03*
X472482Y1107997D03*
X468282D03*
X459938Y1110092D03*
X463604Y1115896D03*
X473367Y1113648D03*
X474818Y1116101D03*
Y1118801D03*
X472582Y1110597D03*
X470482Y1112397D03*
X468282Y1110897D03*
Y1113797D03*
X470382Y1109397D03*
X463604Y1118396D03*
X462687Y1160834D03*
X474548Y1172384D03*
Y1169884D03*
Y1167384D03*
Y1164884D03*
Y1162384D03*
X468850Y1160834D03*
X474548Y1174884D03*
X465785Y1197471D03*
X461285Y1193471D03*
Y1197471D03*
X465785Y1193471D03*
X474647Y1260160D03*
Y1257160D03*
X471647D03*
Y1260160D03*
X459290Y1297035D03*
X463290D03*
X492135Y103411D03*
X492529Y97667D03*
X483675D03*
X487925Y95111D03*
X479331Y102495D03*
X485475Y118342D03*
Y121742D03*
Y132515D03*
Y135915D03*
X479065Y142862D03*
X486206Y143762D03*
X480106Y148717D03*
X487654Y195176D03*
X489672Y199248D03*
X485154Y195176D03*
X482654D03*
X486672Y199248D03*
X490154Y195176D03*
X485235Y210509D03*
X482735D03*
X489672Y202048D03*
X486672Y201748D03*
X484508Y206806D03*
X487008D03*
X476659Y216970D03*
Y219470D03*
X476725Y226320D03*
X476659Y221970D03*
X493272Y230117D03*
X484427Y230556D03*
X488682Y227824D03*
X479686Y228646D03*
X483412Y242078D03*
X478643Y232971D03*
X488769Y246874D03*
X489288Y238714D03*
X490989Y244297D03*
X482636Y256394D03*
X492817Y357111D03*
X491843Y351089D03*
X481724Y373589D03*
Y369089D03*
X490885Y373589D03*
X491053Y365423D03*
X491289Y391589D03*
X481724Y382589D03*
Y378089D03*
X490885Y382570D03*
X490985Y412342D03*
X488438Y418417D03*
X485485Y439903D03*
X489485D03*
X481485Y439900D03*
Y431917D03*
X489485Y431417D03*
X492736Y491982D03*
X482836Y534249D03*
X491818Y534909D03*
X491445Y541135D03*
X482905Y527726D03*
Y548726D03*
Y544726D03*
X491534Y552726D03*
X491511Y546553D03*
X487209Y611071D03*
X484772Y621311D03*
X493392Y622285D03*
X493580Y616905D03*
X484772Y629311D03*
Y625311D03*
X493661Y627713D03*
X493778Y633724D03*
X481165Y646036D03*
X483059Y662649D03*
X488765Y667224D03*
X481742Y657477D03*
X486837Y701306D03*
Y704706D03*
X489406Y797558D03*
X489572Y822805D03*
X479448Y828594D03*
X479700Y847600D03*
X477574Y860815D03*
X490706Y859339D03*
X491616Y938771D03*
X476475Y952249D03*
X479613Y952189D03*
X489163Y977163D03*
X487091Y989550D03*
X480711Y999941D03*
X477857Y1004375D03*
X488041Y1020440D03*
X485678Y1039880D03*
X485633Y1036155D03*
X477765Y1093432D03*
X477607Y1089942D03*
X491503Y1086796D03*
Y1084296D03*
X478517Y1086724D03*
Y1084224D03*
Y1081724D03*
X476017D03*
Y1084224D03*
Y1086724D03*
X486369Y1105552D03*
X490647Y1101917D03*
X488927Y1104335D03*
X490582Y1106897D03*
X482575Y1104792D03*
X484082Y1106867D03*
X480167Y1113648D03*
X477667D03*
X477048Y1172384D03*
Y1169884D03*
Y1167384D03*
Y1164884D03*
Y1162384D03*
X479521Y1179209D03*
Y1181709D03*
Y1184209D03*
Y1186709D03*
X477048Y1174884D03*
X490671Y1192621D03*
Y1190121D03*
X477206Y1192621D03*
Y1190121D03*
X489647Y1260160D03*
Y1257160D03*
X486647D03*
Y1260160D03*
X480647Y1257160D03*
X477647D03*
Y1260160D03*
X480647D03*
X483647Y1257160D03*
Y1260160D03*
X490100Y1302100D03*
X487600D03*
X503325Y90650D03*
X508637Y90615D03*
X503075Y95236D03*
X492775Y114655D03*
Y111255D03*
X492294Y106561D03*
X492775Y128828D03*
Y125428D03*
X496023Y362913D03*
X497048Y369450D03*
X495750Y377531D03*
X506500Y379687D03*
X495203Y386890D03*
X503729Y439919D03*
X503682Y448419D03*
X500729Y469905D03*
X496729Y470419D03*
X504729Y469905D03*
X496729Y461919D03*
X504729Y461419D03*
X505476Y485128D03*
X497095Y481467D03*
X501224Y492050D03*
X501649Y482165D03*
X501887Y504825D03*
X499387D03*
X496887D03*
X500890Y500202D03*
X502493Y495917D03*
X492736Y495982D03*
X501828Y517401D03*
X499328D03*
X496828D03*
X502379Y522569D03*
X495444Y531948D03*
X503494Y531882D03*
X502379Y525369D03*
X500994Y531882D03*
X498494D03*
X504079Y529169D03*
X503729Y555194D03*
X500929D03*
Y571194D03*
X503729D03*
Y563194D03*
X500929D03*
X505286Y581222D03*
X502486D03*
X505286Y591215D03*
X502486D03*
X505458Y610562D03*
X502658D03*
Y607762D03*
X505458D03*
X497448Y610548D03*
X504265Y633736D03*
X499258Y633716D03*
X506278Y628078D03*
X494465Y657772D03*
X502755Y657694D03*
X496070Y665976D03*
X499528Y657843D03*
X504966Y678098D03*
X498284Y681453D03*
Y678953D03*
X500714Y708755D03*
X502832Y720491D03*
X504895Y770457D03*
X501495D03*
X504508Y783817D03*
X506166Y793224D03*
X504641Y789139D03*
X507095Y814784D03*
X494677Y830468D03*
X509665Y824512D03*
X495073Y835586D03*
X495470Y844271D03*
X495700Y849389D03*
X503383Y863025D03*
X498507Y865392D03*
X508248Y873319D03*
X509791Y881932D03*
X509017Y905295D03*
X494315Y941212D03*
X503144Y957934D03*
X504088Y985171D03*
X506888D03*
X506702Y978947D03*
X493091Y989550D03*
X503933Y981392D03*
X498435Y1008766D03*
X506566D03*
Y996766D03*
X498524Y997590D03*
X498585Y1016266D03*
X506566Y1012266D03*
X503177Y1058097D03*
X495677D03*
X493177D03*
X498177D03*
X500677D03*
X503177Y1060697D03*
X495677D03*
X493177D03*
X498177D03*
X500677D03*
X494003Y1086796D03*
X496503D03*
X499003D03*
X501503D03*
Y1084296D03*
X499003D03*
X496503D03*
X494003D03*
X501831Y1090288D03*
X496372Y1106298D03*
X504610Y1107997D03*
X501831Y1093088D03*
X500410Y1107997D03*
X497063Y1115896D03*
X505495Y1113648D03*
X506946Y1116101D03*
Y1118801D03*
X504710Y1110597D03*
X500410Y1113797D03*
X502610Y1112397D03*
X500410Y1110897D03*
X502510Y1109397D03*
X493397Y1110092D03*
X497063Y1118396D03*
X498727Y1128759D03*
X495236Y1129094D03*
X502376Y1172384D03*
Y1169884D03*
Y1167384D03*
Y1164884D03*
Y1162384D03*
X504876Y1172384D03*
Y1169884D03*
Y1167384D03*
Y1164884D03*
Y1162384D03*
X492818D03*
Y1164884D03*
Y1167384D03*
Y1169884D03*
Y1172384D03*
X495318D03*
Y1169884D03*
Y1167384D03*
Y1164884D03*
Y1162384D03*
X502562Y1158200D03*
X506451Y1179209D03*
Y1181709D03*
Y1184209D03*
Y1186709D03*
X504876Y1174884D03*
X493821Y1186921D03*
Y1184421D03*
Y1181921D03*
Y1179421D03*
X492818Y1174884D03*
X495318D03*
X502376D03*
X504136Y1190121D03*
Y1192621D03*
X496136Y1190121D03*
Y1192621D03*
X506562Y1222194D03*
X502562D03*
X498562D03*
X494562D03*
X506562Y1226194D03*
Y1230194D03*
Y1234194D03*
Y1238194D03*
X502562Y1226194D03*
Y1230194D03*
Y1234194D03*
Y1238194D03*
X498562Y1226194D03*
Y1230194D03*
Y1234194D03*
Y1238194D03*
X494562Y1226194D03*
Y1230194D03*
Y1234194D03*
Y1238194D03*
Y1246194D03*
Y1242194D03*
X506562D03*
Y1246194D03*
X502562Y1242194D03*
Y1246194D03*
X498562Y1242194D03*
Y1246194D03*
X504647Y1257160D03*
X507347D03*
X501647D03*
Y1260160D03*
X495647D03*
X492647D03*
Y1257160D03*
X495647D03*
X498647D03*
Y1260160D03*
X507347D03*
X504647D03*
X521872Y82593D03*
Y85193D03*
Y74793D03*
Y77393D03*
Y79993D03*
X521916Y92874D03*
X512958Y99961D03*
X513008Y95236D03*
X523943Y107649D03*
Y104249D03*
X520965Y162368D03*
X523565D03*
X511820Y207978D03*
Y210478D03*
Y215478D03*
Y212978D03*
X522276Y208213D03*
Y213213D03*
Y210713D03*
Y215713D03*
X515149Y264180D03*
X517649D03*
X515074Y258880D03*
X524043Y270026D03*
Y267526D03*
X514769Y312953D03*
X519638Y314346D03*
X511790Y313804D03*
X512943Y443071D03*
X520823Y442603D03*
X511753Y454339D03*
Y456839D03*
X509253D03*
Y454339D03*
X518240Y459371D03*
X509253Y459339D03*
X511753D03*
X512210Y475825D03*
X517310Y470045D03*
X513310Y462004D03*
X522756Y461818D03*
X508325Y485138D03*
X512210Y478625D03*
X513910Y482425D03*
X513325Y485138D03*
X510825D03*
X519786Y491214D03*
X523489Y492987D03*
X519786Y493714D03*
X523489Y495487D03*
X509955Y537958D03*
X513658Y539731D03*
X518716Y541895D03*
X521216Y544895D03*
Y541895D03*
X513658Y542231D03*
X518416Y544895D03*
X509955Y540458D03*
X521494Y582747D03*
X508086Y581222D03*
X520945Y590801D03*
X508086Y591215D03*
X520770Y597130D03*
X524770Y605637D03*
X518940Y620653D03*
Y617853D03*
X511058Y610562D03*
Y607762D03*
X508258Y610562D03*
Y607762D03*
X520770Y605443D03*
X516770D03*
X523616Y625013D03*
X515267Y627908D03*
X511278Y633473D03*
X521778Y642184D03*
X521868Y666577D03*
X518812Y662874D03*
X510425Y683246D03*
X522200Y677613D03*
X521540Y686319D03*
X515484Y695757D03*
X515504Y701351D03*
X521159Y706388D03*
X515649D03*
X512530Y718301D03*
X514531Y716398D03*
X523929Y706388D03*
X518389D03*
X521131Y741071D03*
X517731D03*
X511724Y741035D03*
X508324D03*
X520549Y761982D03*
X509096Y753072D03*
X515422Y753455D03*
X513504Y755804D03*
X513278Y783286D03*
X520833Y773389D03*
X513551Y773203D03*
X522697Y797102D03*
X519891Y795848D03*
X518157Y803973D03*
X518565Y811973D03*
X520741Y805149D03*
X522481Y824661D03*
X517702Y826600D03*
X514682Y834590D03*
X511741Y846649D03*
X524741Y845149D03*
X520870Y874694D03*
X525159Y913818D03*
X521572Y901500D03*
X516902Y910251D03*
X520146Y939241D03*
X523289Y939195D03*
X521353Y952266D03*
X522544Y992854D03*
X512232Y985172D03*
X514566Y1000766D03*
X514690Y996766D03*
Y1004766D03*
X514566Y1016266D03*
X514649Y1020266D03*
X514843Y1030766D03*
X519500Y1028377D03*
X518497Y1105552D03*
X522775Y1101917D03*
X521055Y1104335D03*
X514703Y1104792D03*
X522710Y1106897D03*
X516210Y1106867D03*
X509795Y1113648D03*
X512295D03*
X520646Y1169884D03*
Y1167384D03*
Y1164884D03*
Y1162384D03*
X523146D03*
Y1164884D03*
Y1167384D03*
Y1169884D03*
Y1172384D03*
X520646D03*
X520751Y1186921D03*
Y1184421D03*
Y1181921D03*
Y1179421D03*
X523146Y1174884D03*
X520646D03*
X523066Y1190121D03*
Y1192621D03*
X522562Y1222194D03*
X518562D03*
X514562D03*
X510562D03*
X522562Y1226194D03*
X518562D03*
Y1230194D03*
Y1234194D03*
X514562Y1226194D03*
Y1230194D03*
Y1234194D03*
Y1238194D03*
X510562Y1226194D03*
Y1230194D03*
Y1234194D03*
Y1238194D03*
X514562Y1242194D03*
Y1246194D03*
X510562Y1242194D03*
Y1246194D03*
X530197Y98551D03*
X540751Y97475D03*
X533092Y114623D03*
Y111223D03*
X533747Y103783D03*
X533092Y128796D03*
Y125396D03*
X532281Y141247D03*
X528509Y147540D03*
X539748Y143740D03*
X537128Y148277D03*
X530665Y162793D03*
Y165393D03*
Y170493D03*
Y167993D03*
X538170Y172190D03*
X535668Y181009D03*
X529662Y181426D03*
X532873Y181366D03*
X537589Y177616D03*
X529870Y184221D03*
X532487Y184012D03*
X533906Y211359D03*
Y213859D03*
X528848Y211695D03*
X537609Y213132D03*
X526348Y208695D03*
X529148D03*
X526348Y211695D03*
X537609Y215632D03*
X537853Y256303D03*
X532525Y265701D03*
X537612Y265896D03*
X526843Y270026D03*
X529343D03*
X526843Y267526D03*
X529343D03*
X534160Y281716D03*
X540101Y281982D03*
X532659Y359557D03*
X526388Y351301D03*
X531612Y354272D03*
X531636Y349057D03*
X528812Y369164D03*
X533211Y364746D03*
X533115Y371856D03*
X530144Y376062D03*
X531953Y380749D03*
X542034Y392209D03*
X541706Y386223D03*
X533189Y390723D03*
X531953Y385749D03*
X531992Y397552D03*
X526216Y456652D03*
X528716D03*
X526216Y459152D03*
Y461652D03*
X528716Y459152D03*
Y461652D03*
X535119Y491133D03*
X531047Y498151D03*
X535119Y493633D03*
Y496133D03*
Y498633D03*
X531047Y495151D03*
X528547D03*
X528247Y498151D03*
X525288Y537877D03*
X535219Y555897D03*
Y553297D03*
X533488Y548344D03*
X525288Y540377D03*
Y545377D03*
Y542877D03*
X528488Y548344D03*
X525988D03*
X530988D03*
X535219Y561097D03*
Y563697D03*
Y566797D03*
Y558497D03*
X532009Y570478D03*
X529214Y570686D03*
X529423Y573303D03*
X532069Y573689D03*
X532426Y576484D03*
X535819Y578405D03*
X541245Y578986D03*
X524770Y597232D03*
X534820Y596782D03*
X540770Y596729D03*
X529601Y596089D03*
X526756Y613913D03*
Y616713D03*
Y619513D03*
X538826Y614158D03*
Y616958D03*
Y619758D03*
X536770Y605443D03*
X537664Y661556D03*
X534264D03*
X529664Y664056D03*
X526264D03*
X538316Y687357D03*
X535738Y687489D03*
X536087Y702364D03*
X529469Y706230D03*
X526699Y706388D03*
X535585Y736593D03*
X538985D03*
X530985Y741593D03*
X527585D03*
X524598Y753387D03*
X539449Y782389D03*
X537578Y772428D03*
X532304Y806649D03*
X531313Y812850D03*
Y826630D03*
X532316Y833649D03*
X534000Y843000D03*
X537300Y842900D03*
X530741Y845149D03*
X534632Y849830D03*
X525718Y873821D03*
X533468Y878533D03*
X538468Y888033D03*
X530968Y888283D03*
X528975Y898346D03*
X537279Y897943D03*
X533143Y897910D03*
X531076Y913190D03*
X527879Y952189D03*
X530473Y961728D03*
X528500Y1106365D03*
X529191Y1115896D03*
X525525Y1110092D03*
X529191Y1118396D03*
X528274Y1160834D03*
X554198Y68581D03*
X554211Y80581D03*
X546293Y76587D03*
Y72615D03*
X547732Y100625D03*
X540682Y106186D03*
X552105Y112083D03*
X556394Y103621D03*
X543494Y121735D03*
Y132509D03*
Y118335D03*
Y135909D03*
X548311Y141247D03*
X552798Y143518D03*
X551898Y152373D03*
X555048Y152562D03*
X540843Y168697D03*
X555850Y178560D03*
X555913Y172665D03*
X555740Y183834D03*
X541931Y191941D03*
X555260Y190185D03*
X549985Y192490D03*
X556030Y200864D03*
X548940Y206767D03*
X546440D03*
X543940D03*
X556119Y212455D03*
X556053Y207037D03*
X549070Y221708D03*
X546570D03*
X553420Y221642D03*
X545185Y231021D03*
Y228221D03*
X544070Y221708D03*
X543485Y224421D03*
X550736Y236189D03*
X548236D03*
X545736D03*
X550677Y248765D03*
X548177D03*
X545677D03*
X542628Y266114D03*
X545874Y268195D03*
X548374D03*
X551174Y270695D03*
X554834Y265897D03*
X551174Y268195D03*
X548374Y270695D03*
X545874D03*
X551536Y359223D03*
Y354723D03*
Y350223D03*
Y345723D03*
Y377223D03*
Y372723D03*
Y368223D03*
Y363723D03*
Y381723D03*
X551620Y390723D03*
X553563Y384987D03*
X544738Y581659D03*
X544770Y605443D03*
X551475Y661504D03*
X547227Y678299D03*
X547276Y675521D03*
X543101Y698772D03*
X540379Y719785D03*
X557751Y750851D03*
X549168Y781600D03*
X545768D03*
X550420Y793743D03*
X556326D03*
X540578Y793889D03*
X544515Y793875D03*
X544741Y809649D03*
X544878Y816309D03*
X546855Y829949D03*
X550087Y829836D03*
X556326Y829989D03*
X556741Y820149D03*
X544741Y823149D03*
X546241Y843149D03*
X557836Y851669D03*
X548665Y850399D03*
X540968Y878360D03*
X546940Y871389D03*
X548327Y905295D03*
X552238Y959102D03*
X552923Y988813D03*
X542793Y998507D03*
X544719Y1007522D03*
X551485Y1006648D03*
X551673Y1023900D03*
X548852Y1018307D03*
X545094Y1013678D03*
X545566Y1023731D03*
X554696Y1018469D03*
X556493Y1118351D03*
X557584Y1543411D03*
X560573Y60513D03*
X563433Y60438D03*
X557973Y55513D03*
X569114Y86012D03*
X558341Y88801D03*
X569114Y94374D03*
X561258Y94351D03*
X565207Y94279D03*
X560701Y85731D03*
X564255Y86046D03*
X564451Y116594D03*
X570394Y110784D03*
X564451Y119594D03*
X574973Y124663D03*
X564885Y124283D03*
X569951Y124879D03*
X563292Y161306D03*
X560543Y157370D03*
X564627Y176665D03*
Y168665D03*
X556726Y186629D03*
X564627Y196665D03*
Y192665D03*
X564740Y186778D03*
X564659Y204864D03*
Y208864D03*
X569708Y218085D03*
X572508D03*
X560300Y219379D03*
X560928Y228631D03*
X575035Y249108D03*
X566416Y248371D03*
X557334Y265897D03*
X573479Y374705D03*
X569938Y378317D03*
X559070Y684809D03*
Y700809D03*
Y688209D03*
X561570Y696209D03*
Y692809D03*
X559070Y716809D03*
X561570Y708809D03*
Y712209D03*
X559070Y704209D03*
Y720209D03*
X558616Y732530D03*
X562001Y732834D03*
X562374Y721593D03*
X567428Y750145D03*
X557847Y744599D03*
X563200Y739600D03*
X571493Y763090D03*
X570038Y752339D03*
X564362Y757979D03*
X560263Y782207D03*
X567126Y779066D03*
X571984Y784507D03*
X561001Y806889D03*
X567559Y803008D03*
Y824661D03*
X562400Y818900D03*
X560813Y840574D03*
X568990Y844721D03*
X572476Y845535D03*
X559295Y874267D03*
X559887Y877196D03*
X561134Y869291D03*
X559260Y891043D03*
X559214Y897425D03*
X564165Y894411D03*
X567827Y884000D03*
X562328Y957307D03*
X566303Y951807D03*
X569403D03*
X563103D03*
X570603Y957207D03*
X560923Y980443D03*
X556923Y980523D03*
X564923Y988813D03*
X560923D03*
X556923D03*
X568923D03*
X558112Y1009655D03*
X560912D03*
X567484Y1024003D03*
X571857Y1016827D03*
X559057Y1030563D03*
X562057D03*
X568057Y1030672D03*
X565057D03*
X571857Y1029427D03*
X566058Y1109564D03*
X560211D03*
X566058Y1122164D03*
X560211D03*
X566058Y1134764D03*
X560211D03*
X566058Y1147364D03*
X560211D03*
X566058Y1159964D03*
X560211D03*
X566058Y1172564D03*
X560211D03*
X566058Y1185164D03*
X560211D03*
X568532Y1200001D03*
X575620Y1207737D03*
X569135Y1214372D03*
X564890Y1218169D03*
X570796Y1530309D03*
X567324Y1528151D03*
X572432Y1521462D03*
X565400Y1535100D03*
X563968Y1541445D03*
X568279Y1538438D03*
X572507Y1541375D03*
X586037Y97667D03*
X581693Y102495D03*
X576420Y116594D03*
X575394Y110784D03*
X587837Y118342D03*
Y121742D03*
Y132515D03*
X576420Y119594D03*
X579954Y125107D03*
X587837Y135915D03*
X581427Y142862D03*
X588568Y143762D03*
X582468Y148717D03*
X576317Y138838D03*
X587516Y195176D03*
X585016D03*
X589034Y199248D03*
X587597Y210509D03*
X585097D03*
X589034Y201748D03*
X586870Y206806D03*
X576308Y216385D03*
X579021Y216970D03*
Y219470D03*
X579087Y226320D03*
X579021Y221970D03*
X586789Y230556D03*
X591044Y227824D03*
X582048Y228646D03*
X585774Y242078D03*
X581005Y232971D03*
X577655Y244571D03*
X584998Y256394D03*
X578193Y336391D03*
X584679Y336285D03*
X576556Y728219D03*
X575979Y732517D03*
X573778Y747437D03*
X577638Y769772D03*
X578271Y763556D03*
X583102Y767137D03*
X587183Y785008D03*
X578204Y775137D03*
X585912Y778470D03*
X588345Y798030D03*
X588659Y790336D03*
X582100Y787600D03*
X586060Y793145D03*
X581001Y810973D03*
X588377Y807536D03*
X588272Y804601D03*
X588231Y801520D03*
X577501Y829069D03*
X588001Y829624D03*
X582737Y819831D03*
X581158Y823473D03*
X573300Y829600D03*
X579827Y888000D03*
X580327Y892000D03*
X586136Y908935D03*
X583065Y903294D03*
X573103Y941307D03*
X585703D03*
X586103Y961807D03*
X573895Y965319D03*
X584923Y988813D03*
X576923D03*
X580923D03*
X588923D03*
X572923D03*
X577704Y1029427D03*
Y1016827D03*
X587880Y1034834D03*
X581967Y1105091D03*
X587467D03*
X582012Y1102091D03*
X587467Y1117691D03*
X581967D03*
X582012Y1127291D03*
Y1114691D03*
X587467Y1130291D03*
X581967D03*
X587467Y1142891D03*
X582012Y1139891D03*
X581967Y1155491D03*
X587467D03*
X581967Y1142891D03*
X582012Y1152491D03*
X581967Y1168091D03*
X587467D03*
X582012Y1165091D03*
X581967Y1180691D03*
X587467D03*
X582012Y1177691D03*
X586502Y1227300D03*
X583520Y1230407D03*
X581803Y1493687D03*
X578859Y1497758D03*
X588859Y1490895D03*
X590826Y1495688D03*
X588507Y1514141D03*
X582027Y1502800D03*
X581803Y1509687D03*
X577931Y1505687D03*
X575809Y1532912D03*
X572849Y1518702D03*
X587809Y1528389D03*
X583809Y1533025D03*
X579809Y1528163D03*
X587809Y1545854D03*
X583809Y1541607D03*
X577571Y1544013D03*
X594497Y103411D03*
X594891Y97667D03*
X605687Y90650D03*
X590287Y95111D03*
X595137Y111255D03*
Y114655D03*
X594656Y106561D03*
X595137Y125428D03*
Y128828D03*
X590016Y195176D03*
X592516D03*
X592034Y199248D03*
Y202048D03*
X589370Y206806D03*
X595634Y230117D03*
X591131Y246874D03*
X591650Y238714D03*
X593351Y244297D03*
X592900Y309871D03*
X605147Y378600D03*
Y382600D03*
X597776Y401513D03*
Y398113D03*
X595376Y412287D03*
Y426460D03*
Y415687D03*
Y440633D03*
Y429860D03*
X605262Y458711D03*
X595376Y444033D03*
X602462Y458711D03*
X595376Y469387D03*
Y472787D03*
X604606Y463600D03*
X595376Y483560D03*
Y486960D03*
X598462Y504684D03*
X595376Y513521D03*
Y516921D03*
Y531094D03*
Y527694D03*
X599110Y552466D03*
X605011Y603600D03*
Y619600D03*
Y623600D03*
X592272Y877262D03*
X592110Y895611D03*
X601084Y913544D03*
X604715Y914640D03*
X589203Y941407D03*
X591403Y938807D03*
Y936007D03*
X591754Y956979D03*
X597556Y965829D03*
X602484Y965764D03*
X600923Y988813D03*
X592923D03*
X604923D03*
X596923D03*
X599113Y1012354D03*
X593658Y1009354D03*
X593613Y1012354D03*
X599113Y1024954D03*
X593613D03*
X593658Y1021954D03*
X606434Y1041904D03*
X603682Y1053457D03*
X594183Y1220068D03*
X593519Y1224472D03*
X592885Y1229402D03*
X592634Y1234921D03*
X591487Y1501687D03*
X591481Y1509313D03*
X595809Y1532133D03*
X591872Y1518071D03*
X595809Y1546214D03*
X591809Y1542407D03*
X610999Y90615D03*
X615370Y95236D03*
X615320Y99961D03*
X605437Y95236D03*
X620727Y162368D03*
X614182Y210478D03*
Y215478D03*
Y212978D03*
Y207978D03*
X617511Y264180D03*
X620011D03*
X617436Y258880D03*
X605778Y391001D03*
Y405174D03*
Y394401D03*
Y408574D03*
Y422747D03*
Y419347D03*
Y433521D03*
Y436921D03*
X607789Y453682D03*
X606026Y455921D03*
X605778Y479899D03*
Y490673D03*
Y476499D03*
Y494073D03*
Y520633D03*
Y524033D03*
Y534806D03*
Y538206D03*
X609133Y941137D03*
X605733D03*
X608965Y966414D03*
X616923Y988813D03*
X608923D03*
X612923Y997860D03*
X618878Y1011914D03*
X621479Y1030482D03*
X607993Y1036920D03*
X610780Y1051037D03*
X617634Y1049283D03*
X617894Y1043955D03*
X612955Y1062941D03*
X622736Y1151870D03*
Y1159350D03*
X613738Y1546507D03*
X624234Y74793D03*
Y82593D03*
Y85193D03*
Y77393D03*
Y79993D03*
X624278Y92874D03*
X632559Y98551D03*
X635454Y114623D03*
Y111223D03*
X636109Y103783D03*
X626305Y104249D03*
Y107649D03*
X635454Y128796D03*
Y125396D03*
X630871Y147540D03*
X634643Y141247D03*
X639490Y148277D03*
X625927Y162368D03*
X623327D03*
X633027Y165393D03*
Y162793D03*
Y170493D03*
Y167993D03*
X639951Y177616D03*
X632024Y181426D03*
X635235Y181366D03*
X632232Y184221D03*
X634849Y184012D03*
X628710Y211695D03*
Y208695D03*
X631510D03*
X624638Y208213D03*
X636268Y211359D03*
Y213859D03*
X631210Y211695D03*
X624638Y213213D03*
Y210713D03*
Y215713D03*
X639974Y265896D03*
X634887Y265701D03*
X629205Y267526D03*
X626405D03*
X631705D03*
X629205Y270026D03*
X626405D03*
X631705D03*
X636522Y281716D03*
X632009Y541863D03*
Y545263D03*
X630201Y553407D03*
X632701D03*
X630201Y550907D03*
X632701D03*
X634185Y569426D03*
X634471Y566929D03*
X628425Y572070D03*
X629772Y569928D03*
X632119Y570962D03*
X631862Y568475D03*
X621592Y1033862D03*
X626476Y1155610D03*
X621727Y1556800D03*
X648655Y76587D03*
Y72615D03*
X650094Y100625D03*
X643113Y97475D03*
X643044Y106186D03*
X645856Y118335D03*
Y132509D03*
Y121735D03*
Y135909D03*
X650673Y141247D03*
X655160Y143518D03*
X642110Y143740D03*
X654260Y152373D03*
X640532Y172190D03*
X638030Y181009D03*
X643205Y168697D03*
X644293Y191941D03*
X652347Y192490D03*
X646302Y206767D03*
X651302D03*
X648802D03*
X639971Y213132D03*
X648932Y221708D03*
X647547Y228221D03*
X645847Y224421D03*
X647547Y231021D03*
X646432Y221708D03*
X651432D03*
X639971Y215632D03*
X650598Y236189D03*
X648098D03*
X653098D03*
X653039Y248765D03*
X650539D03*
X648039D03*
X640215Y256303D03*
X644990Y266114D03*
X650736Y268195D03*
X653536Y270695D03*
Y268195D03*
X650736Y270695D03*
X648236D03*
Y268195D03*
X642463Y281982D03*
X642414Y545528D03*
X651149Y577716D03*
X648211Y610400D03*
X650958Y668153D03*
X662935Y60513D03*
X665795Y60438D03*
X657507Y58013D03*
X656560Y68581D03*
X671476Y86012D03*
X656573Y80581D03*
X660703Y88801D03*
X663620Y94351D03*
X667569Y94279D03*
X663063Y85731D03*
X666617Y86046D03*
X658756Y103621D03*
X666813Y116594D03*
X654467Y112083D03*
X666813Y119594D03*
X667247Y124283D03*
X672313Y124879D03*
X665654Y161306D03*
X657410Y152562D03*
X662905Y157370D03*
X666989Y176665D03*
Y168665D03*
X658275Y172665D03*
X658212Y178560D03*
X658102Y183834D03*
X659088Y186629D03*
X657622Y190185D03*
X658392Y200864D03*
X666989Y196665D03*
Y192665D03*
X667102Y186778D03*
X667021Y204864D03*
Y208864D03*
X658481Y212455D03*
X658415Y207037D03*
X655782Y221642D03*
X662662Y219379D03*
X663290Y228631D03*
X668886Y248371D03*
X657196Y265897D03*
X659696D03*
X670066Y390995D03*
X661761Y382109D03*
X670066Y405168D03*
X662766Y398082D03*
X670066Y408568D03*
Y394395D03*
X662766Y401482D03*
X670066Y422741D03*
Y419341D03*
X662766Y415655D03*
Y426428D03*
Y412255D03*
Y440602D03*
X670066Y433515D03*
X662766Y429828D03*
X670066Y436915D03*
X662766Y444002D03*
X670066Y469381D03*
Y472781D03*
X662766Y476468D03*
Y490641D03*
X670066Y483554D03*
Y486954D03*
X662766Y479868D03*
Y494041D03*
X670066Y516915D03*
X662766Y520602D03*
Y524002D03*
X670066Y513515D03*
Y527688D03*
X662766Y534775D03*
X670066Y531088D03*
X662766Y538175D03*
X661760Y551683D03*
Y561420D03*
Y558917D03*
X657581Y577937D03*
X660586Y606929D03*
X665086Y604567D03*
X665586Y595500D03*
X660827Y612592D03*
X666244Y610072D03*
X660546Y618400D03*
X666180Y616317D03*
X665643Y646055D03*
X658233Y646449D03*
X658064Y650119D03*
X657967Y662981D03*
X662092Y666275D03*
X659209Y691851D03*
X661018Y707592D03*
X688399Y97667D03*
X671476Y94374D03*
X678782Y116594D03*
X684055Y102495D03*
X677756Y110784D03*
X672756D03*
X678782Y119594D03*
X682316Y125107D03*
X677335Y124663D03*
X683789Y142862D03*
X684830Y148717D03*
X678679Y138838D03*
X674870Y218085D03*
X681383Y219470D03*
Y216970D03*
X678670Y216385D03*
X681383Y221970D03*
X681449Y226320D03*
X672070Y218085D03*
X684410Y228646D03*
X683367Y232971D03*
X677397Y249108D03*
X680017Y244571D03*
X682857Y339477D03*
X687055Y376456D03*
X685353Y396718D03*
X678461Y455981D03*
X675237Y465611D03*
X682586Y530000D03*
X682086Y540500D03*
X681086Y547075D03*
X681286Y549800D03*
X680586Y568000D03*
X681126Y558800D03*
X681190Y562800D03*
X696859Y103411D03*
X697253Y97667D03*
X692649Y95111D03*
X697499Y114655D03*
Y111255D03*
X697018Y106561D03*
X690199Y132515D03*
X697499Y125428D03*
Y128828D03*
X690199Y121742D03*
Y118342D03*
Y135915D03*
X690930Y143762D03*
X691396Y199248D03*
X687378Y195176D03*
X689878D03*
X694396Y199248D03*
X694878Y195176D03*
X692378D03*
X691396Y201748D03*
X689232Y206806D03*
X687459Y210509D03*
X689959D03*
X694396Y202048D03*
X691732Y206806D03*
X697996Y230117D03*
X689151Y230556D03*
X693406Y227824D03*
X694012Y238714D03*
X688136Y242078D03*
X693493Y246874D03*
X695713Y244297D03*
X690504Y253198D03*
X689486Y339583D03*
X702448Y546712D03*
Y542712D03*
X699188Y656321D03*
X702086Y678462D03*
X692478Y730641D03*
X702691Y762971D03*
Y756971D03*
X692356Y764614D03*
X691991Y759581D03*
X702677Y780659D03*
Y775159D03*
X692155Y778974D03*
X692221Y773449D03*
X690449Y814406D03*
X708049Y90650D03*
X713361Y90615D03*
X717732Y95236D03*
X717682Y99961D03*
X707799Y95236D03*
X716544Y215478D03*
Y210478D03*
Y207978D03*
Y212978D03*
X718338Y305272D03*
X712692Y356779D03*
X717105Y410964D03*
X717420Y404334D03*
X709781Y442956D03*
X720996Y442856D03*
X711598Y438323D03*
X719051Y458455D03*
X719612Y451108D03*
X710643Y456335D03*
X711764Y445873D03*
X706211Y465874D03*
X713791Y474424D03*
Y488597D03*
Y477824D03*
Y491997D03*
Y518558D03*
Y521958D03*
Y536131D03*
Y532731D03*
X711463Y546712D03*
X713791Y571997D03*
Y568597D03*
Y582771D03*
Y586171D03*
Y596944D03*
Y600344D03*
Y611117D03*
Y614517D03*
X704364Y618288D03*
X711328Y653821D03*
X705390Y655789D03*
X705776Y678519D03*
X713200Y699676D03*
X716623Y702463D03*
X703600Y702212D03*
X703680Y697094D03*
X715802Y706446D03*
X710196Y707562D03*
X717434Y782500D03*
X710275Y786131D03*
X713222Y793312D03*
Y790812D03*
X712901Y821600D03*
X726596Y74793D03*
Y77393D03*
Y79993D03*
Y85193D03*
Y82593D03*
X726640Y92874D03*
X734921Y98551D03*
X728667Y104249D03*
Y107649D03*
X733233Y147540D03*
X728289Y162368D03*
X725689D03*
X734386Y181426D03*
X734594Y184221D03*
X727000Y213213D03*
Y208213D03*
X733872Y208695D03*
X731072D03*
X733572Y211695D03*
X731072D03*
X727000Y210713D03*
Y215713D03*
X722373Y264180D03*
X719873D03*
X719798Y258880D03*
X737249Y265701D03*
X731567Y267526D03*
X728767D03*
X734067D03*
Y270026D03*
X731567D03*
X728767D03*
X723404Y379657D03*
X721900Y384500D03*
X723440Y391496D03*
X734661Y393633D03*
X731511Y381113D03*
X723440Y398583D03*
X732035Y442606D03*
X722097Y453881D03*
X731952Y446606D03*
X722097Y446595D03*
X721091Y470737D03*
Y467337D03*
X732959Y463479D03*
X733430Y467367D03*
X721091Y484910D03*
Y481510D03*
X724362Y504731D03*
X721091Y514871D03*
Y511471D03*
Y525644D03*
Y529044D03*
Y561510D03*
Y564910D03*
Y579084D03*
Y575684D03*
Y593257D03*
Y604030D03*
Y589857D03*
Y607430D03*
X722473Y693718D03*
X723656Y705858D03*
X720985Y711658D03*
X725667Y732161D03*
X723177Y728219D03*
X721163Y738981D03*
X733000Y816000D03*
X730880Y828924D03*
X733680Y828977D03*
X732713Y853890D03*
X722600Y869600D03*
X728503Y891692D03*
X736452Y890548D03*
X728692Y886653D03*
X724707Y893143D03*
X719661Y904900D03*
X722789Y927095D03*
X722400Y942500D03*
X725194Y942073D03*
X720271Y931730D03*
X732306Y942682D03*
X728846Y948331D03*
X733798Y950186D03*
X727116Y959326D03*
X732825Y1604100D03*
X736067Y1611892D03*
X729600Y1625165D03*
X732268Y1618260D03*
X751017Y76587D03*
Y72615D03*
X752456Y100625D03*
X745475Y97475D03*
X737816Y114623D03*
Y111223D03*
X745406Y106186D03*
X738471Y103783D03*
X748218Y118335D03*
X737816Y128796D03*
X748218Y132509D03*
Y121735D03*
X737816Y125396D03*
X748218Y135909D03*
X737005Y141247D03*
X744472Y143740D03*
X741852Y148277D03*
X735389Y165393D03*
Y162793D03*
Y170493D03*
Y167993D03*
X740392Y181009D03*
X737597Y181366D03*
X745567Y168697D03*
X742894Y172190D03*
X742313Y177616D03*
X746655Y191941D03*
X737211Y184012D03*
X750667Y192300D03*
X751164Y206767D03*
X748664D03*
X738630Y213859D03*
Y211359D03*
X742333Y213132D03*
X749909Y228221D03*
Y231021D03*
X751294Y221708D03*
X748209Y224421D03*
X748794Y221708D03*
X742333Y215632D03*
X750460Y236189D03*
X750401Y248765D03*
X742577Y256303D03*
X747352Y266114D03*
X742336Y265896D03*
X750598Y268195D03*
Y270695D03*
X744825Y281982D03*
X738884Y281716D03*
X741051Y316389D03*
X749444Y393858D03*
X749606Y384410D03*
X752785Y382047D03*
X753086Y403500D03*
X751086Y398583D03*
X749539Y438269D03*
Y440869D03*
Y435669D03*
Y430469D03*
Y433069D03*
X735599Y449961D03*
X739316Y458572D03*
X750393Y451677D03*
Y454177D03*
X741992Y763480D03*
X742000Y768137D03*
X743428Y772418D03*
X741993Y775909D03*
X736000Y864266D03*
X742407Y988452D03*
X743062Y1004460D03*
X749439Y1458777D03*
X740530Y1524113D03*
X747140Y1581335D03*
X749786Y1590517D03*
X738775Y1597866D03*
X737892Y1602340D03*
X749704Y1608631D03*
X744924Y1617709D03*
X743331Y1627871D03*
X741705Y1622015D03*
X738325Y1634485D03*
X762697Y55513D03*
X758922Y68581D03*
X765297Y60513D03*
X758935Y80581D03*
X763065Y88801D03*
X765982Y94351D03*
X769931Y94279D03*
X765425Y85731D03*
X756829Y112083D03*
X761118Y103621D03*
X769609Y124283D03*
X753035Y141247D03*
X757522Y143518D03*
X756622Y152373D03*
X759772Y152562D03*
X765267Y157370D03*
X760637Y172665D03*
X760464Y183834D03*
X760574Y178560D03*
X761450Y186629D03*
X754709Y192490D03*
X759984Y190185D03*
X760754Y200864D03*
X753182Y198671D03*
X753664Y206767D03*
X769383Y208864D03*
X760843Y212455D03*
X760777Y207037D03*
X753794Y221708D03*
X758144Y221642D03*
X765024Y219379D03*
X763653Y224536D03*
X752960Y236189D03*
X755460D03*
X755401Y248765D03*
X752901D03*
X753098Y268195D03*
X755898D03*
X753098Y270695D03*
X755898D03*
X759558Y265897D03*
X762058D03*
X769349Y324518D03*
X759029Y328867D03*
X754805Y339559D03*
X759624Y353961D03*
X756086Y377912D03*
X766344D03*
X755086Y391496D03*
X756086Y386500D03*
X766344Y381912D03*
X756174Y397912D03*
X755086Y409000D03*
X766344Y397912D03*
X752339Y438269D03*
Y433069D03*
Y430469D03*
Y435669D03*
Y440869D03*
X752893Y451677D03*
Y454177D03*
X752097Y460218D03*
Y463618D03*
X755035Y1443524D03*
X765713Y1437365D03*
X760398Y1440276D03*
X755187Y1580821D03*
X759802Y1590864D03*
X763542Y1590186D03*
X768361Y1610083D03*
X762671Y1619367D03*
X756358Y1613767D03*
X768157Y60438D03*
X773838Y86012D03*
Y94374D03*
X768979Y86046D03*
X781144Y116594D03*
X769175D03*
X775118Y110784D03*
X780118D03*
X781144Y119594D03*
X769175D03*
X784678Y125107D03*
X779697Y124663D03*
X774675Y124879D03*
X781041Y138838D03*
X768016Y161306D03*
X769351Y176665D03*
Y168665D03*
Y192665D03*
X769464Y186778D03*
X769383Y204864D03*
X774432Y218085D03*
X777232D03*
X783745Y216970D03*
X781032Y216385D03*
X783745Y221970D03*
X783811Y226320D03*
X783745Y219470D03*
X782379Y244571D03*
X779759Y249108D03*
X771140Y248371D03*
X772165Y314890D03*
X784118Y303962D03*
X771941Y311740D03*
X772162Y332584D03*
X778502Y348015D03*
X772859Y347937D03*
X774419Y353470D03*
X784902Y428653D03*
X778079Y467306D03*
Y470706D03*
Y481479D03*
Y484879D03*
Y514839D03*
Y511439D03*
Y529013D03*
Y525613D03*
X775746Y539315D03*
X777708Y553287D03*
X781429Y545017D03*
X778079Y561479D03*
Y564879D03*
Y575652D03*
Y579052D03*
Y589825D03*
Y593225D03*
Y603999D03*
Y607399D03*
X778860Y626912D03*
X778205Y622912D03*
X783694Y1410977D03*
X778685Y1416198D03*
X780162Y1412848D03*
X777749Y1431432D03*
X783469Y1424655D03*
X771557Y1446818D03*
X768910Y1437741D03*
X777749Y1435432D03*
Y1439432D03*
X777260Y1446237D03*
X778428Y1455156D03*
X777725Y1450193D03*
X783620Y1460108D03*
X768812Y1453306D03*
X781124Y1583553D03*
X781110Y1595254D03*
X777059Y1608982D03*
X784046Y1600438D03*
X778045Y1619395D03*
X778358Y1627418D03*
X771383Y1616917D03*
X799221Y103411D03*
X799615Y97667D03*
X790761D03*
X795011Y95111D03*
X799861Y114655D03*
Y111255D03*
X786417Y102495D03*
X799380Y106561D03*
X792561Y132515D03*
Y118342D03*
X799861Y128828D03*
X792561Y121742D03*
X799861Y125428D03*
X792561Y135915D03*
X786151Y142862D03*
X793292Y143762D03*
X787192Y148717D03*
X796758Y199248D03*
X797240Y195176D03*
X794740D03*
X789740D03*
X792240D03*
X793758Y199248D03*
X794094Y206806D03*
X791594D03*
X789821Y210509D03*
X792321D03*
X793758Y201748D03*
X796758Y202048D03*
X800358Y230117D03*
X795768Y227824D03*
X791513Y230556D03*
X786772Y228646D03*
X796374Y238714D03*
X790498Y242078D03*
X785729Y232971D03*
X795855Y246874D03*
X798075Y244297D03*
X789722Y256394D03*
X786461Y293028D03*
X790280Y287421D03*
X800155Y337368D03*
X800029Y333368D03*
X797141Y350368D03*
X795445Y356950D03*
X789581Y405011D03*
X793893Y409502D03*
X784804Y425371D03*
X794173Y450510D03*
X802136Y448334D03*
X788481Y474418D03*
Y477818D03*
Y488591D03*
Y491991D03*
Y518552D03*
Y521952D03*
Y532725D03*
Y536125D03*
X796000Y553101D03*
X788481Y571991D03*
Y568591D03*
Y586165D03*
Y582765D03*
Y600338D03*
Y596938D03*
Y614511D03*
Y611111D03*
X788600Y1006923D03*
X799631Y1025440D03*
X795631D03*
X789050Y1026150D03*
X796338Y1138130D03*
X793842Y1143384D03*
X797160Y1146609D03*
X792277Y1173065D03*
X799020Y1175975D03*
X798353Y1172011D03*
X787887Y1174500D03*
X798542Y1188345D03*
X792382Y1191664D03*
X794533Y1195766D03*
X794983Y1334030D03*
Y1331230D03*
X793548Y1397690D03*
X795296Y1416995D03*
X792848Y1414718D03*
X793459Y1429165D03*
X789647Y1427518D03*
X788648Y1422044D03*
X785820Y1425993D03*
X798601Y1431673D03*
X793288Y1450918D03*
X793744Y1437159D03*
X786787Y1433800D03*
X787694Y1442749D03*
X800607Y1440760D03*
X790361Y1447895D03*
X790754Y1441399D03*
X793994Y1441499D03*
X799057Y1449158D03*
X797083Y1467883D03*
X799057Y1456016D03*
X794005Y1464178D03*
X790296Y1463459D03*
X787038Y1460533D03*
X786591Y1452803D03*
X790989Y1455695D03*
X799314Y1475693D03*
X797318Y1471242D03*
X810411Y90650D03*
X815723Y90615D03*
X810161Y95236D03*
X805952Y301675D03*
X817456Y305368D03*
Y313368D03*
X809490Y305368D03*
X809466Y310604D03*
X801097Y325858D03*
X817100Y319600D03*
X809457Y330459D03*
X809490Y325368D03*
Y317368D03*
X809489Y313830D03*
X809490Y321368D03*
Y333368D03*
X816177Y441442D03*
X813456Y441474D03*
X810749Y443045D03*
X815840Y444091D03*
Y456060D03*
X810453Y453330D03*
X810406Y448214D03*
X810756Y471071D03*
Y468571D03*
X814580Y468806D03*
X814828Y472053D03*
X810756Y473571D03*
Y476071D03*
X813902Y730738D03*
X813678Y740979D03*
X813653Y746856D03*
X817584Y764219D03*
X813635Y762000D03*
X818000Y797000D03*
X817845Y817879D03*
X818500Y810135D03*
X813000Y805000D03*
X813548Y814000D03*
X813009Y819734D03*
X815500Y824000D03*
X815863Y830097D03*
X814299Y840877D03*
X813887Y835146D03*
X816037Y845578D03*
X812440Y862306D03*
X814080Y864464D03*
X812575Y880834D03*
X812219Y883586D03*
X817884Y915425D03*
X803673Y1025440D03*
X803453Y1134729D03*
X814835D03*
X806835D03*
X809632Y1142666D03*
X817964Y1157404D03*
X811507Y1157544D03*
X810018Y1167768D03*
X815037D03*
X814160Y1178240D03*
X814170Y1185205D03*
X805212Y1180175D03*
X805519Y1187215D03*
X815455Y1201043D03*
X811485D03*
X807489D03*
X804452Y1199814D03*
X804458Y1193112D03*
X809027Y1219895D03*
X807020Y1217900D03*
X812302Y1223170D03*
X815149Y1226016D03*
X810148Y1374884D03*
X806148Y1383715D03*
Y1375208D03*
X810204Y1401661D03*
X804654Y1404769D03*
X812901Y1432804D03*
X815901D03*
X810059Y1432778D03*
X812104Y1426483D03*
X809986Y1438785D03*
X812986D03*
X815986D03*
X809986Y1441485D03*
X812986D03*
X815986D03*
X812901Y1435504D03*
X815901D03*
X810001D03*
X803057Y1449158D03*
X801057Y1447158D03*
X805569Y1441519D03*
X803057Y1456016D03*
X801057Y1458016D03*
X802684Y1465549D03*
X801354Y1478681D03*
X807576Y1469584D03*
X804919Y1489247D03*
X828958Y79993D03*
Y77393D03*
Y74793D03*
Y85193D03*
Y82593D03*
X829002Y92874D03*
X820094Y95236D03*
X820044Y99961D03*
X831029Y104249D03*
Y107649D03*
X830651Y162368D03*
X828051D03*
X829362Y213213D03*
X818906Y207978D03*
Y212978D03*
Y215478D03*
Y210478D03*
X829362Y208213D03*
Y210713D03*
Y215713D03*
X822235Y264180D03*
X824735D03*
X822160Y258880D03*
X831129Y267526D03*
Y270026D03*
X822477Y309368D03*
X825971Y345101D03*
X829485D03*
X822626Y348066D03*
X818840Y444091D03*
X825103Y430358D03*
Y435558D03*
Y432958D03*
X831378Y433086D03*
Y435686D03*
Y430486D03*
X818840Y456060D03*
X824650Y455034D03*
Y450034D03*
X817328Y472053D03*
X820810Y471243D03*
X817380Y468806D03*
X823544Y475061D03*
Y472561D03*
X820810Y473743D03*
X828918Y480580D03*
X831418D03*
X831057Y484036D03*
X834282Y536085D03*
X828272Y535462D03*
X827291Y533100D03*
X829496Y676793D03*
X829784Y716589D03*
Y705489D03*
X823890Y703415D03*
X823670Y710542D03*
X824387Y726246D03*
X818307Y724144D03*
X821582Y727140D03*
X826484Y747127D03*
X827500Y750000D03*
X819788Y739634D03*
X830484Y738750D03*
X824500Y760500D03*
X830075Y769000D03*
X822151Y752283D03*
X824500Y756000D03*
X817365Y756827D03*
X824500Y778500D03*
Y774000D03*
Y782500D03*
X830075Y787000D03*
X824500Y796500D03*
X824342Y792315D03*
X824500Y800500D03*
X830075Y805000D03*
X824500Y814500D03*
X830075Y823000D03*
X829946Y829788D03*
X825721Y839816D03*
X830014Y833046D03*
X829757Y842672D03*
X822608Y848526D03*
X822916Y852576D03*
X823540Y857956D03*
X831654Y864494D03*
X831583Y853454D03*
X822938Y863298D03*
X826209Y866052D03*
X823234Y870830D03*
X833194Y873561D03*
X827992Y874107D03*
X826070Y893014D03*
X817152Y896380D03*
X817139Y890330D03*
X830063Y898500D03*
X819918Y889365D03*
X823900Y882083D03*
X824804Y898395D03*
X834465Y884538D03*
X829848Y914211D03*
X818031Y907747D03*
X825336Y916774D03*
X831057Y916745D03*
X834751Y922368D03*
X823552Y930700D03*
X829617Y939583D03*
X824414Y939655D03*
X816519Y931147D03*
X824168Y949538D03*
X825670Y964671D03*
X832423Y964669D03*
X828964Y977780D03*
X830356Y1116251D03*
X827856D03*
X825335Y1137129D03*
X819449Y1134534D03*
X819026Y1128137D03*
X825744Y1150087D03*
X823220Y1170767D03*
X818879Y1187310D03*
X823309Y1180235D03*
X823516Y1185238D03*
X819489Y1201039D03*
X823489Y1200969D03*
X823608Y1208993D03*
X819419Y1230265D03*
X817360Y1228226D03*
X816648Y1380758D03*
X824901Y1427404D03*
X827901D03*
X821901D03*
X818901Y1430104D03*
X821901D03*
X830901D03*
X827901D03*
X824901D03*
Y1432804D03*
X827901D03*
X830901D03*
X821901D03*
X818901D03*
X824901Y1435504D03*
X827901D03*
X821901D03*
X818901D03*
X821986Y1441485D03*
X818986D03*
Y1438785D03*
X821986D03*
X826204Y1444689D03*
Y1440689D03*
X826341Y1451236D03*
X826365Y1458974D03*
X826219Y1455244D03*
X837283Y98551D03*
X847837Y97475D03*
X840178Y114623D03*
Y111223D03*
X840833Y103783D03*
X847768Y106186D03*
X840178Y128796D03*
Y125396D03*
X837751Y165393D03*
Y162793D03*
Y170493D03*
Y167993D03*
X842754Y181009D03*
X839959Y181366D03*
X836748Y181426D03*
X847929Y168697D03*
X844675Y177616D03*
X845256Y172190D03*
X839573Y184012D03*
X836956Y184221D03*
X836234Y208695D03*
X833434D03*
X835934Y211695D03*
X840992Y213859D03*
Y211359D03*
X833434Y211695D03*
X844695Y213132D03*
Y215632D03*
X844939Y256303D03*
X844698Y265896D03*
X839611Y265701D03*
X849714Y266114D03*
X836429Y267526D03*
X833929D03*
Y270026D03*
X836429D03*
X841246Y281716D03*
X847187Y281982D03*
X842240Y324854D03*
X848879Y360849D03*
X845435Y356172D03*
X846098Y408715D03*
X849591Y411388D03*
X842515Y461382D03*
X850732Y469382D03*
X842779Y473076D03*
X842916Y467009D03*
X833293Y490636D03*
Y487836D03*
X833918Y480580D03*
X834215Y484138D03*
X844227Y479882D03*
X842476Y482382D03*
X833269Y506683D03*
X833953Y530621D03*
X848444Y657756D03*
X837272Y663910D03*
X839636Y666533D03*
X842352Y659243D03*
X842640Y662814D03*
X838152Y700215D03*
X845784Y705489D03*
Y716589D03*
X845850Y710969D03*
X845784Y708089D03*
X836078Y709619D03*
X835987Y713745D03*
X838484Y746701D03*
X846484Y738750D03*
X836713Y738751D03*
X842661Y769521D03*
X846000Y772079D03*
X840136Y830903D03*
X836839Y831301D03*
X836894Y824401D03*
X848224Y823502D03*
X835626Y843629D03*
X838189Y843459D03*
Y847490D03*
X835215Y847719D03*
X848384Y843459D03*
X846239Y847490D03*
X835553Y835119D03*
X848384Y839459D03*
Y835459D03*
X838194Y836962D03*
X848739Y847459D03*
X837183Y855459D03*
X840234Y851459D03*
X847138Y859459D03*
X839530Y859408D03*
X848384Y863459D03*
X846336Y855459D03*
X845820Y863413D03*
X848384Y851459D03*
X843574Y859423D03*
X837434Y851459D03*
X833327Y855560D03*
X837383Y879530D03*
X837396Y871459D03*
X840234Y875459D03*
X836999Y867413D03*
X845876Y879459D03*
X848384Y867459D03*
X845820Y867413D03*
X848384Y879459D03*
Y871459D03*
Y875459D03*
X837290Y887490D03*
X842827Y895443D03*
X835346Y891346D03*
X848322Y888421D03*
X848792Y896472D03*
X836066Y894955D03*
X847098Y891213D03*
X845633Y883492D03*
X845964Y887490D03*
X837276Y883459D03*
X848200Y883400D03*
X841329Y926602D03*
X841274Y914060D03*
X843315Y916612D03*
X836909Y916618D03*
Y914018D03*
X833683Y939579D03*
X836243D03*
X833683Y949105D03*
X836243D03*
X842856Y949146D03*
X836423Y964669D03*
X835431Y977775D03*
X840935Y1011499D03*
X844058Y1011738D03*
X848045Y1019310D03*
X848070Y1022190D03*
X839744Y1444959D03*
Y1440859D03*
Y1448959D03*
X836704Y1448849D03*
Y1440849D03*
X836744Y1444849D03*
X845306Y1438269D03*
X846844Y1454334D03*
X837685Y1453196D03*
X839744Y1457959D03*
X835474Y1457397D03*
X846044Y1451459D03*
X839744Y1461959D03*
X834475Y1460059D03*
X865059Y55513D03*
X861284Y68581D03*
X861297Y80581D03*
X853379Y76587D03*
Y72615D03*
X854818Y100625D03*
X859191Y112083D03*
X863480Y103621D03*
X850580Y118335D03*
Y132509D03*
Y121735D03*
Y135909D03*
X862826Y183834D03*
X862999Y172665D03*
X862936Y178560D03*
X849017Y191941D03*
X863812Y186629D03*
X857071Y192490D03*
X862346Y190185D03*
X863116Y200864D03*
X853029Y192300D03*
X853526Y206767D03*
X856026D03*
X851026D03*
X863205Y212455D03*
X863139Y207037D03*
X860506Y221642D03*
X852271Y228221D03*
Y231021D03*
X853656Y221708D03*
X856156D03*
X850571Y224421D03*
X851156Y221708D03*
X866015Y224536D03*
X852822Y236189D03*
X855322D03*
X857822D03*
X852763Y248765D03*
X855263D03*
X857763D03*
X852960Y268195D03*
Y270695D03*
X855460D03*
X864420Y265897D03*
X858260Y268195D03*
Y270695D03*
X861920Y265897D03*
X855460Y268195D03*
X863430Y309368D03*
Y316970D03*
X863114Y324505D03*
X863040Y330140D03*
X861770Y343006D03*
X852569Y356712D03*
X856069Y356426D03*
X854086Y374500D03*
X858586D03*
X863086D03*
X860586Y383000D03*
X861235Y394000D03*
X854086Y392999D03*
X864086Y384000D03*
X855017Y411969D03*
X861413Y417071D03*
X858827Y419896D03*
X858410Y413890D03*
X858767Y416685D03*
X861622Y419688D03*
X862882Y458991D03*
X854882D03*
X862882Y461791D03*
X854882D03*
X850748Y465382D03*
X861468Y483303D03*
Y487303D03*
X858169Y495032D03*
X853989Y630453D03*
Y632953D03*
X861663Y646653D03*
X855300Y646819D03*
X853982Y657506D03*
X859441Y678015D03*
X849680Y694789D03*
X858186Y701170D03*
X855646Y692710D03*
X864029Y688970D03*
X867455Y710611D03*
X858002Y707244D03*
X857986Y722670D03*
X854484Y746701D03*
X859199Y744517D03*
X854484Y738633D03*
X859000Y756000D03*
X849500Y758500D03*
Y763500D03*
X863443Y753254D03*
X859000Y764000D03*
Y760000D03*
Y774000D03*
X849500Y776500D03*
Y781500D03*
X861425Y770500D03*
X859000Y781000D03*
Y778000D03*
X853282Y789887D03*
X857632Y789385D03*
X859000Y792000D03*
X849500Y794500D03*
Y799500D03*
X861425Y788500D03*
X859000Y800000D03*
Y796000D03*
X861425Y806500D03*
X859000Y810000D03*
X849500Y812500D03*
X859000Y814000D03*
X850496Y831469D03*
X861425Y824500D03*
X849500Y817500D03*
X859000Y818000D03*
X851184Y839459D03*
Y835459D03*
X859165Y848728D03*
X851239Y847459D03*
X851184Y843459D03*
Y863459D03*
X862114Y859479D03*
X851184Y851459D03*
X859603Y863570D03*
X859461Y859459D03*
X851184Y867459D03*
Y871459D03*
Y875459D03*
X859234Y879600D03*
X859463Y866125D03*
X851184Y879459D03*
X849267Y892567D03*
X859614Y883800D03*
Y887846D03*
X850900Y888359D03*
X850800Y883500D03*
X858988Y898307D03*
X855524Y898505D03*
X864253Y918042D03*
X856628D03*
X849600Y918028D03*
X849205Y924129D03*
X867096Y935963D03*
X858601Y934505D03*
X853030Y934690D03*
X851925Y951350D03*
X850686Y1006923D03*
X853449Y1007048D03*
X863334Y1009393D03*
X861047Y1018909D03*
X860887Y1023208D03*
Y1026762D03*
X863956Y1020763D03*
X863689Y1024974D03*
X863944Y1432359D03*
Y1429359D03*
X860944Y1432359D03*
X857944Y1429359D03*
X860944D03*
Y1426359D03*
X857944D03*
X863944D03*
X857944Y1432359D03*
X863944Y1435359D03*
Y1441359D03*
Y1438359D03*
X860944Y1441359D03*
X857944Y1435359D03*
X860944D03*
X857944Y1441359D03*
Y1438359D03*
X860944D03*
X850544Y1447559D03*
X853514Y1457510D03*
X850644Y1457359D03*
X870519Y60438D03*
X867659Y60513D03*
X876200Y86012D03*
X867787Y85731D03*
X865427Y88801D03*
X876200Y94374D03*
X872293Y94279D03*
X868344Y94351D03*
X871341Y86046D03*
X871713Y168665D03*
Y176665D03*
Y196665D03*
Y192665D03*
X871826Y186778D03*
X871745Y204864D03*
Y208864D03*
X867386Y219379D03*
X883118Y262687D03*
X876622Y293721D03*
X872050Y302644D03*
X873262Y300030D03*
X869924Y305368D03*
X879112Y302369D03*
X877977Y305368D03*
Y309368D03*
X869924Y313368D03*
X877977D03*
Y325368D03*
Y317368D03*
Y321368D03*
X869924D03*
Y328722D03*
X874005Y344917D03*
X870413Y342791D03*
X869924Y333722D03*
X877977Y333368D03*
Y329368D03*
X872158Y359962D03*
X868086Y373750D03*
X876736Y383125D03*
X877909Y391731D03*
X880736Y383125D03*
X882925Y391099D03*
X872736Y391754D03*
X867586Y393000D03*
Y385000D03*
X869342Y407627D03*
X868586Y398500D03*
X877253Y420380D03*
X876917Y415322D03*
X879417D03*
X881190Y411619D03*
X878690D03*
X874253Y422880D03*
Y420080D03*
X877253Y422880D03*
X881271Y426952D03*
X878771D03*
X873536Y437408D03*
X876036D03*
X881036D03*
X878536D03*
X873771Y426952D03*
X876271D03*
X870882Y458991D03*
X880910Y454634D03*
Y457434D03*
Y460234D03*
X870882Y461791D03*
X869454Y479303D03*
X869954Y487303D03*
X882954Y486256D03*
X882195Y539204D03*
X867093Y554703D03*
X866938Y549771D03*
X878382Y554942D03*
X874649Y545296D03*
X876949Y571419D03*
X867093Y586828D03*
Y574703D03*
X881476Y588202D03*
X881131Y577349D03*
X875290Y578703D03*
X876351Y605023D03*
Y608523D03*
X879135Y632552D03*
X872862Y666859D03*
X878881Y667156D03*
X876286Y690970D03*
X868919Y700894D03*
X876286Y694970D03*
Y698970D03*
X881157Y749148D03*
X874142Y748914D03*
X879875Y753612D03*
X873728Y752692D03*
X875473Y742056D03*
X878670Y742841D03*
X869325Y761259D03*
X870017Y757313D03*
X867000Y774000D03*
X870000Y780000D03*
X879887Y784719D03*
X880040Y792851D03*
X867000Y792000D03*
X876402Y797415D03*
X874925Y800746D03*
X870035Y801032D03*
X867000Y810000D03*
X879916Y808965D03*
X877407Y828017D03*
X877818Y824214D03*
X876475Y830372D03*
X871600Y898584D03*
X872628Y918042D03*
X876628Y915242D03*
X880628Y918042D03*
X876628D03*
X872126Y934766D03*
X865830Y961600D03*
X870209Y949384D03*
X865973Y978187D03*
X874066Y977928D03*
X875391Y993796D03*
X872183Y993980D03*
X878976Y994020D03*
X871069Y1023114D03*
X878927Y1022387D03*
X878783Y1018751D03*
X872845Y1018988D03*
X866906Y1018751D03*
X866887Y1023208D03*
X875887D03*
X878887Y1026762D03*
X872887D03*
X866887D03*
X869741Y1025895D03*
X873824Y1071604D03*
X871224D03*
X876424D03*
Y1074104D03*
X871224D03*
X873824D03*
X868624Y1071604D03*
Y1074104D03*
X870057Y1091604D03*
X875257D03*
Y1089104D03*
X870057D03*
X872657D03*
X880115Y1084666D03*
X867457Y1091604D03*
Y1089104D03*
X872657Y1091604D03*
X875375Y1107647D03*
X872675D03*
X870075D03*
X867475D03*
X871364Y1120636D03*
X873964D03*
X876564D03*
X879264D03*
X875376Y1110175D03*
X872676D03*
X870076D03*
X867476D03*
X871364Y1139336D03*
X868664D03*
X879264Y1130336D03*
X876564D03*
X873964D03*
X871364D03*
X870522Y1148080D03*
X868022D03*
X875321Y1207654D03*
X872600Y1300833D03*
Y1298333D03*
X872944Y1432359D03*
Y1429359D03*
Y1426359D03*
X869944Y1432359D03*
Y1429359D03*
Y1426359D03*
X866944Y1432359D03*
Y1429359D03*
Y1426359D03*
X872944Y1435359D03*
Y1441359D03*
Y1438359D03*
X869944Y1435359D03*
X866944D03*
X869944Y1441359D03*
Y1438359D03*
X866944Y1441359D03*
Y1438359D03*
X881244Y1448859D03*
Y1440859D03*
X878244Y1451605D03*
X881244Y1464859D03*
Y1453059D03*
Y1456859D03*
X875744Y1453573D03*
X881244Y1476859D03*
X883233Y147540D03*
X887005Y141247D03*
X894472Y143740D03*
X891852Y148277D03*
X893284Y233339D03*
Y236739D03*
X895064Y250186D03*
X891383Y243203D03*
X896034Y243307D03*
X885884Y255118D03*
X897004Y257480D03*
X892484Y260860D03*
X887148Y249670D03*
X896953Y272012D03*
X886496Y268968D03*
X895140Y265236D03*
X886059Y284644D03*
X885918Y289500D03*
X885989Y309368D03*
Y305368D03*
Y317368D03*
X885953Y325368D03*
X885989Y313368D03*
X885953Y321368D03*
Y329368D03*
Y333368D03*
X896592Y358369D03*
Y354369D03*
X888812Y357372D03*
X883552Y357276D03*
X896592Y374369D03*
X891251Y387484D03*
X890553Y392038D03*
X887266Y400158D03*
Y405158D03*
Y402658D03*
X896579Y404043D03*
X893779D03*
X889979Y405743D03*
X890903Y454634D03*
Y457434D03*
Y460234D03*
X891454Y486303D03*
X892931Y534093D03*
X885931D03*
X891449Y547363D03*
X893949D03*
X886549Y553963D03*
X885556Y543664D03*
X887417Y566713D03*
X891673Y600049D03*
X891933Y618143D03*
X895933Y609696D03*
X883309Y666608D03*
X892461Y666671D03*
X886304Y666650D03*
X884903Y696678D03*
X884911Y690279D03*
X886836Y715970D03*
X893241Y704656D03*
X883686Y729778D03*
X889525Y722060D03*
X882098Y741565D03*
X884976Y740891D03*
X884463Y744757D03*
X881637Y744154D03*
X883126Y766124D03*
X883413Y759855D03*
X892040Y784511D03*
X889763Y788159D03*
X898737Y792289D03*
X889516Y792851D03*
X891916Y799605D03*
X884002Y797616D03*
X887916Y800815D03*
X895916Y808965D03*
X883916D03*
X887916D03*
X895829Y800660D03*
X883916Y800815D03*
X890326Y828548D03*
X895050D03*
X889178Y905619D03*
X884628Y915242D03*
Y918042D03*
X896553D03*
X892628Y915242D03*
X888628D03*
Y918042D03*
X882763Y933472D03*
X891367Y941126D03*
X888400Y994579D03*
X894660Y994330D03*
X891343Y994378D03*
X885099Y1021685D03*
X881887Y1023208D03*
X888743Y1019931D03*
X895394Y1026985D03*
X893147Y1020025D03*
X893887Y1023208D03*
X887887D03*
X890887Y1026762D03*
X884887D03*
X882779Y1074104D03*
Y1071604D03*
X887979Y1074104D03*
X885379D03*
X890579D03*
Y1071604D03*
X885379D03*
X887979D03*
X882615Y1084666D03*
X887862Y1088067D03*
X894004Y1081231D03*
X892856Y1102760D03*
X894249Y1114103D03*
X891549D03*
X888949D03*
X886349D03*
Y1123803D03*
X888949D03*
X891549D03*
X894249D03*
X895275Y1132870D03*
X892575D03*
X895547Y1145169D03*
X894713Y1210419D03*
X898878Y1214182D03*
X899286Y1219469D03*
X892532Y1220112D03*
X897169Y1225259D03*
X886888Y1263058D03*
X889388D03*
X891888D03*
X889388Y1260558D03*
X886888D03*
X891888D03*
X886926Y1298712D03*
X889729Y1295516D03*
X891107Y1314305D03*
X887342Y1314990D03*
X889244Y1444859D03*
X892244Y1449636D03*
Y1440859D03*
X889944Y1457959D03*
X889244Y1460859D03*
X895244Y1457510D03*
X889336Y1452554D03*
X893919Y1462132D03*
X889244Y1472859D03*
Y1468859D03*
X903035Y141247D03*
X907522Y143518D03*
X906622Y152373D03*
X909772Y152562D03*
X899573Y158195D03*
X910977Y243307D03*
Y248032D03*
Y262205D03*
X898048Y269387D03*
X913057Y311046D03*
X915653Y307438D03*
X899352Y308560D03*
Y311960D03*
X909298Y302347D03*
X905898D03*
X898533Y334498D03*
X908521Y356708D03*
X908625Y359317D03*
X905483Y355262D03*
X905000Y362158D03*
X898869Y351114D03*
X906161Y367191D03*
X913288Y372752D03*
X910646Y376084D03*
X906344Y372524D03*
X911072Y386992D03*
X897736Y383125D03*
X901747Y398492D03*
Y403492D03*
Y400992D03*
X910250Y457262D03*
Y454462D03*
X907450D03*
Y457262D03*
X910250Y451662D03*
X907450D03*
X910250Y460062D03*
X907450D03*
X910236Y465272D03*
X910759Y475511D03*
X899931Y534093D03*
X899530Y530753D03*
X914296Y558143D03*
X913728Y550495D03*
X899407Y560019D03*
X908846Y560124D03*
X910789Y598726D03*
X898207Y599891D03*
X900676Y621536D03*
X904076D03*
X909508Y621616D03*
X912908D03*
X900753Y656925D03*
X912462Y683770D03*
X909265Y677795D03*
X912462Y687770D03*
X906886Y702285D03*
X902236Y689332D03*
Y694332D03*
X908699Y709387D03*
X913247Y714204D03*
X902841Y703665D03*
X910836Y721570D03*
X913858Y721289D03*
X907866Y795572D03*
X911028Y796598D03*
X909785Y810778D03*
X903916Y810809D03*
X913716Y811954D03*
X899916Y808965D03*
X902641Y800748D03*
X907884Y829866D03*
X908920Y905630D03*
X900628Y918042D03*
X912628Y915242D03*
X908628Y918042D03*
X900628Y915242D03*
X912628Y918042D03*
X904838D03*
X908628Y915242D03*
X900983Y940895D03*
X903759Y951358D03*
X909811Y962400D03*
X913005Y969605D03*
X912690Y994350D03*
X897825Y994413D03*
X909166Y994188D03*
X897717Y1019915D03*
X899887Y1023208D03*
Y1026762D03*
X908422Y1023103D03*
X908856Y1017677D03*
X902389Y1081764D03*
X908799Y1093659D03*
Y1088659D03*
X908278Y1083484D03*
X908799Y1096659D03*
Y1100659D03*
X902353Y1104333D03*
X898278Y1136426D03*
X898047Y1145169D03*
X903959Y1207823D03*
X906784Y1216607D03*
X913784Y1221057D03*
X910633Y1222799D03*
X906309Y1226647D03*
X909077Y1232724D03*
X899699Y1283872D03*
X910788Y1299456D03*
X906506Y1299188D03*
X902908Y1299828D03*
X911117Y1314130D03*
X902875Y1309301D03*
X905740Y1309264D03*
X908700Y1316300D03*
X911135Y1345560D03*
X904177Y1359955D03*
X899944Y1432359D03*
X908944Y1426359D03*
Y1429359D03*
Y1432359D03*
X911944Y1426359D03*
Y1429359D03*
Y1432359D03*
X905944Y1426359D03*
X899944D03*
X902944D03*
Y1429359D03*
X899944D03*
X902944Y1432359D03*
X905944Y1429359D03*
Y1432359D03*
X902944Y1438359D03*
X899944D03*
Y1441359D03*
X902944Y1435359D03*
X899944D03*
X908944Y1438359D03*
Y1441359D03*
X911944Y1438359D03*
Y1441359D03*
X902944D03*
X905944Y1438359D03*
Y1441359D03*
X908944Y1435359D03*
X911944D03*
X905944D03*
X919175Y116594D03*
X930118Y110784D03*
X925118D03*
X919175Y119594D03*
X924675Y124879D03*
X929697Y124663D03*
X919609Y124283D03*
X931041Y138838D03*
X918016Y161306D03*
X915267Y157370D03*
X916453Y167975D03*
X927898Y203256D03*
X925098D03*
X919577Y240945D03*
Y250394D03*
Y271654D03*
X919616Y268462D03*
X919577Y264567D03*
X923732Y304585D03*
X917882Y328216D03*
Y324816D03*
X915954Y344150D03*
X916229Y336333D03*
X919354Y344150D03*
X919629Y336333D03*
X927964Y344041D03*
X924564D03*
X923311Y349959D03*
X929943Y372600D03*
X921343Y376888D03*
X916330Y377748D03*
X929947Y376821D03*
X915072Y386992D03*
X914323Y398551D03*
Y403551D03*
Y401051D03*
X927563Y424445D03*
X924763D03*
X921963D03*
X927280Y436716D03*
X921680D03*
X924480D03*
X917541Y441280D03*
Y443780D03*
X927766Y456442D03*
X927596Y447453D03*
X921973Y469328D03*
X927401Y469059D03*
X916593Y469140D03*
X928999Y477948D03*
X920999D03*
X924999D03*
X917811Y544325D03*
X923453Y569578D03*
X923642Y561578D03*
X919080Y587640D03*
X921507Y578791D03*
X919038Y579378D03*
X923599Y581578D03*
X921217Y589216D03*
X913998Y597103D03*
X925949Y612363D03*
Y608863D03*
X922626Y633772D03*
X915800Y629700D03*
X918300D03*
X929690Y666593D03*
X920090Y666714D03*
X928353Y686342D03*
X928704Y680261D03*
X921061Y715386D03*
X926961Y723797D03*
X914202Y797460D03*
X923872Y798271D03*
X922352Y800809D03*
X917803Y811365D03*
X927916Y800909D03*
X929790Y828603D03*
X927916Y817015D03*
X925228Y816934D03*
X929181Y895029D03*
X921451Y903800D03*
X920628Y918042D03*
X916628D03*
X924628D03*
X928628D03*
X924628Y915242D03*
X920628D03*
X928628D03*
X916628D03*
X914193Y945318D03*
X928227Y951125D03*
X921364Y951251D03*
X918265Y969745D03*
X923289Y965780D03*
X926796Y966297D03*
X929741Y967006D03*
X916932Y994405D03*
X924956Y994321D03*
X924864Y1026762D03*
Y1023208D03*
X925024Y1018909D03*
X927861Y1024768D03*
X916749Y1084659D03*
X916992Y1076659D03*
X916749Y1092664D03*
X916875Y1098643D03*
X916749Y1104659D03*
X914637Y1210568D03*
Y1214838D03*
X930754Y1310564D03*
X924650Y1327819D03*
Y1324419D03*
X914033Y1345613D03*
X927193Y1361547D03*
X931159Y1379427D03*
X920360Y1387039D03*
X920255Y1383264D03*
X931199Y1371951D03*
X931159Y1390827D03*
Y1406027D03*
X914944Y1426359D03*
Y1429359D03*
Y1432359D03*
Y1438359D03*
Y1441359D03*
Y1435359D03*
X921498Y1446692D03*
X925697Y1460109D03*
X917744Y1453573D03*
X920244Y1451605D03*
X919285Y1456226D03*
X924803Y1474743D03*
X925435Y1478114D03*
X940761Y97667D03*
X945011Y95111D03*
X931144Y116594D03*
X936417Y102495D03*
X931144Y119594D03*
X942561Y118342D03*
Y132515D03*
Y121742D03*
X934678Y125107D03*
X942561Y135915D03*
X936151Y142862D03*
X943292Y143762D03*
X937192Y148717D03*
X945406Y180347D03*
X940406D03*
X942906D03*
X947424Y184419D03*
X944424Y186919D03*
X944760Y191977D03*
X942260D03*
X940487Y195680D03*
X942987D03*
X944424Y184419D03*
X934411Y202141D03*
X931698Y201556D03*
X934411Y207141D03*
X934477Y211491D03*
X934411Y204641D03*
X946234Y213390D03*
X942179Y215727D03*
X937438Y213817D03*
X936395Y218142D03*
X933403Y245507D03*
X936962Y249807D03*
X944248Y239844D03*
X945018Y276051D03*
X943183Y281652D03*
X930727Y302571D03*
X937000Y312284D03*
Y315684D03*
X942731Y324044D03*
X939331D03*
X940997Y331912D03*
Y335312D03*
X942700Y346363D03*
X939300D03*
X934128Y355168D03*
X934464Y358618D03*
X944238Y360828D03*
X934047Y369160D03*
X936175Y364823D03*
X931072Y386992D03*
X941872Y440942D03*
X933424Y458455D03*
X933161Y451442D03*
X933404Y463462D03*
X933412Y468942D03*
X936653Y526836D03*
X944351Y534211D03*
X948532Y541135D03*
X939992Y527726D03*
Y548726D03*
Y544726D03*
X948598Y546553D03*
X948621Y552726D03*
X931627Y557641D03*
Y569578D03*
Y581578D03*
Y577578D03*
Y573578D03*
X933725Y585936D03*
X933741Y598087D03*
Y594687D03*
X933725Y589336D03*
X944296Y611071D03*
X941859Y621311D03*
Y629311D03*
X943181Y632536D03*
X945434Y634325D03*
X941859Y625311D03*
X946128Y666522D03*
X935281Y680945D03*
X936026Y727450D03*
X933974Y719371D03*
X942676Y789286D03*
X933201Y798297D03*
X946970Y786366D03*
X944916Y808965D03*
X938357Y808856D03*
X931916Y817015D03*
X942858Y819430D03*
X945736Y819397D03*
X935124Y831382D03*
X940100Y830700D03*
X935262Y825135D03*
X932418D03*
X940716Y840074D03*
X944297Y839975D03*
X933021Y840893D03*
X933054Y843804D03*
X937200Y841000D03*
X936450Y858327D03*
X937551Y860801D03*
X932770Y878233D03*
X935765Y878317D03*
X934928Y871727D03*
X932319Y871626D03*
X938729Y874396D03*
X945982Y886737D03*
X932300Y890200D03*
X942194Y891216D03*
X930800Y904840D03*
X941592Y900908D03*
X936628Y915242D03*
X940628D03*
X932628D03*
X936628Y918042D03*
X932628D03*
X936371Y951484D03*
X940716Y951733D03*
X946363Y951179D03*
X935255Y962725D03*
X945671Y982191D03*
X940015Y1020176D03*
X934911Y1023579D03*
X945864Y1023208D03*
X930864Y1026762D03*
X936864D03*
X942864D03*
X939864Y1023208D03*
X930864D03*
X930883Y1018751D03*
X936822Y1018988D03*
X942760Y1018751D03*
X943093Y1021769D03*
X932289Y1074182D03*
Y1071682D03*
X937489Y1074182D03*
X934889D03*
X940089D03*
Y1071682D03*
X934889D03*
X937489D03*
X944092Y1084666D03*
X931628Y1091409D03*
Y1088909D03*
X936828Y1091409D03*
X934228D03*
X939428D03*
Y1088909D03*
X934228D03*
X936828D03*
X943241Y1120636D03*
X940541D03*
X937941D03*
X935341D03*
X937941Y1130336D03*
X940541D03*
X943241D03*
X932641Y1139336D03*
X935341Y1130336D03*
Y1139336D03*
X934500Y1147708D03*
X932000D03*
X939298Y1207654D03*
X943891Y1306608D03*
X944207Y1320739D03*
X947308Y1325035D03*
X931137Y1375878D03*
X931159Y1383227D03*
X939559Y1398427D03*
X931159Y1394627D03*
Y1387027D03*
Y1398427D03*
Y1402227D03*
X939559D03*
X944235Y1406262D03*
X943725Y1430744D03*
Y1427744D03*
X934725Y1430744D03*
X940725Y1427744D03*
Y1430744D03*
X934725Y1427744D03*
X937725D03*
Y1430744D03*
X943725Y1433744D03*
Y1439744D03*
Y1436744D03*
X940725Y1433744D03*
Y1439744D03*
Y1436744D03*
X934725Y1433744D03*
X937725D03*
X934725Y1439744D03*
X937725D03*
X934725Y1436744D03*
X937725D03*
X937671Y1492139D03*
Y1488139D03*
X949221Y103411D03*
X949615Y97667D03*
X960411Y90650D03*
X960161Y95236D03*
X949861Y111255D03*
Y114655D03*
X949380Y106561D03*
X949861Y125428D03*
Y128828D03*
X947906Y180347D03*
X947424Y187219D03*
X950177Y215730D03*
X947040Y223885D03*
X948741Y229468D03*
X948785Y242464D03*
X951278Y250583D03*
X946482Y255940D03*
X949974Y291554D03*
X947733Y319680D03*
X950953Y317947D03*
X960376Y392807D03*
X962769Y451419D03*
X959816Y472905D03*
X955816Y473419D03*
Y464919D03*
X963816Y464419D03*
X962563Y485128D03*
X954182Y481467D03*
X958124Y492354D03*
X958736Y482165D03*
X958974Y504825D03*
X956474D03*
X953974D03*
X949823Y491982D03*
X959600Y496486D03*
X949823Y495982D03*
X957977Y500202D03*
X958915Y517401D03*
X956415D03*
X953915D03*
X959466Y522569D03*
Y525369D03*
X958081Y531882D03*
X955581D03*
X961166Y529169D03*
X952531Y531948D03*
X960581Y531882D03*
X948905Y534909D03*
X958016Y555194D03*
X960816D03*
X958016Y563194D03*
X960816D03*
Y571194D03*
X958016D03*
X959573Y581222D03*
X962373D03*
X959573Y591215D03*
X962373D03*
X962545Y607762D03*
X959745D03*
Y610562D03*
X962545D03*
X950479Y622285D03*
X954535Y610548D03*
X950667Y616905D03*
X963365Y628078D03*
X961352Y633736D03*
X950865Y633724D03*
X950748Y627713D03*
X956345Y633716D03*
X949137Y666660D03*
X954526Y666671D03*
X947556Y699550D03*
X956023Y706907D03*
X951151Y730111D03*
X963869Y725057D03*
X955950Y734178D03*
X957763Y725336D03*
X959950Y734178D03*
X957579Y744168D03*
X953837Y763025D03*
X950699Y779711D03*
X956017Y770300D03*
X957500Y780800D03*
X955076Y784861D03*
X950475Y789361D03*
X955225Y788984D03*
X949609Y796051D03*
X957487Y798553D03*
X951461Y812223D03*
X951791Y808121D03*
X957379Y826586D03*
X954760Y826734D03*
X951708Y818894D03*
X955712Y833988D03*
X956239Y829577D03*
X960100Y846665D03*
X954700Y837700D03*
X961175Y838525D03*
X955343Y866850D03*
X955850Y862902D03*
X957900Y856300D03*
X950300Y877800D03*
X953240Y876834D03*
X949382Y886737D03*
X954567Y927654D03*
X964280Y927777D03*
X958567Y927654D03*
X947029Y915242D03*
X959545Y918306D03*
X951863Y936168D03*
X957235Y936398D03*
X962329Y936229D03*
X957671Y977921D03*
X949671D03*
X961671Y991564D03*
X953671D03*
X949671D03*
X953671Y982191D03*
X954937Y1021998D03*
X948864Y1026762D03*
X954864D03*
X951864Y1023208D03*
X957864D03*
X957678Y1018555D03*
X961208Y1018592D03*
X960636Y1021917D03*
X959371Y1026985D03*
X948975Y1021325D03*
X951956Y1071604D03*
X949356D03*
X954556D03*
Y1074104D03*
X949356D03*
X951956D03*
X946756Y1071604D03*
Y1074104D03*
X946592Y1084666D03*
X957981Y1081231D03*
X951839Y1088067D03*
X956833Y1102760D03*
X950326Y1114103D03*
Y1123803D03*
X952926D03*
X955526D03*
Y1114103D03*
X958226D03*
X952926D03*
X958226Y1123803D03*
X956552Y1132870D03*
X959252D03*
X962255Y1136426D03*
X962024Y1145169D03*
X959524D03*
X958690Y1210419D03*
X963263Y1219469D03*
X962855Y1214182D03*
X956509Y1220112D03*
X961146Y1225259D03*
X950865Y1263058D03*
X953365D03*
X955865D03*
X953365Y1260558D03*
X950865D03*
X955865D03*
X948259Y1295965D03*
X948832Y1371654D03*
X951832D03*
X952561Y1383465D03*
X952417Y1379528D03*
X949469D03*
X949385Y1375591D03*
X952385D03*
X952514Y1391339D03*
X952395Y1395276D03*
X952716Y1387402D03*
X952180Y1407087D03*
X950239Y1409555D03*
X948235Y1406262D03*
X946725Y1427744D03*
Y1430744D03*
X949725D03*
Y1427744D03*
X960883Y1427997D03*
Y1430997D03*
X946725Y1433744D03*
X949725D03*
X946725Y1439744D03*
X949725D03*
X946725Y1436744D03*
X949725D03*
X960883Y1433997D03*
Y1436997D03*
Y1439997D03*
X952695Y1444139D03*
X979002Y92874D03*
X965723Y90615D03*
X970094Y95236D03*
X970044Y99961D03*
X978051Y162368D03*
X968906Y207978D03*
Y212978D03*
Y215478D03*
Y210478D03*
X970865Y264068D03*
X973365D03*
X972160Y258880D03*
X977150Y331972D03*
Y338972D03*
X975631Y343112D03*
Y346612D03*
X971721Y407762D03*
X968348Y402369D03*
X971826Y430187D03*
X966694Y427599D03*
X968462Y429368D03*
X970840Y457339D03*
X968340D03*
X962816Y442919D03*
X972030Y446071D03*
X979910Y445603D03*
X970840Y459839D03*
Y462339D03*
X968340D03*
Y459839D03*
X963816Y472905D03*
X976397Y473045D03*
X972397Y465004D03*
X977327Y462371D03*
X965412Y485138D03*
X969297Y478625D03*
Y475825D03*
X970997Y482425D03*
X970412Y485138D03*
X967912D03*
X976873Y491214D03*
Y493714D03*
X970745Y539731D03*
X967042Y537658D03*
X970745Y542231D03*
X978303Y541895D03*
X975803D03*
X967042Y540458D03*
X975503Y544895D03*
X978303D03*
X978581Y582747D03*
X965173Y581222D03*
X978032Y590801D03*
X965173Y591215D03*
X977857Y597130D03*
X976027Y620653D03*
Y617853D03*
X968145Y610562D03*
X965345Y607762D03*
Y610562D03*
X968145Y607762D03*
X977857Y605443D03*
X973857D03*
X972354Y627908D03*
X968365Y633473D03*
X978865Y642184D03*
X966797Y667653D03*
X970197D03*
X965774Y706907D03*
X973712Y722064D03*
X968589Y722434D03*
X970839Y729923D03*
X965042Y722234D03*
X971081Y722637D03*
X978352Y730766D03*
X963950Y734178D03*
X973450Y747280D03*
X965983Y763567D03*
X966127Y776382D03*
X968094Y799792D03*
X976186Y789819D03*
X967562Y802982D03*
X978978Y817618D03*
X978214Y821224D03*
X967337Y828901D03*
X970040Y842903D03*
X969309Y839334D03*
X974437Y849140D03*
X973510Y834991D03*
X967842Y864801D03*
X970299Y853773D03*
X978880Y869552D03*
X967510Y868971D03*
X966813Y904556D03*
X973988Y910038D03*
X968507Y937615D03*
X971443Y938828D03*
X965671Y991564D03*
Y982191D03*
X963864Y1026762D03*
Y1023208D03*
X966366Y1081764D03*
X972776Y1093659D03*
X972255Y1083484D03*
X972776Y1088659D03*
Y1096659D03*
X966330Y1104333D03*
X972776Y1100659D03*
X967936Y1207823D03*
X978614Y1210568D03*
X970761Y1216607D03*
X978614Y1214838D03*
X978169Y1221268D03*
X974985Y1290950D03*
X979996Y1386100D03*
X963883Y1430997D03*
Y1427997D03*
X966883Y1430997D03*
Y1427997D03*
X969883D03*
Y1430997D03*
X975883Y1427997D03*
Y1430997D03*
X972883D03*
Y1427997D03*
X963883Y1433997D03*
X966883D03*
X969883D03*
X963883Y1436997D03*
Y1439997D03*
X966883Y1436997D03*
Y1439997D03*
X969883Y1436997D03*
Y1439997D03*
X975883Y1433997D03*
X972883D03*
X975883Y1436997D03*
X972883D03*
X975883Y1439997D03*
X972883D03*
X977547Y1546081D03*
X974547D03*
X971547D03*
X978958Y85193D03*
Y82593D03*
Y77393D03*
Y74793D03*
Y79993D03*
X987283Y98551D03*
X990178Y114623D03*
Y111223D03*
X990833Y103783D03*
X981029Y104249D03*
Y107649D03*
X990178Y128796D03*
Y125396D03*
X985595Y147540D03*
X989367Y141247D03*
X996834Y143740D03*
X994214Y148277D03*
X980651Y162368D03*
X987751Y162793D03*
Y165393D03*
Y167993D03*
Y170493D03*
X995256Y172190D03*
X994675Y177616D03*
X989959Y181366D03*
X986748Y181426D03*
X992754Y181009D03*
X986956Y184221D03*
X989573Y184012D03*
X994695Y213132D03*
X979362Y208213D03*
Y210713D03*
Y213213D03*
X986234Y208695D03*
X983434D03*
X985934Y211695D03*
X990992Y213859D03*
Y211359D03*
X983434Y211695D03*
X979362Y215713D03*
X994695Y215632D03*
X994939Y256303D03*
X989611Y265701D03*
X994698Y265896D03*
X986429Y270026D03*
X983929D03*
X981129D03*
X983929Y267526D03*
X986429D03*
X981129D03*
X991246Y281716D03*
X997187Y281982D03*
X987517Y314092D03*
X993552Y318175D03*
X990420Y340454D03*
Y337954D03*
X989630Y343862D03*
X983717Y341665D03*
X983956Y346652D03*
X993026Y353813D03*
X981719Y352217D03*
X988631Y349496D03*
X980045Y366559D03*
X986373Y370467D03*
X991392Y409230D03*
X985303Y464652D03*
Y462152D03*
Y459652D03*
X987803Y464652D03*
Y462152D03*
Y459652D03*
X981843Y464818D03*
X992206Y491133D03*
Y498633D03*
X988134Y495151D03*
X985634D03*
X980576Y492987D03*
X985334Y498151D03*
X980576Y495487D03*
X988134Y498151D03*
X992206Y493633D03*
Y496133D03*
X982375Y537877D03*
X992306Y555897D03*
Y553297D03*
X989888Y548366D03*
X987388D03*
X982388D03*
X984888D03*
X982375Y542877D03*
Y545377D03*
Y540377D03*
X992306Y561097D03*
Y563697D03*
Y566797D03*
Y558497D03*
X986301Y570686D03*
X989096Y570478D03*
X989513Y576484D03*
X989156Y573689D03*
X986510Y573303D03*
X992906Y578405D03*
X981857Y597232D03*
X991907Y596782D03*
X986688Y596089D03*
X983843Y619513D03*
Y616713D03*
Y613913D03*
X993857Y605443D03*
X981857Y605637D03*
X980703Y625013D03*
X986600Y717641D03*
X987461Y745796D03*
X981876Y745179D03*
X988371Y764143D03*
X983786Y765647D03*
X984357Y777555D03*
X997051Y778833D03*
X990699Y778630D03*
X987990Y774005D03*
X987394Y787490D03*
X987501Y812573D03*
X985921Y805135D03*
X994051Y810871D03*
X996385Y816141D03*
X979203Y829159D03*
X994094Y829000D03*
X982300Y821200D03*
X987702Y829159D03*
X989700Y846500D03*
X987202Y846395D03*
X987319Y843589D03*
X979203Y833159D03*
X989800Y843900D03*
X987200Y848940D03*
X987703Y837159D03*
X990457Y852043D03*
X983269Y853883D03*
X981700Y856300D03*
X979891Y876589D03*
X992441Y870398D03*
X988054Y888283D03*
X990300Y897500D03*
X979592Y902849D03*
X982783Y909995D03*
X979498Y907500D03*
X989311Y920364D03*
X983227Y968565D03*
X988240Y1020015D03*
Y1016923D03*
Y1023968D03*
X984909Y1081071D03*
X983751Y1078675D03*
X980969Y1076659D03*
X980726Y1084659D03*
X980852Y1098643D03*
X980726Y1104659D03*
Y1092664D03*
X986645Y1108465D03*
X989513Y1097683D03*
X995009Y1131223D03*
X991763Y1140378D03*
Y1128378D03*
Y1134378D03*
X984558Y1140774D03*
X988112Y1137774D03*
X984558Y1128774D03*
Y1134774D03*
X987804Y1131619D03*
X984817Y1303297D03*
X979001Y1288925D03*
X990613Y1324248D03*
Y1327048D03*
X993413Y1324248D03*
Y1327048D03*
X990501Y1320756D03*
X988784Y1361974D03*
X980139Y1381496D03*
X980166Y1373622D03*
X980203Y1377559D03*
X980047Y1397245D03*
X985448Y1398271D03*
X980092Y1389370D03*
X980139Y1393308D03*
X984136Y1401636D03*
X987136D03*
X986949Y1430997D03*
Y1427997D03*
X983949D03*
X989949Y1430997D03*
Y1427997D03*
X983949Y1430997D03*
X992949Y1427997D03*
Y1430997D03*
X986949Y1433997D03*
X983949D03*
X989949D03*
X992949D03*
X986949Y1436997D03*
X983949D03*
X986949Y1439997D03*
X983949D03*
X989949Y1436997D03*
Y1439997D03*
X992949Y1436997D03*
Y1439997D03*
X978934Y1444392D03*
X978987Y1489832D03*
X982241Y1489637D03*
X986773Y1546081D03*
X983773D03*
X980773D03*
X1011187Y-33526D03*
Y-30126D03*
X1011284Y68581D03*
X1011297Y80581D03*
X1003379Y72615D03*
Y76587D03*
X1004818Y100625D03*
X997837Y97475D03*
X1013480Y103621D03*
X997768Y106186D03*
X1009191Y112083D03*
X1000580Y121735D03*
Y118335D03*
Y132509D03*
Y135909D03*
X1005397Y141247D03*
X1009884Y143518D03*
X1008984Y152373D03*
X1012936Y178560D03*
X997929Y168697D03*
X1012826Y183834D03*
X1012999Y172665D03*
X999017Y191941D03*
X1003029Y192300D03*
X1012346Y190185D03*
X1007071Y192490D03*
X1013116Y200864D03*
X1003526Y206767D03*
X1006026D03*
X1001026D03*
X1010291Y199582D03*
X1013139Y207037D03*
X1013205Y212455D03*
X1002271Y228221D03*
Y231021D03*
X1010506Y221642D03*
X1003656Y221708D03*
X1006156D03*
X1000571Y224421D03*
X1001156Y221708D03*
X1002822Y236189D03*
X1005322D03*
X1007822D03*
X1002763Y248765D03*
X1005263D03*
X1007763D03*
X999714Y266114D03*
X1008260Y268195D03*
X1005460D03*
X1002960D03*
X1008260Y270695D03*
X1002960D03*
X1005460D03*
X1000698Y300276D03*
X1002580Y309619D03*
X1010499Y309062D03*
X1003181Y323057D03*
X1001105Y318006D03*
X1009770Y344486D03*
X997020Y345354D03*
X1003076Y332496D03*
X1000420Y353954D03*
X996024Y352132D03*
X1001825Y581659D03*
X998332Y578986D03*
X997857Y596729D03*
X995913Y619758D03*
Y616958D03*
Y614158D03*
X1001857Y605443D03*
X1003900Y628700D03*
X1001605Y627605D03*
X1005800Y637600D03*
X1002883Y622521D03*
X1001676Y678015D03*
X1011185Y724519D03*
X1009562Y722438D03*
X1003990Y765899D03*
X1007990D03*
X1002751Y757169D03*
X999990Y764566D03*
X1013151Y756726D03*
X1012695Y776728D03*
X999990Y774671D03*
X1013319Y785929D03*
X1007027Y792973D03*
X998376Y810970D03*
X1006054Y810969D03*
X1010699Y803454D03*
X1002699Y819475D03*
X1011144Y844340D03*
X1010977Y841737D03*
X1012703Y837659D03*
X1001187Y850084D03*
X1004577Y853679D03*
X1004713Y871389D03*
X998313Y888295D03*
X1005413Y905295D03*
X1004953Y923995D03*
X1008935Y924007D03*
X1004994Y955372D03*
X1007919Y948822D03*
X1011019D03*
X1004719D03*
X1012219Y954222D03*
X1006222Y980337D03*
X1009564Y988874D03*
X999879Y998507D03*
X1001805Y1007522D03*
X1008571Y1006648D03*
X1008759Y1023900D03*
X1002180Y1013678D03*
X1002652Y1023731D03*
X1005938Y1018307D03*
X995317Y1137378D03*
X996213Y1324248D03*
Y1327048D03*
X1009333Y1346693D03*
Y1343293D03*
X998600Y1369200D03*
X1008387Y1380797D03*
X998600Y1373400D03*
X997401Y1381200D03*
X999283Y1377400D03*
X1007850Y1368835D03*
X998643Y1398271D03*
X1008138Y1407186D03*
Y1409986D03*
X1005338Y1407186D03*
Y1409986D03*
X1008138Y1415586D03*
Y1412786D03*
X1005338Y1415586D03*
Y1412786D03*
X1008138Y1418386D03*
X1005338D03*
X998949Y1427997D03*
Y1430997D03*
X995949D03*
Y1427997D03*
X1009981Y1431097D03*
Y1428097D03*
X1006981D03*
Y1431097D03*
X998949Y1433997D03*
X995949D03*
X998949Y1436997D03*
X995949D03*
X998949Y1439997D03*
X995949D03*
X1009981Y1434097D03*
X1006981D03*
X1009981Y1437097D03*
X1006981D03*
X1009981Y1440097D03*
X1006981D03*
X1002194Y1444392D03*
X1015059Y55513D03*
X1020519Y60438D03*
X1017659Y60513D03*
X1026200Y86012D03*
X1017787Y85731D03*
X1026200Y94374D03*
X1015427Y88801D03*
X1022293Y94279D03*
X1018344Y94351D03*
X1021341Y86046D03*
X1021537Y116594D03*
X1027480Y110784D03*
X1021537Y119594D03*
X1021971Y124283D03*
X1027037Y124879D03*
X1020378Y161306D03*
X1012134Y152562D03*
X1017629Y157370D03*
X1021713Y176665D03*
Y168665D03*
X1013812Y186629D03*
X1021713Y196665D03*
X1021826Y186778D03*
X1021713Y192665D03*
X1021745Y204864D03*
Y208864D03*
X1026794Y218085D03*
X1017386Y219379D03*
X1018014Y228631D03*
X1023502Y248371D03*
X1014420Y265897D03*
X1011920D03*
X1027216Y289440D03*
X1022604Y290262D03*
X1016635Y300276D03*
X1012635D03*
X1025749D03*
X1020635D03*
X1022435Y312865D03*
X1021848Y310396D03*
X1020406Y350772D03*
X1012188Y443421D03*
X1015659Y679654D03*
Y683054D03*
X1021885Y698974D03*
X1022937Y691421D03*
X1014641Y724436D03*
X1012851Y722417D03*
X1026916Y719769D03*
X1018015Y751565D03*
X1013486Y750773D03*
X1024684Y756485D03*
X1017664Y779101D03*
X1014064Y793660D03*
X1018071Y798490D03*
X1013821Y813520D03*
X1014781Y810319D03*
X1017955Y812097D03*
X1021895Y818974D03*
X1020703Y837659D03*
X1013918Y851306D03*
X1017800Y867065D03*
X1016973Y877196D03*
X1016574Y874537D03*
X1016798Y890299D03*
X1021408Y895008D03*
X1024913Y884000D03*
X1012842Y910685D03*
X1022346Y917669D03*
X1029570Y917718D03*
X1018419Y917575D03*
X1014719Y938322D03*
X1027319D03*
X1027719Y958822D03*
X1014009Y980356D03*
X1018009D03*
X1014009Y988813D03*
X1018009D03*
X1021924Y980456D03*
X1026009Y988813D03*
X1022009D03*
X1017998Y1009655D03*
X1015198D03*
X1024570Y1024003D03*
X1011782Y1016591D03*
X1022143Y1030672D03*
X1019143D03*
X1016143D03*
X1025143D03*
X1023144Y1109564D03*
X1017297D03*
X1023144Y1122164D03*
X1017297D03*
X1023144Y1134764D03*
X1017297D03*
X1023144Y1147364D03*
X1017297D03*
X1023144Y1159964D03*
X1017297D03*
Y1172564D03*
X1023162Y1174445D03*
X1023139Y1184856D03*
X1017297Y1185164D03*
X1026221Y1214372D03*
X1021976Y1218169D03*
X1023358Y1363921D03*
X1013991Y1360842D03*
X1019391Y1377061D03*
X1012981Y1431097D03*
Y1428097D03*
X1015981D03*
Y1431097D03*
X1021981Y1428097D03*
Y1431097D03*
X1018981D03*
Y1428097D03*
X1012981Y1434097D03*
X1015981D03*
X1012981Y1437097D03*
Y1440097D03*
X1015981Y1437097D03*
Y1440097D03*
X1021981Y1434097D03*
X1018981D03*
X1021981Y1437097D03*
X1018981D03*
X1021981Y1440097D03*
X1018981D03*
X1025615Y1444492D03*
X1020023Y1489637D03*
X1016769Y1489832D03*
X1043123Y97667D03*
X1033506Y116594D03*
X1038779Y102495D03*
X1032480Y110784D03*
X1033506Y119594D03*
X1037040Y125107D03*
X1032059Y124663D03*
X1038513Y142862D03*
X1045654Y143762D03*
X1039554Y148717D03*
X1033403Y138838D03*
X1042102Y195176D03*
X1042183Y210509D03*
X1029594Y218085D03*
X1036107Y221970D03*
X1036173Y226320D03*
X1036107Y219470D03*
Y216970D03*
X1033394Y216385D03*
X1043875Y230556D03*
X1039134Y228646D03*
X1042860Y242078D03*
X1038091Y232971D03*
X1034741Y244571D03*
X1032121Y249108D03*
X1042084Y256394D03*
X1037290Y296293D03*
X1033890D03*
X1045650Y300093D03*
X1029639Y300141D03*
X1041783Y321114D03*
X1030220Y313554D03*
X1042948Y333696D03*
X1043106Y340230D03*
X1031259Y350427D03*
X1029885Y711762D03*
X1033200Y731700D03*
X1035619Y755809D03*
X1038344Y756476D03*
X1043016Y782161D03*
X1038678Y776750D03*
X1039251Y812340D03*
X1042414Y801443D03*
X1043425Y830800D03*
X1043626Y836563D03*
X1041100Y838500D03*
X1037527Y836486D03*
X1031813Y850273D03*
X1046045Y841217D03*
X1040822Y841339D03*
X1044390Y861210D03*
X1035185Y862793D03*
X1037685Y862789D03*
X1038363Y875288D03*
X1037709Y886209D03*
X1038010Y902565D03*
X1033019Y933022D03*
Y935822D03*
X1030819Y938422D03*
X1033370Y953994D03*
X1038009Y988813D03*
X1030009D03*
X1042009D03*
X1034009D03*
X1028943Y1016827D03*
X1034790D03*
X1028943Y1029427D03*
X1034790D03*
X1039499Y1098758D03*
X1039053Y1105091D03*
X1044553D03*
X1039098Y1102091D03*
X1039053Y1117691D03*
X1044553D03*
X1039098Y1114691D03*
Y1127291D03*
X1039053Y1130291D03*
X1044553D03*
Y1142891D03*
X1039098Y1139891D03*
X1039053Y1142891D03*
Y1155491D03*
X1044553D03*
X1039098Y1152491D03*
X1044553Y1168091D03*
X1039053D03*
X1039098Y1165091D03*
X1044553Y1180691D03*
X1039053D03*
X1039098Y1177691D03*
X1032831Y1207950D03*
X1029797Y1220921D03*
X1040606Y1230407D03*
X1043588Y1227300D03*
X1032867Y1431213D03*
Y1428213D03*
X1029867D03*
X1035867Y1431213D03*
Y1428213D03*
X1029867Y1431213D03*
X1038867Y1428213D03*
Y1431213D03*
X1041867D03*
Y1428213D03*
X1032867Y1434213D03*
X1029867D03*
X1035867D03*
X1038867D03*
X1032867Y1437213D03*
X1029867D03*
X1032867Y1440213D03*
X1029867D03*
X1035867Y1437213D03*
Y1440213D03*
X1038867Y1437213D03*
Y1440213D03*
X1041867Y1434213D03*
Y1437213D03*
Y1440213D03*
X1051583Y103411D03*
X1051977Y97667D03*
X1047373Y95111D03*
X1052223Y111255D03*
Y114655D03*
X1051742Y106561D03*
X1044923Y118342D03*
X1052223Y125428D03*
Y128828D03*
X1044923Y132515D03*
Y121742D03*
Y135915D03*
X1047102Y195176D03*
X1046120Y199248D03*
X1044602Y195176D03*
X1049120Y199248D03*
X1049602Y195176D03*
X1046120Y201748D03*
X1049120Y202048D03*
X1044683Y210509D03*
X1046456Y206806D03*
X1043956D03*
X1052720Y230117D03*
X1048130Y227824D03*
X1048736Y238714D03*
X1048217Y246874D03*
X1050437Y244297D03*
X1045364Y279895D03*
X1051796Y279965D03*
X1050164Y302748D03*
X1050076Y305512D03*
X1061387Y343509D03*
X1060679Y356151D03*
X1054863Y401513D03*
Y398113D03*
X1052463Y412287D03*
Y415687D03*
Y426460D03*
Y440633D03*
Y429860D03*
Y444033D03*
X1059549Y458711D03*
X1052463Y469387D03*
Y472787D03*
Y486960D03*
Y483560D03*
Y513521D03*
Y516921D03*
Y531094D03*
Y527694D03*
X1055885Y554555D03*
X1046068Y792742D03*
X1046930Y796557D03*
X1048314Y833102D03*
X1053392Y832788D03*
X1051550Y823146D03*
X1055700Y840900D03*
X1053913Y837718D03*
X1050358Y837793D03*
X1052500Y841200D03*
X1049087Y856033D03*
X1053909Y855472D03*
X1045300Y872352D03*
X1054900Y879321D03*
X1058155Y887635D03*
X1050295Y891100D03*
X1054009Y988813D03*
X1046009D03*
X1050009D03*
X1058009D03*
X1056199Y1012354D03*
X1050744Y1009354D03*
X1056199Y1024954D03*
X1050699D03*
Y1012354D03*
X1050744Y1021954D03*
X1046485Y1034538D03*
X1057212Y1040356D03*
X1049930Y1221407D03*
X1050605Y1224472D03*
X1049770Y1229402D03*
X1049720Y1234921D03*
X1052660Y1293257D03*
X1050002Y1293283D03*
X1049204Y1337377D03*
X1049670Y1347462D03*
X1046075Y1350650D03*
X1049493Y1350694D03*
X1044867Y1428213D03*
Y1431213D03*
Y1434213D03*
Y1437213D03*
Y1440213D03*
X1048403Y1444608D03*
X1062773Y90650D03*
X1068085Y90615D03*
X1072456Y95236D03*
X1072406Y99961D03*
X1062523Y95236D03*
X1071268Y207978D03*
Y212978D03*
Y215478D03*
Y210478D03*
X1074597Y264180D03*
X1074522Y258880D03*
X1076571Y310574D03*
X1060679Y368276D03*
X1062865Y391001D03*
X1062234Y378600D03*
Y382600D03*
X1062865Y408574D03*
Y405174D03*
Y394401D03*
Y422747D03*
Y419347D03*
Y436921D03*
Y433521D03*
X1062349Y458711D03*
X1064876Y453682D03*
X1063113Y455921D03*
X1061693Y463600D03*
X1062865Y476499D03*
Y479899D03*
Y490673D03*
Y494073D03*
Y520633D03*
Y524033D03*
Y534806D03*
Y538206D03*
X1062098Y603600D03*
X1061342Y610269D03*
X1061496Y612786D03*
X1062098Y619600D03*
X1063642Y634190D03*
X1062098Y623600D03*
X1066931Y645389D03*
X1060698Y931619D03*
X1069685Y933391D03*
X1066878Y931909D03*
X1070009Y988813D03*
X1069607Y980131D03*
X1066009Y980330D03*
X1062009Y988813D03*
X1065823Y988773D03*
X1074009Y988813D03*
X1070009Y997860D03*
X1073525Y1012428D03*
X1076110Y1029535D03*
X1065079Y1036920D03*
X1076577Y1041332D03*
X1074232Y1055836D03*
X1067866Y1051037D03*
X1060768Y1053457D03*
X1074650Y1070006D03*
X1069642Y1445541D03*
X1068861Y1451311D03*
X1081187Y-72706D03*
Y-69306D03*
X1081320Y85193D03*
Y82593D03*
Y79993D03*
Y77393D03*
Y74793D03*
X1089645Y98551D03*
X1081364Y92874D03*
X1092540Y111223D03*
Y114623D03*
X1083391Y104249D03*
Y107649D03*
X1092540Y128796D03*
Y125396D03*
X1087957Y147540D03*
X1091729Y141247D03*
X1083013Y162368D03*
X1090113Y165393D03*
Y162793D03*
X1080413Y162368D03*
X1090113Y170493D03*
Y167993D03*
X1092321Y181366D03*
X1089110Y181426D03*
X1091935Y184012D03*
X1089318Y184221D03*
X1081724Y208213D03*
X1085796Y208695D03*
Y211695D03*
X1081724Y210713D03*
Y213213D03*
X1088596Y208695D03*
X1088296Y211695D03*
X1081724Y215713D03*
X1077097Y264180D03*
X1091973Y265701D03*
X1083491Y267526D03*
X1088791D03*
X1086291D03*
X1083491Y270026D03*
X1086291D03*
X1088791D03*
X1093608Y281716D03*
X1080351Y328256D03*
X1079748Y322743D03*
Y319343D03*
X1080351Y331656D03*
X1082297Y340770D03*
X1092554Y340318D03*
X1085615Y339815D03*
X1092561Y353374D03*
X1082787Y348501D03*
X1091031Y374810D03*
X1089788Y550907D03*
X1087288D03*
X1089788Y553407D03*
X1087288D03*
X1089096Y541863D03*
Y545263D03*
X1091558Y566929D03*
X1091272Y569426D03*
X1088949Y568475D03*
X1089206Y570962D03*
X1086859Y569928D03*
X1085512Y572070D03*
X1078920Y856700D03*
X1090375Y899047D03*
X1076800Y1012900D03*
X1078755Y1031518D03*
X1079178Y1037884D03*
X1076868Y1047293D03*
X1079910Y1045264D03*
X1079822Y1151870D03*
X1083562Y1155610D03*
X1079822Y1159350D03*
X1083283Y1526583D03*
X1084000Y1529600D03*
X1091529Y1528718D03*
X1091525Y1546300D03*
X1090876Y1554183D03*
X1091569Y1561300D03*
X1092527Y1579422D03*
X1086469Y1588435D03*
X1090469D03*
X1083900Y1593206D03*
X1082176Y1600598D03*
X1090904Y1599047D03*
X1088021Y1606949D03*
X1093778Y1599574D03*
X1086904Y1599004D03*
X1090093Y1628297D03*
X1085474Y1629028D03*
X1089474Y1638213D03*
X1105741Y76587D03*
Y72615D03*
X1100199Y97475D03*
X1107180Y100625D03*
X1100130Y106186D03*
X1093195Y103783D03*
X1102942Y118335D03*
Y132509D03*
Y121735D03*
Y135909D03*
X1107759Y141247D03*
X1099196Y143740D03*
X1096576Y148277D03*
X1095116Y181009D03*
X1100291Y168697D03*
X1097618Y172190D03*
X1109903Y171523D03*
X1097037Y177616D03*
X1101379Y191941D03*
X1109433Y192490D03*
X1105888Y206767D03*
X1108388D03*
X1103388D03*
X1093354Y213859D03*
Y211359D03*
X1097057Y213132D03*
X1104633Y228221D03*
X1106018Y221708D03*
X1108518D03*
X1102933Y224421D03*
X1103518Y221708D03*
X1104633Y231021D03*
X1097057Y215632D03*
X1105184Y236189D03*
X1107684D03*
X1105125Y248765D03*
X1107625D03*
X1097301Y256303D03*
X1102076Y266114D03*
X1097060Y265896D03*
X1107822Y268195D03*
X1105322D03*
Y270695D03*
X1107822D03*
X1099549Y281982D03*
X1093478Y310305D03*
X1108779Y327705D03*
X1103432Y340544D03*
X1097976Y340477D03*
X1105012Y353504D03*
X1098845Y353404D03*
X1093841Y371335D03*
X1099501Y545528D03*
X1108236Y577716D03*
X1105298Y610400D03*
X1108045Y668153D03*
X1092769Y936975D03*
X1095080Y1513398D03*
X1096780Y1526700D03*
X1101402Y1531702D03*
X1095250Y1531600D03*
X1098617Y1546183D03*
X1096780Y1535400D03*
X1100876Y1554183D03*
X1099371Y1561153D03*
X1100476Y1579318D03*
X1102904Y1566668D03*
X1093682Y1582433D03*
X1098498Y1590435D03*
X1104233Y1587983D03*
X1100233Y1588000D03*
X1107620Y1603602D03*
X1098904Y1602138D03*
X1101946Y1614709D03*
X1096941Y1627905D03*
X1105474Y1629450D03*
X1101474Y1637820D03*
X1093474Y1638213D03*
X1105474Y1638426D03*
X1097474Y1637753D03*
X1114781Y58013D03*
X1113646Y68581D03*
X1120021Y60513D03*
X1122881Y60438D03*
X1113659Y80581D03*
X1120149Y85731D03*
X1117789Y88801D03*
X1123703Y86046D03*
X1120706Y94351D03*
X1124655Y94279D03*
X1115842Y103621D03*
X1123899Y116594D03*
X1111553Y112083D03*
X1123899Y119594D03*
X1124333Y124283D03*
X1112246Y143518D03*
X1111346Y152373D03*
X1122740Y161306D03*
X1114496Y152562D03*
X1119991Y157370D03*
X1124075Y168665D03*
Y176665D03*
X1115188Y183834D03*
X1115298Y178560D03*
X1115361Y172665D03*
X1116174Y186629D03*
X1124075Y192665D03*
Y196665D03*
X1115478Y200864D03*
X1114708Y190185D03*
X1124188Y186778D03*
X1124107Y204864D03*
X1115501Y207037D03*
X1115567Y212455D03*
X1124107Y208864D03*
X1112868Y221642D03*
X1119748Y219379D03*
X1120376Y228631D03*
X1110184Y236189D03*
X1110125Y248765D03*
X1116782Y265897D03*
X1114282D03*
X1110622Y268195D03*
Y270695D03*
X1115000Y329000D03*
Y334000D03*
Y339000D03*
X1118848Y382109D03*
X1119853Y398082D03*
Y401482D03*
Y412255D03*
Y426428D03*
Y415655D03*
Y440602D03*
Y429828D03*
Y444002D03*
Y490641D03*
Y476468D03*
Y479868D03*
Y494041D03*
Y524002D03*
Y520602D03*
Y538175D03*
Y534775D03*
X1118847Y551683D03*
Y561420D03*
Y558917D03*
X1122705Y588515D03*
X1114668Y577937D03*
X1117673Y606929D03*
X1122673Y595500D03*
X1122173Y604567D03*
X1122705Y591015D03*
X1123331Y610072D03*
X1123267Y616317D03*
X1117633Y618400D03*
X1117914Y612592D03*
X1115151Y650119D03*
X1115320Y646449D03*
X1115054Y662981D03*
X1116296Y691851D03*
X1111785Y686971D03*
X1118105Y707592D03*
X1128562Y86012D03*
Y94374D03*
X1135868Y116594D03*
X1141141Y102495D03*
X1129842Y110784D03*
X1134842D03*
X1135868Y119594D03*
X1139402Y125107D03*
X1129399Y124879D03*
X1134421Y124663D03*
X1140875Y142862D03*
X1141916Y148717D03*
X1135765Y138838D03*
X1129156Y218085D03*
X1131956D03*
X1138469Y221970D03*
X1138535Y226320D03*
X1138469Y219470D03*
Y216970D03*
X1135756Y216385D03*
X1141496Y228646D03*
X1140453Y232971D03*
X1137103Y244571D03*
X1134483Y249108D03*
X1125864Y248371D03*
X1137830Y336230D03*
X1127153Y390995D03*
Y408568D03*
Y405168D03*
Y394395D03*
Y422741D03*
Y419341D03*
Y436915D03*
Y433515D03*
X1135548Y455804D03*
X1127153Y472781D03*
Y469381D03*
X1134629Y465551D03*
X1127153Y486954D03*
Y483554D03*
X1126622Y506256D03*
X1127153Y516915D03*
Y513515D03*
Y527688D03*
Y531088D03*
X1139673Y530000D03*
X1139173Y540500D03*
X1138373Y549800D03*
X1138173Y547075D03*
X1137673Y568000D03*
X1138213Y558800D03*
X1138277Y562800D03*
X1129471Y732571D03*
X1153945Y103411D03*
X1145485Y97667D03*
X1154339D03*
X1149735Y95111D03*
X1154585Y114655D03*
Y111255D03*
X1154104Y106561D03*
X1154585Y128828D03*
X1147285Y118342D03*
Y121742D03*
Y132515D03*
X1154585Y125428D03*
X1147285Y135915D03*
X1148016Y143762D03*
X1149464Y195176D03*
X1148482Y199248D03*
X1151482D03*
X1144464Y195176D03*
X1146964D03*
X1151964D03*
X1151482Y202048D03*
X1146318Y206806D03*
X1144545Y210509D03*
X1147045D03*
X1148818Y206806D03*
X1148482Y201748D03*
X1146237Y230556D03*
X1155082Y230117D03*
X1150492Y227824D03*
X1151098Y238714D03*
X1145222Y242078D03*
X1150579Y246874D03*
X1152799Y244297D03*
X1147590Y253198D03*
X1145587Y339148D03*
X1142440Y396718D03*
X1157451Y618288D03*
X1156275Y656321D03*
X1155146Y699491D03*
X1152512Y728543D03*
X1148962Y747253D03*
X1152485Y764552D03*
X1147468Y766093D03*
X1154652Y791056D03*
X1145910Y803642D03*
X1153485Y813142D03*
X1154985Y802897D03*
X1153229Y848581D03*
X1170447Y90615D03*
X1165135Y90650D03*
X1174768Y99961D03*
X1164885Y95236D03*
X1173630Y207978D03*
Y210478D03*
Y212978D03*
Y215478D03*
X1173559Y304948D03*
X1171445Y422088D03*
X1166868Y442956D03*
X1168685Y438323D03*
X1168398Y456309D03*
X1168851Y445873D03*
X1163298Y465874D03*
X1170878Y474424D03*
Y477824D03*
Y488597D03*
Y491997D03*
Y518558D03*
Y521958D03*
Y532731D03*
Y536131D03*
X1159535Y546712D03*
Y542712D03*
X1165400Y553300D03*
X1167900D03*
X1170878Y571997D03*
Y568597D03*
Y586171D03*
Y582771D03*
Y596944D03*
Y600344D03*
Y614517D03*
Y611117D03*
X1161451Y618288D03*
X1160275Y656321D03*
X1164275D03*
X1162863Y678519D03*
X1159173Y678462D03*
X1170465Y677836D03*
X1157646Y699491D03*
X1162646D03*
X1160146D03*
X1169256Y694983D03*
X1163774Y713347D03*
X1166115Y718469D03*
X1171934Y733857D03*
X1173034Y765060D03*
X1169697Y791935D03*
X1164925Y791607D03*
X1164732Y802269D03*
X1173122Y802759D03*
X1163579Y850774D03*
X1161535Y844167D03*
X1159887Y869106D03*
X1174461Y914515D03*
X1183682Y85193D03*
Y82593D03*
Y74793D03*
Y79993D03*
Y77393D03*
X1183726Y92874D03*
X1174818Y95236D03*
X1185753Y107649D03*
Y104249D03*
X1182775Y162368D03*
X1185375D03*
X1188158Y211695D03*
X1184086Y210713D03*
Y213213D03*
Y208213D03*
X1190958Y208695D03*
X1188158D03*
X1184086Y215713D03*
X1176959Y264180D03*
X1179459D03*
X1177035Y257919D03*
X1185853Y267526D03*
X1188653D03*
X1185853Y270026D03*
X1188653D03*
X1179901Y306366D03*
X1181706Y310131D03*
X1178045Y312193D03*
X1181379Y316049D03*
X1174929Y319167D03*
X1179761Y336380D03*
X1187996Y331992D03*
X1191748Y392676D03*
X1188598Y381500D03*
X1178083Y442856D03*
X1189122Y442606D03*
X1176699Y451108D03*
X1176138Y458455D03*
X1179184Y453881D03*
Y446595D03*
X1188739Y446606D03*
X1178178Y467337D03*
Y470737D03*
X1190046Y463479D03*
X1178178Y484910D03*
Y481510D03*
Y511471D03*
Y514871D03*
Y529044D03*
Y525644D03*
Y564910D03*
Y561510D03*
Y579084D03*
Y575684D03*
Y604030D03*
Y593257D03*
Y589857D03*
Y607430D03*
X1174595Y771744D03*
X1176500Y784933D03*
X1185516Y844248D03*
X1190968Y848703D03*
X1184340Y851072D03*
X1183012Y856553D03*
X1190213Y856816D03*
X1187431Y868340D03*
X1180239Y868430D03*
X1179858Y883455D03*
X1179727Y886197D03*
X1181654Y894671D03*
X1185058Y883475D03*
X1187151Y921000D03*
X1182000Y936500D03*
X1189219Y940703D03*
X1192007Y98551D03*
X1202561Y97475D03*
X1194902Y114623D03*
Y111223D03*
X1195557Y103783D03*
X1202492Y106186D03*
X1205304Y118335D03*
Y121735D03*
X1194902Y128796D03*
X1205304Y132509D03*
X1194902Y125396D03*
X1205304Y135909D03*
X1190319Y147540D03*
X1194091Y141247D03*
X1201558Y143740D03*
X1198938Y148277D03*
X1192475Y165393D03*
Y162793D03*
Y167993D03*
Y170493D03*
X1199980Y172190D03*
X1194683Y181366D03*
X1191472Y181426D03*
X1197478Y181009D03*
X1202653Y168697D03*
X1199399Y177616D03*
X1203741Y191941D03*
X1194297Y184012D03*
X1191680Y184221D03*
X1205750Y206767D03*
X1195716Y211359D03*
Y213859D03*
X1199419Y213132D03*
X1190658Y211695D03*
X1205295Y224421D03*
X1205880Y221708D03*
X1199419Y215632D03*
X1199663Y256303D03*
X1199422Y265896D03*
X1204438Y266114D03*
X1194335Y265701D03*
X1191153Y267526D03*
Y270026D03*
X1201911Y281982D03*
X1195970Y281716D03*
X1201113Y315039D03*
X1190127Y324142D03*
X1195800Y324000D03*
X1206531Y393858D03*
X1208173Y398583D03*
X1192702Y440489D03*
X1192957Y435158D03*
X1193000Y444841D03*
X1192686Y449961D03*
X1196403Y458572D03*
X1192431Y868620D03*
X1192152Y884399D03*
X1192367Y903785D03*
X1190210Y900909D03*
X1191151Y936296D03*
X1193219Y940703D03*
X1197173Y940645D03*
X1196352Y951033D03*
X1191219Y967757D03*
X1191928Y987314D03*
X1198644Y985289D03*
X1195757Y988131D03*
X1203419Y1011161D03*
X1200008D03*
X1196300Y998600D03*
X1202028Y998349D03*
X1199700Y1013661D03*
X1201800Y1019431D03*
X1219783Y55513D03*
X1216008Y68581D03*
X1222383Y60513D03*
X1216021Y80581D03*
X1208103Y72615D03*
Y76587D03*
X1222511Y85731D03*
X1220151Y88801D03*
X1218204Y103621D03*
X1209542Y100625D03*
X1213915Y112083D03*
X1210121Y141247D03*
X1214608Y143518D03*
X1213708Y152373D03*
X1216858Y152562D03*
X1222353Y157370D03*
X1217550Y183834D03*
X1212265Y171523D03*
X1217723Y172665D03*
X1217660Y178560D03*
X1218536Y186629D03*
X1211795Y192490D03*
X1210268Y198671D03*
X1217840Y200864D03*
X1217070Y190185D03*
X1207753Y192300D03*
X1208250Y206767D03*
X1210750D03*
X1217863Y207037D03*
X1217929Y212455D03*
X1215230Y221642D03*
X1206995Y228221D03*
X1208380Y221708D03*
X1210880D03*
X1206995Y231021D03*
X1222110Y219379D03*
X1222738Y228631D03*
X1207546Y236189D03*
X1210046D03*
X1212546D03*
X1207487Y248765D03*
X1209987D03*
X1212487D03*
X1219144Y265897D03*
X1216644D03*
X1212984Y268195D03*
X1210184D03*
X1207684D03*
X1212984Y270695D03*
X1207684D03*
X1210184D03*
X1220723Y324466D03*
X1211892Y339559D03*
X1215776Y331072D03*
X1213173Y377912D03*
X1217177Y369925D03*
X1206693Y384410D03*
X1213173Y386500D03*
X1209872Y382047D03*
X1212173Y391496D03*
X1213261Y397912D03*
X1210173Y403500D03*
X1212173Y409000D03*
X1209426Y433069D03*
Y430469D03*
Y435669D03*
Y440869D03*
Y438269D03*
X1206626Y433069D03*
Y430469D03*
Y435669D03*
Y440869D03*
Y438269D03*
X1209980Y451677D03*
X1207480Y454177D03*
X1209980D03*
X1207480Y451677D03*
X1209184Y463618D03*
Y460218D03*
X1225405Y-72678D03*
Y-69278D03*
X1230761Y-33628D03*
Y-30228D03*
X1225243Y60438D03*
X1230924Y86012D03*
Y94374D03*
X1226065Y86046D03*
X1227017Y94279D03*
X1223068Y94351D03*
X1238230Y116594D03*
X1226261D03*
X1232204Y110784D03*
X1237204D03*
X1238230Y119594D03*
X1226261D03*
X1236783Y124663D03*
X1226695Y124283D03*
X1231761Y124879D03*
X1238127Y138838D03*
X1225102Y161306D03*
X1226437Y176665D03*
Y168665D03*
Y192665D03*
X1226550Y186778D03*
X1226469Y204864D03*
Y208864D03*
X1231518Y218085D03*
X1234318D03*
X1238118Y216385D03*
X1239465Y244571D03*
X1236845Y249108D03*
X1228226Y248371D03*
X1229252Y314890D03*
X1229028Y311740D03*
X1226436Y324518D03*
X1229922Y324550D03*
X1234904Y316942D03*
X1232197Y316964D03*
X1238293Y317296D03*
X1229438Y332584D03*
X1235589Y348015D03*
X1229942Y347937D03*
X1231506Y353470D03*
X1223431Y377912D03*
X1225755Y369391D03*
X1229122Y369355D03*
X1222601Y369251D03*
X1223431Y381912D03*
Y397912D03*
X1235166Y470706D03*
Y467306D03*
Y484879D03*
Y481479D03*
Y514839D03*
Y511439D03*
Y529013D03*
Y525613D03*
X1232833Y539315D03*
X1232149Y550137D03*
X1234941D03*
X1235166Y564879D03*
Y561479D03*
Y575652D03*
Y579052D03*
Y593225D03*
Y603999D03*
Y589825D03*
Y607399D03*
X1235930Y626229D03*
X1235292Y622912D03*
X1237500Y632405D03*
X1238034Y629961D03*
X1238695Y627313D03*
X1256307Y103411D03*
X1247847Y97667D03*
X1256701D03*
X1252097Y95111D03*
X1243503Y102495D03*
X1249647Y118342D03*
Y132515D03*
Y121742D03*
X1241764Y125107D03*
X1249647Y135915D03*
X1243237Y142862D03*
X1250378Y143762D03*
X1244278Y148717D03*
X1251826Y195176D03*
X1254326D03*
X1253844Y199248D03*
X1249326Y195176D03*
X1250844Y199248D03*
X1246826Y195176D03*
X1249407Y210509D03*
X1253844Y202048D03*
X1250844Y201748D03*
X1251180Y206806D03*
X1248680D03*
X1246907Y210509D03*
X1240831Y221970D03*
X1240897Y226320D03*
X1240831Y219470D03*
Y216970D03*
X1248599Y230556D03*
X1252854Y227824D03*
X1243858Y228646D03*
X1253460Y238714D03*
X1247584Y242078D03*
X1252941Y246874D03*
X1242815Y232971D03*
X1246808Y256394D03*
X1241205Y303962D03*
X1253245Y416888D03*
Y419488D03*
Y422088D03*
X1245568Y474418D03*
Y488591D03*
Y477818D03*
Y491991D03*
Y521952D03*
Y518552D03*
Y536125D03*
Y532725D03*
X1253087Y553101D03*
X1241629Y550065D03*
X1245568Y568591D03*
Y571991D03*
Y582765D03*
Y586165D03*
Y596938D03*
Y600338D03*
Y611111D03*
Y614511D03*
X1248106Y1004700D03*
X1245400Y1003700D03*
X1246000Y1014800D03*
X1252148Y1026223D03*
X1252500Y1014288D03*
X1246300Y1027800D03*
X1253424Y1138130D03*
X1250928Y1142828D03*
X1254200Y1146600D03*
X1249363Y1173065D03*
X1256218Y1175987D03*
X1249363Y1166065D03*
X1255439Y1172008D03*
X1255628Y1188345D03*
X1253056Y1194917D03*
X1254275Y1531334D03*
X1249894Y1527805D03*
X1253904Y1519645D03*
X1254275Y1539334D03*
X1250434Y1535334D03*
X1267497Y90650D03*
X1267247Y95236D03*
X1256947Y114655D03*
Y111255D03*
X1256466Y106561D03*
X1256947Y128828D03*
Y125428D03*
X1257444Y230117D03*
X1255161Y244297D03*
X1266962Y302167D03*
X1262665Y302730D03*
X1263328Y309003D03*
X1262075Y324075D03*
X1261659Y318258D03*
X1264088Y320382D03*
X1266616Y322456D03*
X1257000Y333500D03*
X1264215Y333215D03*
X1262500Y330655D03*
X1256000Y338000D03*
X1259991Y340691D03*
X1256000Y340500D03*
X1263500Y336000D03*
X1264659Y377173D03*
X1267944Y371767D03*
X1261764Y391533D03*
X1263484Y385644D03*
X1268659Y385123D03*
X1268067Y406060D03*
X1261231Y399918D03*
X1264336Y412106D03*
X1268328Y421489D03*
Y418889D03*
Y416289D03*
X1270397Y447081D03*
X1259223Y454334D03*
X1267540Y459330D03*
X1267493Y454214D03*
X1267836Y449045D03*
X1267843Y473571D03*
Y481071D03*
Y478571D03*
Y476071D03*
X1269629Y848124D03*
X1270892Y856343D03*
X1271121Y892513D03*
X1270276Y897062D03*
X1269221Y894760D03*
X1270586Y905324D03*
X1272661Y929858D03*
X1260539Y1134729D03*
X1267921D03*
X1266718Y1142666D03*
X1263921Y1134729D03*
X1268593Y1157544D03*
X1267104Y1167768D03*
X1272123D03*
X1271246Y1178240D03*
X1271256Y1185205D03*
X1262605Y1187215D03*
X1262298Y1180175D03*
X1260800Y1191096D03*
X1268571Y1201043D03*
X1264575D03*
X1261538Y1199814D03*
X1255296Y1196056D03*
X1263449Y1217228D03*
X1266113Y1219895D03*
X1269388Y1223170D03*
X1267333Y1531334D03*
X1262891Y1527334D03*
X1267183Y1539334D03*
X1262891Y1535334D03*
X1286044Y85539D03*
Y82939D03*
Y75139D03*
Y80339D03*
Y77739D03*
X1286088Y92874D03*
X1272809Y90615D03*
X1277130Y99961D03*
X1277180Y95236D03*
X1285137Y162368D03*
X1275992Y215478D03*
Y212978D03*
Y210478D03*
Y207978D03*
X1286448Y213213D03*
Y210713D03*
Y208213D03*
Y215713D03*
X1281821Y264180D03*
X1279321D03*
X1279246Y258880D03*
X1271571Y281185D03*
X1289345Y330655D03*
X1284419Y359377D03*
X1287437Y379429D03*
X1280699Y377173D03*
X1284659D03*
X1274436Y377350D03*
X1276659Y385123D03*
X1273659D03*
X1280659D03*
X1284333Y391569D03*
X1282760Y401066D03*
X1272421Y403300D03*
X1271828Y405889D03*
Y408489D03*
Y413689D03*
Y411089D03*
Y416289D03*
Y421489D03*
Y418889D03*
Y424089D03*
X1272215Y432718D03*
Y435518D03*
X1282092Y442118D03*
Y439318D03*
X1271828Y426689D03*
X1272927Y450091D03*
X1275927D03*
X1273397Y447081D03*
X1281737Y461034D03*
Y456034D03*
X1272927Y462060D03*
X1275927D03*
X1286005Y485580D03*
X1280631Y480194D03*
Y477694D03*
X1277897Y478876D03*
Y476376D03*
X1274415Y477053D03*
X1271915D03*
X1284900Y678800D03*
X1283400Y715500D03*
X1278255Y722241D03*
X1283400Y719700D03*
X1282539Y746076D03*
X1279539Y748576D03*
X1282539Y751076D03*
X1279539Y763576D03*
X1282539Y766076D03*
X1279539Y758576D03*
X1282539Y756076D03*
Y761076D03*
X1279539Y753576D03*
Y768576D03*
Y780576D03*
Y784576D03*
X1285092Y819500D03*
X1285500Y827500D03*
X1281388Y827388D03*
X1281777Y823500D03*
X1285500Y843500D03*
X1281331Y843331D03*
X1281269Y835492D03*
X1285500Y835500D03*
X1283025Y848305D03*
X1271438Y861846D03*
X1285500Y863500D03*
Y859500D03*
Y855500D03*
Y851500D03*
X1279460Y854487D03*
Y859487D03*
Y864487D03*
X1274396Y866896D03*
X1285500Y867500D03*
X1279460Y874487D03*
Y869487D03*
Y879487D03*
X1285302Y877283D03*
X1282285Y865602D03*
X1274264Y898591D03*
X1279460Y884487D03*
X1285302Y885783D03*
X1279299Y898813D03*
X1279460Y889487D03*
X1285302Y881783D03*
X1281075Y911075D03*
X1282184Y898854D03*
X1274400Y914123D03*
X1283494Y907176D03*
X1275493Y929858D03*
X1279493D03*
X1283493D03*
X1279693Y919800D03*
X1274670Y919808D03*
X1281400Y940256D03*
X1289547Y941000D03*
X1281733Y949475D03*
X1275788Y1124088D03*
X1282421Y1137129D03*
X1271921Y1134729D03*
X1275794D03*
X1282830Y1150087D03*
X1275050Y1157404D03*
X1280306Y1170767D03*
X1275965Y1187232D03*
X1280602Y1185238D03*
X1280395Y1180235D03*
X1272541Y1201043D03*
X1276575Y1201039D03*
X1280575Y1200969D03*
X1280694Y1208993D03*
X1274446Y1228226D03*
X1272235Y1226016D03*
X1297687Y-33656D03*
Y-30256D03*
X1297785Y33768D03*
X1302139Y26325D03*
X1302785Y31168D03*
X1294369Y98551D03*
X1304923Y97475D03*
X1297264Y114623D03*
Y111223D03*
X1297919Y103783D03*
X1288115Y104249D03*
Y107649D03*
X1297264Y128796D03*
Y125396D03*
X1294837Y162793D03*
X1287737Y162368D03*
X1294837Y165393D03*
Y167993D03*
Y170493D03*
X1301761Y177616D03*
X1302342Y172190D03*
X1299840Y181009D03*
X1293834Y181426D03*
X1297045Y181366D03*
X1294042Y184221D03*
X1296659Y184012D03*
X1301781Y213132D03*
X1298078Y211359D03*
Y213859D03*
X1290520Y211695D03*
X1293020D03*
X1290520Y208695D03*
X1293320D03*
X1301781Y215632D03*
X1302025Y256303D03*
X1296697Y265701D03*
X1301784Y265896D03*
X1293515Y270026D03*
X1291015D03*
X1288215D03*
Y267526D03*
X1293515D03*
X1291015D03*
X1304273Y281982D03*
X1298332Y281716D03*
X1294000Y324000D03*
X1303000Y326692D03*
X1293000Y338500D03*
X1303000Y331000D03*
X1302896Y343797D03*
Y340397D03*
X1292500Y335000D03*
X1299959Y356954D03*
X1294080Y349820D03*
X1291410Y371060D03*
X1295410Y371076D03*
X1293048Y379088D03*
X1298346Y379028D03*
X1293100Y409539D03*
X1296100D03*
X1293100Y406739D03*
X1296100Y407039D03*
X1295764Y401981D03*
X1298264D03*
X1300037Y398278D03*
X1297537D03*
X1292618Y413611D03*
X1295118D03*
X1300118D03*
X1297618D03*
X1292383Y424067D03*
X1294883D03*
X1299883D03*
X1297383D03*
X1299757Y438293D03*
Y441093D03*
X1290092Y442118D03*
Y439318D03*
X1299757Y443893D03*
X1287719Y470001D03*
X1290219D03*
X1299867Y477318D03*
X1299466Y466409D03*
X1299807Y472020D03*
X1288144Y489036D03*
X1291005Y485580D03*
X1288505D03*
X1301314Y484882D03*
X1299304Y487382D03*
X1290380Y495636D03*
Y492836D03*
X1300817Y568635D03*
X1301194Y565518D03*
X1305836Y660009D03*
X1298963Y659609D03*
X1289811Y677612D03*
X1289317Y706932D03*
X1291604Y781576D03*
Y776576D03*
Y771435D03*
X1295491Y798821D03*
X1298720Y798975D03*
X1289730Y806845D03*
X1302140Y812625D03*
X1302501Y824747D03*
X1297667Y832150D03*
X1293500Y827500D03*
X1296770Y828775D03*
X1293500Y843500D03*
Y835500D03*
X1296687Y839500D03*
X1293500Y851500D03*
X1294000Y863500D03*
X1293500Y879800D03*
Y871800D03*
Y875800D03*
X1288164Y892354D03*
X1296866Y894993D03*
X1305250Y889250D03*
X1293272Y887800D03*
X1293500Y883800D03*
X1291129Y892267D03*
X1294264Y905595D03*
X1301657Y899129D03*
X1288500Y901254D03*
X1298966Y899610D03*
X1296466D03*
X1298000Y917000D03*
X1294075D03*
X1304949Y928546D03*
X1292500Y928000D03*
X1295453Y928047D03*
X1291059Y917000D03*
X1302000D03*
X1302500Y939500D03*
X1300882Y937144D03*
X1296500Y961500D03*
X1289500Y949500D03*
X1300500Y960000D03*
X1290792Y961363D03*
X1300500Y970187D03*
X1297558Y970216D03*
X1292836Y975244D03*
X1292631Y979845D03*
X1299717Y1024136D03*
X1297852Y1014475D03*
X1295815Y1124943D03*
X1295893Y1122182D03*
X1310853Y37543D03*
X1314887Y45448D03*
X1318859D03*
X1311904Y100625D03*
X1320566Y103621D03*
X1304854Y106186D03*
X1316277Y112083D03*
X1307666Y118335D03*
Y132509D03*
Y121735D03*
Y135909D03*
X1305015Y168697D03*
X1319912Y183834D03*
X1314627Y171523D03*
X1320085Y172665D03*
X1320022Y178560D03*
X1306103Y191941D03*
X1319432Y190185D03*
X1314157Y192490D03*
X1320202Y200864D03*
X1310115Y192300D03*
X1308112Y206767D03*
X1313112D03*
X1310612D03*
X1320225Y207037D03*
X1320291Y212455D03*
X1313242Y221708D03*
X1310742D03*
X1309357Y231021D03*
Y228221D03*
X1317592Y221642D03*
X1308242Y221708D03*
X1307657Y224421D03*
X1309908Y236189D03*
X1314908D03*
X1312408D03*
X1312349Y248765D03*
X1309849D03*
X1314849D03*
X1306800Y266114D03*
X1310046Y268195D03*
X1312546D03*
X1315346D03*
X1319006Y265897D03*
X1312546Y270695D03*
X1310046D03*
X1315346D03*
X1318362Y310562D03*
X1305928Y318250D03*
X1308428D03*
X1315256Y336510D03*
X1313103Y339606D03*
X1312240Y334681D03*
X1315397Y333709D03*
X1308012Y348109D03*
X1305910Y377581D03*
X1310172Y367956D03*
X1308410Y379591D03*
X1311283Y370801D03*
X1308826Y389402D03*
X1306113Y383817D03*
X1312626Y387702D03*
X1315426D03*
X1306113Y386317D03*
Y388817D03*
X1309750Y438293D03*
Y441093D03*
Y443893D03*
X1311488Y471560D03*
X1307819Y474382D03*
X1307835Y470382D03*
X1319474Y467560D03*
X1319974Y475560D03*
X1311488D03*
X1318160Y520053D03*
X1317945Y523058D03*
X1319000Y562500D03*
Y558500D03*
Y586500D03*
Y574500D03*
Y578500D03*
Y605000D03*
Y590500D03*
X1319323Y598454D03*
X1319000Y621000D03*
Y609000D03*
Y633000D03*
Y625000D03*
Y637000D03*
Y653500D03*
Y649500D03*
Y641000D03*
Y669500D03*
Y665500D03*
Y681500D03*
Y677500D03*
X1313979Y677726D03*
X1319000Y685500D03*
Y696500D03*
Y700500D03*
Y712500D03*
Y716500D03*
Y724500D03*
Y728500D03*
Y732500D03*
X1321000Y796000D03*
X1313000D03*
X1317000Y799000D03*
Y788000D03*
X1313000D03*
X1315000Y811620D03*
X1319000D03*
X1317000Y804000D03*
X1313000D03*
X1321000D03*
X1310715Y820491D03*
Y822991D03*
Y817991D03*
X1310687Y830206D03*
Y832706D03*
Y827706D03*
X1310971Y842319D03*
X1305786Y867704D03*
X1310994Y866859D03*
X1309753Y877589D03*
X1305740Y877534D03*
X1310535Y870775D03*
X1308220Y889253D03*
X1311061Y889361D03*
X1314500Y911500D03*
X1319500Y901500D03*
X1314500Y905000D03*
X1305356Y902597D03*
X1319500Y905000D03*
X1309103Y917000D03*
X1313867Y925605D03*
X1311325Y928918D03*
X1319554Y925585D03*
X1309103Y936559D03*
X1306500Y936500D03*
X1315779Y943743D03*
X1313152Y936605D03*
X1312575Y943974D03*
X1321256Y943815D03*
X1311000Y961500D03*
X1307000Y960500D03*
X1315441Y960000D03*
X1307000Y970000D03*
X1311000Y970124D03*
X1307707Y979870D03*
X1317254Y990777D03*
X1317053Y988111D03*
X1319874Y989856D03*
X1307561Y986951D03*
X1315606Y1042825D03*
X1315756Y1039344D03*
X1312873Y1036543D03*
X1306385Y1036646D03*
X1319221Y1058097D03*
Y1060697D03*
X1316869Y1107997D03*
X1319069Y1112397D03*
X1318969Y1109397D03*
X1316869Y1113797D03*
Y1110897D03*
X1317437Y1160834D03*
X1318178Y1192621D03*
Y1190121D03*
X1319237Y1221428D03*
X1311237D03*
X1315237D03*
X1311237Y1233428D03*
Y1229428D03*
Y1225428D03*
X1315237Y1237428D03*
Y1233428D03*
Y1229428D03*
Y1225428D03*
X1319237Y1237428D03*
Y1233428D03*
Y1229428D03*
Y1225428D03*
X1315237Y1241428D03*
X1319237D03*
X1308107Y1283395D03*
X1310773Y1282411D03*
X1303900Y1288000D03*
X1318287Y1295381D03*
Y1291381D03*
X1324120Y22742D03*
X1331073Y33400D03*
X1328003Y32403D03*
X1328318Y27333D03*
X1336623Y30483D03*
X1322853Y37530D03*
X1328799Y168665D03*
Y176665D03*
X1320898Y186629D03*
X1328799Y192665D03*
Y196665D03*
X1328912Y186778D03*
X1328831Y204864D03*
Y208864D03*
X1324472Y219379D03*
X1325100Y228631D03*
X1321506Y265897D03*
X1334110Y310562D03*
X1321762D03*
X1329636Y307562D03*
X1326236D03*
X1332563Y326356D03*
X1325573Y326719D03*
X1332359Y322685D03*
X1326489Y356945D03*
X1331005Y356670D03*
X1331922Y359836D03*
X1325007Y370951D03*
X1334109Y373401D03*
X1334285Y386567D03*
X1331606D03*
X1328896D03*
X1320594Y387151D03*
Y382151D03*
Y384651D03*
X1329097Y435321D03*
Y438121D03*
X1326297Y435321D03*
Y438121D03*
X1329097Y440921D03*
X1326297D03*
X1329097Y443721D03*
X1326297D03*
X1335440Y452799D03*
X1329083Y448931D03*
X1329606Y459170D03*
X1332974Y474513D03*
X1321450Y520268D03*
X1321164Y523130D03*
X1326993Y556788D03*
X1331096Y549931D03*
X1327043Y573346D03*
X1327000Y562500D03*
X1326946Y567906D03*
X1338000Y562500D03*
X1327000Y578500D03*
Y583826D03*
X1335000Y594500D03*
X1327000Y605000D03*
Y594500D03*
Y609000D03*
X1333224Y615484D03*
X1327000Y613000D03*
Y621000D03*
X1335532Y622260D03*
X1338000Y609000D03*
X1327000Y629000D03*
X1327003Y623940D03*
X1335000Y641000D03*
X1338000Y653500D03*
X1327000Y641000D03*
X1327011Y646064D03*
X1327000Y657500D03*
X1335000Y685500D03*
X1327000D03*
Y695500D03*
Y700500D03*
X1338000D03*
X1327000Y711500D03*
Y716500D03*
X1335000Y732500D03*
X1327000D03*
X1330295Y746328D03*
X1326970Y736464D03*
X1336661Y753675D03*
Y745675D03*
Y737675D03*
X1330295Y751328D03*
X1330086Y763758D03*
X1330324Y779030D03*
X1336746Y781675D03*
X1329000Y796000D03*
X1325000Y799000D03*
X1337000Y796000D03*
X1333000Y799000D03*
Y788000D03*
X1329000D03*
X1321000D03*
X1325000D03*
X1331000Y811620D03*
X1327000D03*
X1329000Y804000D03*
X1325000D03*
X1333000D03*
X1323000Y811620D03*
X1335000D03*
X1335803Y826500D03*
X1331056Y904557D03*
X1336096Y905042D03*
X1336000Y900500D03*
X1324000Y901000D03*
X1331078Y900500D03*
X1330500Y925500D03*
X1334500D03*
X1326500D03*
X1333425Y930925D03*
X1324000D03*
X1333132Y933781D03*
X1336000Y943500D03*
X1329199Y933825D03*
X1323000Y934075D03*
X1326500Y943500D03*
X1335343Y961727D03*
X1321028Y961749D03*
X1332500Y961500D03*
X1325550Y960445D03*
X1332000Y969500D03*
X1327000D03*
X1329503Y991088D03*
X1334909Y990340D03*
X1332404Y988215D03*
X1329834Y988132D03*
X1324735Y989966D03*
X1327267Y988271D03*
X1322427Y988221D03*
X1333974Y1033483D03*
X1320549Y1037876D03*
X1322773Y1040599D03*
X1329221Y1058097D03*
X1321721D03*
X1324221D03*
X1326721D03*
Y1060697D03*
X1329221D03*
X1321721D03*
X1324221D03*
X1326163Y1082501D03*
X1326189Y1085205D03*
X1329163Y1082501D03*
X1329189Y1085205D03*
X1326189Y1088205D03*
X1326471Y1091227D03*
X1329189Y1088205D03*
X1323189Y1085205D03*
Y1087705D03*
X1323163Y1082501D03*
X1323021Y1090956D03*
X1337514Y1104335D03*
X1334956Y1105552D03*
X1321069Y1107997D03*
X1323021Y1093956D03*
X1331162Y1104792D03*
X1332669Y1106867D03*
X1321169Y1110597D03*
X1321954Y1113648D03*
X1326254D03*
X1328754D03*
X1323405Y1118801D03*
Y1116101D03*
X1325635Y1172384D03*
Y1162384D03*
Y1164884D03*
Y1167384D03*
Y1169884D03*
X1323135Y1172384D03*
Y1162384D03*
Y1164884D03*
Y1167384D03*
Y1169884D03*
X1334793Y1179421D03*
Y1181921D03*
Y1184421D03*
Y1186921D03*
X1320493Y1186709D03*
Y1184209D03*
Y1181709D03*
Y1179209D03*
X1325635Y1174884D03*
X1323135D03*
X1331643Y1192621D03*
Y1190121D03*
X1327237Y1221428D03*
X1331237D03*
X1335237D03*
X1323237D03*
X1327237Y1237428D03*
Y1233428D03*
Y1229428D03*
Y1225428D03*
X1331237Y1237428D03*
Y1233428D03*
Y1229428D03*
Y1225428D03*
X1335237Y1237428D03*
Y1233428D03*
Y1229428D03*
Y1225428D03*
X1323237Y1237428D03*
Y1233428D03*
Y1229428D03*
Y1225428D03*
X1335237Y1241428D03*
X1323237Y1245428D03*
Y1241428D03*
X1327237Y1245428D03*
Y1241428D03*
X1331237Y1245428D03*
Y1241428D03*
X1335237Y1245428D03*
X1333876Y1257160D03*
Y1260160D03*
X1337687Y-69306D03*
Y-72706D03*
X1336646Y22627D03*
X1336551Y26534D03*
X1340320Y147540D03*
X1344092Y141247D03*
X1351559Y143740D03*
X1348939Y148277D03*
X1348419Y265222D03*
X1340104Y279117D03*
X1344007Y279054D03*
X1337510Y310562D03*
X1347990Y322539D03*
X1341169Y325926D03*
X1346009Y336080D03*
X1346093Y340805D03*
X1349636Y340862D03*
X1346065Y347106D03*
X1338471Y356959D03*
X1337509Y373401D03*
X1349763Y371908D03*
X1342810Y408104D03*
X1345610D03*
X1348410D03*
X1336388Y424939D03*
X1342527Y420375D03*
X1345327D03*
X1348127D03*
X1336388Y427439D03*
X1346443Y431112D03*
X1352008Y435101D03*
X1352271Y442114D03*
X1346613Y440101D03*
X1352251Y447121D03*
X1346248Y452718D03*
X1340820Y452987D03*
X1352259Y452601D03*
X1347846Y461607D03*
X1339846D03*
X1339049Y471334D03*
X1343846Y461607D03*
X1346738Y564492D03*
X1339289Y568461D03*
X1342053Y579339D03*
X1346533Y576780D03*
X1340522Y586133D03*
X1343000Y590458D03*
X1346533Y581898D03*
X1344129Y606914D03*
X1344433Y601201D03*
X1339289Y614961D03*
X1344680Y619085D03*
X1346738Y611192D03*
X1346533Y628398D03*
X1346378Y623734D03*
X1342053Y625839D03*
X1340522Y632633D03*
X1343000Y636958D03*
X1346738Y655492D03*
X1339289Y659461D03*
X1346533Y667780D03*
X1342053Y670339D03*
X1346533Y672898D03*
X1340522Y677133D03*
X1343000Y681458D03*
X1350929Y687043D03*
X1340299Y686243D03*
X1346738Y702492D03*
X1346533Y719898D03*
X1339289Y706461D03*
X1342053Y717339D03*
X1346533Y714780D03*
X1340522Y724133D03*
X1343000Y728458D03*
X1344768Y737675D03*
Y741675D03*
Y745675D03*
Y749675D03*
Y753675D03*
Y761675D03*
Y757675D03*
X1336450Y765675D03*
X1344768Y773675D03*
Y781350D03*
X1345226Y777675D03*
X1341000Y799000D03*
X1345000Y796000D03*
X1341000Y788000D03*
X1345000D03*
X1337000D03*
X1348917Y796000D03*
Y788000D03*
X1352817Y796000D03*
X1349000Y804000D03*
X1351000Y811620D03*
X1347000D03*
X1343000D03*
X1337000Y804000D03*
X1345000D03*
X1341000D03*
X1349976Y829000D03*
X1350000Y825500D03*
X1340000Y900000D03*
X1351500Y903000D03*
Y906500D03*
X1340000Y906000D03*
Y903000D03*
X1351511Y900000D03*
X1350500Y925500D03*
X1338500D03*
X1342500D03*
X1346500D03*
X1353948Y943603D03*
X1345948D03*
X1349848Y936755D03*
X1338500Y930500D03*
X1350500D03*
X1342500D03*
X1346500D03*
X1337514Y988259D03*
X1343465Y1026123D03*
X1340665D03*
X1343465Y1028923D03*
X1340665D03*
X1347552Y1091816D03*
Y1089316D03*
X1345052Y1081816D03*
Y1084316D03*
Y1086816D03*
X1347552D03*
Y1084316D03*
X1350418Y1090288D03*
X1347552Y1081816D03*
X1344241Y1106298D03*
X1348997Y1107997D03*
X1350418Y1093088D03*
X1339234Y1101917D03*
X1339169Y1106897D03*
X1341984Y1110092D03*
X1345650Y1115896D03*
X1348997Y1113797D03*
Y1110897D03*
X1351197Y1112397D03*
X1351097Y1109397D03*
X1345650Y1118396D03*
X1347300Y1128332D03*
X1343725Y1128738D03*
X1343905Y1162384D03*
Y1164884D03*
Y1167384D03*
Y1169884D03*
Y1172384D03*
X1341405D03*
Y1169884D03*
Y1167384D03*
Y1164884D03*
Y1162384D03*
X1350963Y1172384D03*
Y1169884D03*
Y1167384D03*
Y1164884D03*
Y1162384D03*
X1351149Y1158200D03*
X1347423Y1186709D03*
Y1184209D03*
Y1181709D03*
Y1179209D03*
X1343905Y1174884D03*
X1341405D03*
X1350963D03*
X1337108Y1192621D03*
Y1190121D03*
X1345108D03*
Y1192621D03*
X1347237Y1221428D03*
X1343237D03*
X1339237D03*
X1347237Y1237428D03*
Y1233428D03*
Y1229428D03*
X1343237D03*
Y1233428D03*
Y1237428D03*
X1339237D03*
Y1233428D03*
Y1229428D03*
Y1225428D03*
X1347237Y1245428D03*
Y1241428D03*
X1343237D03*
Y1245428D03*
X1339237D03*
Y1241428D03*
X1339876Y1257160D03*
X1342876D03*
X1345876Y1260160D03*
Y1257160D03*
X1348876Y1260160D03*
Y1257160D03*
X1351876Y1260160D03*
Y1257160D03*
X1336876Y1260160D03*
Y1257160D03*
X1342876Y1260160D03*
X1339876D03*
X1360122Y141247D03*
X1364609Y143518D03*
X1363709Y152373D03*
X1366859Y152562D03*
X1363535Y327877D03*
X1366535Y335751D03*
Y339151D03*
X1363535Y331277D03*
Y343625D03*
X1366535Y354899D03*
Y351499D03*
X1363535Y347025D03*
X1360719Y424601D03*
X1352817Y788000D03*
X1367000Y811620D03*
X1365000Y804000D03*
X1355000Y811620D03*
X1363000D03*
X1353000Y804000D03*
X1359000Y811620D03*
X1357000Y804000D03*
X1361000D03*
X1354185Y906498D03*
X1367000Y904500D03*
X1363000Y900500D03*
X1367000D03*
X1354500Y925500D03*
X1366500D03*
X1358500D03*
X1362500D03*
X1365948Y939475D03*
X1357948Y938842D03*
X1361948Y943603D03*
X1369948D03*
X1362500Y930500D03*
X1366500D03*
X1354500D03*
X1358500D03*
X1364765Y1004766D03*
X1367444Y1003763D03*
X1357765Y1019766D03*
X1361265D03*
X1365049Y1028416D03*
X1365314Y1021793D03*
X1357265Y1026266D03*
Y1034266D03*
X1366265Y1039880D03*
X1369642Y1104335D03*
X1367084Y1105552D03*
X1353197Y1107997D03*
X1363290Y1104792D03*
X1364797Y1106867D03*
X1353297Y1110597D03*
X1354082Y1113648D03*
X1355533Y1116101D03*
Y1118801D03*
X1360882Y1113648D03*
X1358382D03*
X1353463Y1172384D03*
Y1169884D03*
Y1167384D03*
Y1164884D03*
Y1162384D03*
X1361723Y1179421D03*
Y1181921D03*
Y1184421D03*
Y1186921D03*
X1353463Y1174884D03*
X1364038Y1190121D03*
Y1192621D03*
X1363876Y1260160D03*
Y1257160D03*
X1354876Y1260160D03*
X1357876D03*
X1360876D03*
Y1257160D03*
X1357876D03*
X1354876D03*
X1366876Y1260160D03*
Y1257160D03*
X1376262Y116594D03*
X1382205Y110784D03*
X1387205D03*
X1376262Y119594D03*
X1386784Y124663D03*
X1376696Y124283D03*
X1381762Y124879D03*
X1375103Y161306D03*
X1372354Y157370D03*
X1384319Y218085D03*
X1381519D03*
X1386846Y249108D03*
X1378227Y248371D03*
X1384265Y320871D03*
Y325371D03*
X1383551Y337808D03*
X1384265Y329871D03*
X1383634Y342766D03*
X1384265Y334371D03*
X1375073Y356871D03*
Y361371D03*
X1383505Y349437D03*
X1384265Y352371D03*
X1372232Y361298D03*
X1383963Y366675D03*
X1377024Y397713D03*
X1375108Y420838D03*
X1375171Y424741D03*
X1375400Y435192D03*
X1375360Y432234D03*
X1383343Y508228D03*
X1383907Y516591D03*
X1383556Y554388D03*
X1378415Y558795D03*
X1383608Y571927D03*
X1378415Y563984D03*
Y569776D03*
X1378957Y584457D03*
X1383000Y584500D03*
X1382997Y581317D03*
X1383425Y590425D03*
X1378415Y605295D03*
X1383608Y618427D03*
X1378415Y610484D03*
Y616276D03*
X1383425Y636925D03*
X1378957Y630957D03*
X1384657Y631620D03*
X1378957Y627988D03*
X1378415Y649795D03*
Y654984D03*
Y660776D03*
X1386289Y672488D03*
X1383425Y681425D03*
X1378957Y675457D03*
X1383000Y675500D03*
X1378415Y696795D03*
Y701984D03*
X1378957Y719488D03*
X1378415Y707776D03*
X1383425Y728425D03*
X1378957Y722457D03*
X1385290Y722400D03*
X1371000Y811620D03*
X1381000Y804000D03*
X1373000D03*
X1369000D03*
X1385360Y811757D03*
X1381428Y812287D03*
X1375193Y811724D03*
X1376708Y901000D03*
X1378500Y925500D03*
X1374369Y925499D03*
X1370500Y925500D03*
X1382500D03*
X1382775Y930281D03*
X1373948Y940103D03*
X1374500Y930500D03*
X1370500D03*
X1378500D03*
X1381519Y996280D03*
X1383162Y991829D03*
X1373534Y1012325D03*
Y1004680D03*
X1378938Y1000586D03*
X1374034Y1015825D03*
X1374059Y1018860D03*
X1376359Y1016825D03*
X1378559Y1038534D03*
X1384784Y1033783D03*
X1385929Y1038665D03*
X1373874Y1032266D03*
Y1035716D03*
X1385152Y1046591D03*
X1377087Y1106365D03*
X1371362Y1101917D03*
X1371297Y1106897D03*
X1382456Y1107997D03*
X1374112Y1110092D03*
X1377778Y1115896D03*
X1384656Y1112397D03*
X1382456Y1110897D03*
Y1113797D03*
X1384556Y1109397D03*
X1377778Y1118396D03*
X1369233Y1169884D03*
Y1172384D03*
X1371733D03*
Y1169884D03*
Y1167384D03*
Y1164884D03*
Y1162384D03*
X1369233D03*
Y1164884D03*
Y1167384D03*
X1376861Y1160834D03*
X1383024D03*
X1369233Y1174884D03*
X1371733D03*
X1375459Y1197471D03*
Y1193471D03*
X1379959Y1197471D03*
Y1193471D03*
X1397848Y97667D03*
X1388231Y116594D03*
X1393504Y102495D03*
X1388231Y119594D03*
X1399648Y132515D03*
Y121742D03*
Y118342D03*
X1391765Y125107D03*
X1399648Y135915D03*
X1393238Y142862D03*
X1400379Y143762D03*
X1394279Y148717D03*
X1388128Y138838D03*
X1399327Y195176D03*
X1396827D03*
X1400845Y199248D03*
Y201748D03*
X1398681Y206806D03*
X1401181D03*
X1399408Y210509D03*
X1396908D03*
X1390832Y216970D03*
Y219470D03*
X1390898Y226320D03*
X1390832Y221970D03*
X1388119Y216385D03*
X1402855Y227824D03*
X1398600Y230556D03*
X1393859Y228646D03*
X1397585Y242078D03*
X1392816Y232971D03*
X1389466Y244571D03*
X1396809Y256394D03*
X1395726Y320529D03*
X1395568Y325529D03*
X1395726Y330529D03*
X1395736Y335529D03*
X1395726Y340529D03*
Y345529D03*
Y360529D03*
Y350529D03*
Y355529D03*
X1391896Y365529D03*
X1399884Y367165D03*
X1387847Y366710D03*
X1400231Y390256D03*
X1396528Y397454D03*
X1399571Y397418D03*
X1393575Y397310D03*
X1390553Y397436D03*
X1391623Y409900D03*
X1387125Y417312D03*
X1393177Y424804D03*
X1389557Y424678D03*
X1389431Y421593D03*
X1390271Y417578D03*
X1393208Y428109D03*
X1393336Y431100D03*
X1403085Y460565D03*
X1393944Y507856D03*
X1394044Y510990D03*
X1397079Y527726D03*
Y548726D03*
Y544726D03*
X1395605Y556217D03*
X1390741Y561000D03*
Y569000D03*
Y565000D03*
X1391087Y581317D03*
X1398946Y621311D03*
X1390741Y611500D03*
Y607500D03*
Y615500D03*
X1391586Y623692D03*
X1398946Y629311D03*
Y625311D03*
X1397000Y652000D03*
Y656000D03*
Y660000D03*
Y699000D03*
Y707000D03*
Y703000D03*
X1391040Y812027D03*
X1386335Y803704D03*
X1390537Y803679D03*
X1394537Y803653D03*
X1398530Y811717D03*
X1402417Y811692D03*
X1400069Y827515D03*
X1401300Y820485D03*
X1395955Y832697D03*
X1402000Y840000D03*
Y848000D03*
X1399872Y845109D03*
X1402000Y864000D03*
X1391316Y857849D03*
X1388488Y857822D03*
X1402000Y876000D03*
X1390182Y873460D03*
X1387582Y873487D03*
X1402000Y884000D03*
Y892000D03*
X1388479Y892923D03*
X1385979D03*
X1390979D03*
X1402000Y900000D03*
X1387520Y905307D03*
X1387753Y912629D03*
X1394891Y914783D03*
X1402187Y908270D03*
X1387504Y899931D03*
X1390541Y900086D03*
X1388980Y921075D03*
X1401000Y925789D03*
X1396869Y958707D03*
X1402064Y965913D03*
X1389192Y992568D03*
X1398854Y987277D03*
X1394885Y999941D03*
X1392031Y1004375D03*
X1385732Y1029482D03*
X1389762Y1043055D03*
X1387813Y1030952D03*
X1399807Y1036155D03*
X1399852Y1039779D03*
X1388523Y1090090D03*
X1392691Y1089224D03*
X1392086Y1092743D03*
X1392691Y1086724D03*
Y1084224D03*
Y1081724D03*
X1390191D03*
Y1084224D03*
Y1086724D03*
X1403101Y1104335D03*
X1400543Y1105552D03*
X1396749Y1104792D03*
X1388451Y1093048D03*
X1386656Y1107997D03*
X1398256Y1106867D03*
X1386756Y1110597D03*
X1394341Y1113648D03*
X1388992Y1118801D03*
Y1116101D03*
X1387541Y1113648D03*
X1391841D03*
X1388722Y1162384D03*
Y1164884D03*
Y1167384D03*
Y1169884D03*
Y1172384D03*
X1391222Y1162384D03*
Y1164884D03*
Y1167384D03*
Y1169884D03*
Y1172384D03*
X1388722Y1174884D03*
X1391222D03*
X1393695Y1186709D03*
Y1184209D03*
Y1181709D03*
Y1179209D03*
X1391380Y1190121D03*
Y1192621D03*
X1385821Y1260160D03*
X1391821Y1257160D03*
X1394821D03*
X1385821D03*
X1388821D03*
X1397821Y1260160D03*
Y1257160D03*
X1400821Y1260160D03*
Y1257160D03*
X1388821Y1260160D03*
X1394821D03*
X1391821D03*
X1385052Y1303139D03*
X1389052D03*
X1406308Y103411D03*
X1406702Y97667D03*
X1417498Y90650D03*
X1417248Y95236D03*
X1402098Y95111D03*
X1406948Y111255D03*
Y114655D03*
X1406467Y106561D03*
X1406948Y128828D03*
Y125428D03*
X1403845Y199248D03*
X1401827Y195176D03*
X1404327D03*
X1403845Y202048D03*
X1407445Y230117D03*
X1403461Y238714D03*
X1402942Y246874D03*
X1405162Y244297D03*
X1402921Y322403D03*
X1409830Y347649D03*
X1404690Y362209D03*
X1416912Y386903D03*
X1408854Y381207D03*
X1416470Y381397D03*
X1402968Y390177D03*
X1414369Y398056D03*
X1408254Y398041D03*
X1407844Y411033D03*
X1415610Y417644D03*
X1415674Y421278D03*
X1417856Y448419D03*
X1414903Y469905D03*
X1410903Y470419D03*
Y461919D03*
X1418903Y461419D03*
X1411269Y481467D03*
X1415623Y492268D03*
X1415823Y482165D03*
X1416061Y504825D03*
X1413561D03*
X1411061D03*
X1415064Y500202D03*
X1406910Y495982D03*
X1416413Y495649D03*
X1406910Y491982D03*
X1416002Y517401D03*
X1413502D03*
X1411002D03*
X1416553Y522569D03*
Y525369D03*
X1415168Y531882D03*
X1412668D03*
X1409618Y531948D03*
X1401438Y534211D03*
X1405992Y534909D03*
X1405619Y541135D03*
X1405685Y546553D03*
X1405708Y552726D03*
X1415103Y555194D03*
Y563194D03*
Y571194D03*
X1416660Y581222D03*
Y591215D03*
X1401383Y611071D03*
X1416832Y610562D03*
Y607762D03*
X1411622Y610548D03*
X1407566Y622285D03*
X1407754Y616905D03*
X1418439Y633736D03*
X1407952Y633724D03*
X1413432Y633716D03*
X1407835Y627713D03*
X1405229Y652028D03*
X1405000Y660000D03*
X1410000Y685000D03*
Y681000D03*
X1404500Y675000D03*
X1410000Y701000D03*
Y697000D03*
X1418000Y696000D03*
Y701000D03*
X1410000Y709000D03*
Y713000D03*
X1405000Y707000D03*
Y703000D03*
X1418000Y717000D03*
X1410000D03*
X1404500Y722000D03*
X1410000Y729000D03*
Y725000D03*
X1418000Y724000D03*
Y729000D03*
X1404249Y735858D03*
X1410000Y745000D03*
Y741000D03*
X1418000Y740000D03*
Y745000D03*
X1407482Y750853D03*
X1410000Y757000D03*
Y753000D03*
Y761000D03*
X1418000D03*
X1406867Y783273D03*
X1409115Y773520D03*
X1414597Y792375D03*
X1406483Y811717D03*
X1413500Y832000D03*
Y828000D03*
X1413449Y823934D03*
X1405402Y819917D03*
X1405500Y844000D03*
Y836000D03*
X1413500Y848000D03*
Y840000D03*
Y836000D03*
Y844000D03*
X1405500Y860000D03*
X1413500Y864000D03*
Y860000D03*
Y856000D03*
Y852000D03*
X1405500Y880000D03*
Y868000D03*
X1413500Y876000D03*
X1417797Y879501D03*
X1413500Y872000D03*
Y868000D03*
X1405500Y888000D03*
Y896000D03*
X1417081D03*
X1413500Y892000D03*
Y884000D03*
Y888000D03*
X1413733Y911137D03*
X1412376Y907848D03*
X1414876D03*
X1417376D03*
X1409876D03*
X1405500Y904000D03*
X1404760Y915186D03*
X1413500Y904000D03*
Y900000D03*
X1417284Y911009D03*
X1416802Y936845D03*
X1416244Y942285D03*
X1419337D03*
X1405214Y965074D03*
X1419446Y977192D03*
X1416618Y992307D03*
X1401265Y989465D03*
X1407265D03*
X1414143Y985486D03*
X1412698Y997590D03*
X1412609Y1008766D03*
X1412759Y1016266D03*
X1402215Y1020440D03*
X1414851Y1058097D03*
X1412351D03*
X1407351D03*
X1409851D03*
X1417351D03*
X1414851Y1060697D03*
X1412351D03*
X1407351D03*
X1409851D03*
X1417351D03*
X1405677Y1086796D03*
X1408177D03*
X1410677D03*
X1413177D03*
X1415677D03*
Y1084296D03*
X1413177D03*
X1410677D03*
X1408177D03*
X1405677D03*
X1416005Y1090288D03*
X1410546Y1106298D03*
X1404821Y1101917D03*
X1404756Y1106897D03*
X1416005Y1093088D03*
X1414584Y1107997D03*
X1411237Y1115896D03*
X1407571Y1110092D03*
X1414584Y1113797D03*
X1416784Y1112397D03*
X1414584Y1110897D03*
X1416684Y1109397D03*
X1411237Y1118396D03*
X1409425Y1129238D03*
X1413177Y1128894D03*
X1409492Y1167384D03*
Y1169884D03*
Y1172384D03*
X1406992D03*
Y1169884D03*
X1416550Y1162384D03*
Y1164884D03*
Y1167384D03*
Y1169884D03*
Y1172384D03*
X1406992Y1167384D03*
Y1164884D03*
Y1162384D03*
X1409492D03*
Y1164884D03*
X1416736Y1158200D03*
X1416550Y1174884D03*
X1409492D03*
X1406992D03*
X1407995Y1179421D03*
Y1181921D03*
Y1184421D03*
Y1186921D03*
X1410310Y1192621D03*
Y1190121D03*
X1404845D03*
Y1192621D03*
X1408736Y1222194D03*
X1412736D03*
X1416736D03*
X1408736Y1238194D03*
Y1234194D03*
Y1230194D03*
Y1226194D03*
X1412736Y1238194D03*
Y1234194D03*
Y1230194D03*
Y1226194D03*
X1416736Y1238194D03*
Y1234194D03*
Y1230194D03*
Y1226194D03*
X1412736Y1246194D03*
Y1242194D03*
X1416736Y1246194D03*
Y1242194D03*
X1408736D03*
Y1246194D03*
X1409821Y1260160D03*
X1412821D03*
Y1257160D03*
X1409821D03*
X1406821D03*
X1403821D03*
X1415821Y1260160D03*
Y1257160D03*
X1403821Y1260160D03*
X1406821D03*
X1417711Y1301729D03*
X1410817Y1305417D03*
X1407825Y1426975D03*
X1408536Y1536570D03*
X1407747Y1549054D03*
X1408044Y1559306D03*
X1407255Y1571732D03*
X1422810Y90615D03*
X1427131Y99961D03*
X1427181Y95236D03*
X1425993Y212978D03*
Y207978D03*
Y210478D03*
Y215478D03*
X1429322Y264180D03*
X1431822D03*
X1429247Y258880D03*
X1434166Y325361D03*
X1434164Y339232D03*
X1434038Y334114D03*
X1435818Y352361D03*
X1421005Y407616D03*
X1417903Y439919D03*
X1434997Y442603D03*
X1427117Y443071D03*
X1423427Y456839D03*
X1425927D03*
X1423427Y454339D03*
X1425927D03*
X1432414Y459371D03*
X1423427Y459339D03*
X1425927D03*
X1418903Y469905D03*
X1431484Y470045D03*
X1427484Y462004D03*
X1422499Y485138D03*
X1419650Y485128D03*
X1426384Y478625D03*
X1428084Y482425D03*
X1427499Y485138D03*
X1424999D03*
X1426384Y476125D03*
X1418253Y529169D03*
X1417668Y531882D03*
X1424129Y537658D03*
X1427832Y539731D03*
X1424129Y540458D03*
X1432590Y544895D03*
X1435390D03*
X1427832Y542231D03*
X1432890Y541895D03*
X1417903Y555194D03*
Y563194D03*
Y571194D03*
X1422260Y581222D03*
X1419460D03*
X1435119Y590801D03*
X1422260Y591215D03*
X1419460D03*
X1431000Y591000D03*
X1434944Y597130D03*
X1433114Y620653D03*
Y617853D03*
X1419632Y607762D03*
X1422432D03*
X1425232Y610562D03*
Y607762D03*
X1422432Y610562D03*
X1419632D03*
X1430944Y605443D03*
X1420452Y628078D03*
X1430175Y627852D03*
X1425452Y633473D03*
X1430481Y658153D03*
X1433529Y660564D03*
X1426615Y674112D03*
X1429000Y685000D03*
X1418000D03*
Y681000D03*
X1425909Y691120D03*
X1433464Y692658D03*
X1418000Y689000D03*
X1433053Y701839D03*
X1426000Y717000D03*
X1418000Y705000D03*
X1431522Y708633D03*
X1434000Y712958D03*
X1430289Y734961D03*
X1418000Y733000D03*
X1417969Y720894D03*
X1429000Y729000D03*
X1434000Y751958D03*
X1433153Y745839D03*
X1427000Y766500D03*
X1426000Y761000D03*
X1435000Y765500D03*
X1434000Y756958D03*
X1418023Y765343D03*
X1427000Y781834D03*
Y770500D03*
X1435000D03*
X1427000Y794500D03*
X1435000Y802500D03*
X1427000Y810500D03*
Y814500D03*
X1435000D03*
Y809500D03*
X1427000Y802500D03*
Y830500D03*
Y826500D03*
X1434975Y830500D03*
X1435000Y825500D03*
X1427000Y842500D03*
Y838500D03*
X1435000Y846500D03*
X1427000D03*
X1435043Y874694D03*
X1435082Y869475D03*
X1423190Y905295D03*
X1429059Y908579D03*
X1426085Y910281D03*
X1429907Y936998D03*
X1424897Y936777D03*
X1435516Y936000D03*
X1420699Y958452D03*
X1430839Y965546D03*
X1420740Y1008766D03*
X1428740Y1000766D03*
X1420740Y996766D03*
X1428864D03*
X1420740Y1012266D03*
X1428740Y1016266D03*
X1428823Y1020266D03*
X1435229Y1104335D03*
X1432671Y1105552D03*
X1428877Y1104792D03*
X1418784Y1107997D03*
X1430384Y1106867D03*
X1418884Y1110597D03*
X1421120Y1116101D03*
Y1118801D03*
X1426469Y1113648D03*
X1423969D03*
X1419669D03*
X1419050Y1162384D03*
Y1164884D03*
Y1167384D03*
Y1169884D03*
Y1172384D03*
Y1174884D03*
X1420625Y1186709D03*
Y1184209D03*
Y1181709D03*
Y1179209D03*
X1418310Y1192621D03*
Y1190121D03*
X1420736Y1222194D03*
X1424736D03*
X1428736D03*
X1432736D03*
X1420736Y1238194D03*
Y1234194D03*
Y1230194D03*
Y1226194D03*
X1424736Y1238194D03*
Y1234194D03*
Y1230194D03*
Y1226194D03*
X1428736Y1238194D03*
Y1234194D03*
Y1230194D03*
Y1226194D03*
X1432736Y1234194D03*
Y1230194D03*
Y1226194D03*
X1420736Y1246194D03*
Y1242194D03*
X1424736Y1246194D03*
Y1242194D03*
X1428736Y1246194D03*
Y1242194D03*
X1421821Y1257160D03*
X1418821D03*
Y1260160D03*
X1421821D03*
X1431080Y1301702D03*
X1421238Y1301712D03*
X1428009Y1301760D03*
X1424732Y1301603D03*
X1432258Y1414600D03*
X1430374Y1492474D03*
X1420877Y1494706D03*
X1421964Y1502813D03*
X1423930Y1520364D03*
X1429587Y1527450D03*
X1433405Y1546001D03*
X1432913Y1568679D03*
X1449685Y34228D03*
X1436045Y77393D03*
Y74793D03*
Y85193D03*
Y82593D03*
Y79993D03*
X1444370Y98551D03*
X1436089Y92874D03*
X1447265Y111223D03*
Y114623D03*
X1447920Y103783D03*
X1438116Y107649D03*
Y104249D03*
X1447265Y125396D03*
Y128796D03*
X1442682Y147540D03*
X1446454Y141247D03*
X1451301Y148277D03*
X1435138Y162368D03*
X1437738D03*
X1444838Y162793D03*
Y165393D03*
Y170493D03*
Y167993D03*
X1451762Y177616D03*
X1449841Y181009D03*
X1447046Y181366D03*
X1443835Y181426D03*
X1444043Y184221D03*
X1446660Y184012D03*
X1448079Y211359D03*
Y213859D03*
X1436449Y213213D03*
Y210713D03*
X1440521Y211695D03*
X1443021D03*
X1440521Y208695D03*
X1443321D03*
X1436449Y208213D03*
Y215713D03*
X1451785Y265896D03*
X1446698Y265701D03*
X1441016Y267526D03*
Y270026D03*
X1443516D03*
X1438216D03*
X1443516Y267526D03*
X1438216D03*
X1448333Y281716D03*
X1449060Y329861D03*
X1448948Y326448D03*
X1449060Y320861D03*
X1438829Y329861D03*
X1437064Y320861D03*
X1448822Y345324D03*
X1448734Y332910D03*
X1448500Y340575D03*
X1439712Y336673D03*
X1440420Y346833D03*
X1449060Y356861D03*
X1441180Y354909D03*
X1448572Y349441D03*
X1449060Y352361D03*
X1447502Y360785D03*
X1434697Y347125D03*
X1439719Y350387D03*
X1443041Y363648D03*
X1434608Y362584D03*
X1438768Y371655D03*
X1442633Y371502D03*
X1445906Y366030D03*
X1440523Y382747D03*
X1435424Y430361D03*
X1440390Y456652D03*
X1442890D03*
Y459152D03*
Y461652D03*
X1440390Y459152D03*
Y461652D03*
X1436930Y461818D03*
X1433960Y491214D03*
X1449293Y491133D03*
X1442721Y495151D03*
X1437663Y492987D03*
X1442421Y498151D03*
X1433960Y493714D03*
X1437663Y495487D03*
X1445221Y498151D03*
X1449293Y493633D03*
Y496133D03*
Y498633D03*
X1445221Y495151D03*
X1439462Y537877D03*
X1449393Y553297D03*
Y555897D03*
X1446988Y548418D03*
X1439462Y540377D03*
X1435390Y541895D03*
X1444488Y548418D03*
X1439488D03*
X1441988D03*
X1439462Y542877D03*
Y545377D03*
X1449393Y558497D03*
Y566797D03*
Y563697D03*
Y561097D03*
X1443388Y570686D03*
X1446183Y570478D03*
X1435668Y582747D03*
X1446600Y576484D03*
X1446243Y573689D03*
X1443597Y573303D03*
X1449993Y578405D03*
X1438944Y597232D03*
X1443775Y596089D03*
X1448994Y596782D03*
X1440930Y613913D03*
Y616713D03*
Y619513D03*
X1434944Y605443D03*
X1438944Y605637D03*
X1437790Y625013D03*
X1435952Y642184D03*
X1446323Y673183D03*
X1437738Y686992D03*
X1448991Y694392D03*
X1451976Y693844D03*
X1437533Y704398D03*
Y699280D03*
X1438930Y716363D03*
X1446860Y730735D03*
X1446538Y719548D03*
X1437738Y730992D03*
X1446717Y735536D03*
X1437533Y743280D03*
Y748398D03*
X1447289Y776461D03*
X1446000Y770500D03*
X1451000Y793458D03*
Y798458D03*
X1450253Y787339D03*
X1443000Y802500D03*
X1447000Y810500D03*
Y818500D03*
X1435000D03*
X1448000Y834500D03*
X1443000Y846500D03*
X1435000Y834500D03*
X1449000Y844500D03*
X1435212Y854042D03*
X1448726Y864400D03*
X1439891Y873821D03*
X1445367Y891888D03*
X1441223Y891957D03*
X1435745Y901500D03*
X1443231Y899006D03*
X1439103Y898564D03*
X1447261Y898571D03*
X1446022Y927000D03*
X1448137Y949440D03*
X1439031Y957683D03*
X1441088Y976409D03*
X1433996Y981437D03*
X1440700Y981763D03*
X1435669Y1005366D03*
X1440869Y1010256D03*
X1435197Y1028372D03*
X1442674Y1106365D03*
X1436949Y1101917D03*
X1436884Y1106897D03*
X1439699Y1110092D03*
X1443365Y1115896D03*
Y1118396D03*
X1442448Y1160834D03*
X1434820Y1162384D03*
Y1164884D03*
Y1167384D03*
Y1169884D03*
Y1172384D03*
X1437320D03*
Y1169884D03*
Y1167384D03*
Y1164884D03*
Y1162384D03*
X1434925Y1179421D03*
Y1181921D03*
Y1184421D03*
Y1186921D03*
X1434820Y1174884D03*
X1437320D03*
X1437240Y1192621D03*
Y1190121D03*
X1436736Y1222194D03*
Y1226194D03*
X1443660Y1310698D03*
X1440260D03*
X1446817Y1335846D03*
X1441200Y1338700D03*
X1435900Y1340800D03*
X1439258Y1414600D03*
X1446135Y1530876D03*
X1443103Y1527201D03*
X1441145Y1540415D03*
X1440153Y1563093D03*
X1443769Y1562173D03*
X1452717Y34052D03*
X1457347Y31518D03*
X1457829Y26425D03*
X1455013Y43128D03*
X1460466Y76587D03*
Y72615D03*
X1461905Y100625D03*
X1454924Y97475D03*
X1454855Y106186D03*
X1457667Y118335D03*
Y121735D03*
Y132509D03*
Y135909D03*
X1462484Y141247D03*
X1466971Y143518D03*
X1453921Y143740D03*
X1466071Y152373D03*
X1455016Y168697D03*
X1452343Y172190D03*
X1464628Y171523D03*
X1456104Y191941D03*
X1464158Y192490D03*
X1458113Y206767D03*
X1463113D03*
X1460613D03*
X1451782Y213132D03*
X1463243Y221708D03*
X1460743D03*
X1458243D03*
X1457658Y224421D03*
X1459358Y231021D03*
Y228221D03*
X1451782Y215632D03*
X1459909Y236189D03*
X1464909D03*
X1462409D03*
X1459850Y248765D03*
X1464850D03*
X1462350D03*
X1452026Y256303D03*
X1456801Y266114D03*
X1460047Y270695D03*
Y268195D03*
X1462547Y270695D03*
Y268195D03*
X1465347Y270695D03*
Y268195D03*
X1454274Y281982D03*
X1459060Y320861D03*
Y325361D03*
Y329861D03*
Y338861D03*
Y343361D03*
Y334361D03*
Y347861D03*
Y352361D03*
X1459873Y391705D03*
X1463145Y391579D03*
X1458214Y406231D03*
X1464536Y433114D03*
X1458912Y581659D03*
X1455419Y578986D03*
X1454944Y596729D03*
X1453000Y614158D03*
Y616958D03*
Y619758D03*
X1450944Y605443D03*
X1458944D03*
X1461474Y655807D03*
X1455761Y683448D03*
X1468372Y673812D03*
X1460111Y683536D03*
X1451428Y673252D03*
X1460816Y727964D03*
X1455291Y759656D03*
X1455159Y763714D03*
X1454504Y777575D03*
X1454533Y784780D03*
X1454738Y772492D03*
X1454533Y789898D03*
X1453102Y821102D03*
X1454541Y831339D03*
X1453102Y826500D03*
X1452619Y836457D03*
X1461113Y871389D03*
X1457218Y888764D03*
X1452641Y888033D03*
X1451286Y898549D03*
X1462500Y905295D03*
X1461888Y936055D03*
X1462000Y957000D03*
X1458202Y960288D03*
X1457937Y966712D03*
X1457352Y976277D03*
X1459519Y989432D03*
X1467096Y988813D03*
X1456966Y998507D03*
X1458892Y1007522D03*
X1465658Y1006648D03*
X1465846Y1023900D03*
X1463025Y1018307D03*
X1459267Y1013678D03*
X1456280Y1023405D03*
X1459683Y1028377D03*
X1481905Y-69278D03*
Y-72678D03*
X1479972Y40780D03*
X1472146Y55513D03*
X1468371Y68581D03*
X1474746Y60513D03*
X1477606Y60438D03*
X1468384Y80581D03*
X1474874Y85731D03*
X1483287Y86012D03*
X1472514Y88801D03*
X1478428Y86046D03*
X1475431Y94351D03*
X1479380Y94279D03*
X1470567Y103621D03*
X1478624Y116594D03*
X1466278Y112083D03*
X1484567Y110784D03*
X1478624Y119594D03*
X1479058Y124283D03*
X1484124Y124879D03*
X1477465Y161306D03*
X1469221Y152562D03*
X1474716Y157370D03*
X1478800Y168665D03*
Y176665D03*
X1469913Y183834D03*
X1470023Y178560D03*
X1470086Y172665D03*
X1470899Y186629D03*
X1469433Y190185D03*
X1478800Y192665D03*
Y196665D03*
X1470203Y200864D03*
X1478913Y186778D03*
X1478832Y204864D03*
X1470292Y212455D03*
X1470226Y207037D03*
X1478832Y208864D03*
X1467593Y221642D03*
X1474473Y219379D03*
X1475101Y228631D03*
X1480589Y248371D03*
X1471507Y265897D03*
X1469007D03*
X1477549Y327200D03*
Y322700D03*
Y345200D03*
Y340700D03*
Y331700D03*
Y358700D03*
Y349700D03*
Y354200D03*
X1480702Y368516D03*
X1468309Y408861D03*
X1475236Y412482D03*
X1466231Y423671D03*
X1469538Y416795D03*
X1466653Y428582D03*
X1471375Y433115D03*
X1477597Y682997D03*
X1475264Y680933D03*
X1474713Y685247D03*
X1479297Y693630D03*
X1476794Y691447D03*
X1476716Y704398D03*
X1479500Y689630D03*
Y697630D03*
X1474425Y712925D03*
X1479759Y720885D03*
X1469957Y706957D03*
X1474000Y707000D03*
X1479794Y709388D03*
X1472000Y727500D03*
X1469116Y719055D03*
X1480000Y731500D03*
X1479759Y743500D03*
X1479657Y735500D03*
X1469957Y750957D03*
X1476716Y748398D03*
X1480000Y739500D03*
X1471006Y744818D03*
X1470801Y739280D03*
X1474425Y756925D03*
X1479665Y754555D03*
X1474000Y753093D03*
X1476677Y827626D03*
X1473489Y861354D03*
X1474060Y877196D03*
X1473468Y874267D03*
X1482387Y872940D03*
X1474883Y868206D03*
X1473433Y891043D03*
X1473387Y897425D03*
X1482195Y885807D03*
X1470925Y920575D03*
X1480343Y914776D03*
X1480109Y943496D03*
X1480144Y946880D03*
X1479441Y961941D03*
X1480414Y952214D03*
X1476500Y974000D03*
X1482237Y966028D03*
X1479196Y970000D03*
X1480414Y975064D03*
X1475096Y980330D03*
X1471096D03*
X1479096Y988813D03*
X1471296D03*
X1475096D03*
X1483096D03*
X1475062Y1008300D03*
Y1002453D03*
X1482535Y1024254D03*
X1468869Y1018469D03*
X1476230Y1030672D03*
X1473230D03*
X1471374Y1118654D03*
X1474384Y1109564D03*
X1480231D03*
X1474384Y1122164D03*
X1480231D03*
X1474384Y1134764D03*
X1480231D03*
X1474384Y1147364D03*
X1480231D03*
X1474384Y1172564D03*
X1480231D03*
X1474384Y1159964D03*
X1480231D03*
X1474384Y1185164D03*
X1480231D03*
X1483308Y1214372D03*
X1479063Y1218169D03*
X1498621Y19043D03*
X1489556Y17645D03*
X1498621Y31043D03*
Y23043D03*
X1489829Y29424D03*
X1490563Y23043D03*
X1500210Y97667D03*
X1483287Y94374D03*
X1490593Y116594D03*
X1495866Y102495D03*
X1489567Y110784D03*
X1490593Y119594D03*
X1494127Y125107D03*
X1489146Y124663D03*
X1495600Y142862D03*
X1496641Y148717D03*
X1490490Y138838D03*
X1493260Y226320D03*
X1493194Y221970D03*
X1490481Y216385D03*
X1493194Y216970D03*
Y219470D03*
X1486681Y218085D03*
X1483881D03*
X1496221Y228646D03*
X1495178Y232971D03*
X1491828Y244571D03*
X1489208Y249108D03*
X1499171Y256394D03*
X1497446Y295877D03*
X1486860Y327200D03*
X1500659Y330024D03*
X1495605Y322700D03*
X1487318Y318200D03*
X1486360Y322700D03*
Y345200D03*
X1500386Y344642D03*
X1486913Y340327D03*
X1487152Y331272D03*
X1495689Y332534D03*
X1495521Y340700D03*
X1486360Y349700D03*
X1495521Y349681D03*
X1495925Y358700D03*
X1499839Y354001D03*
X1486890Y368576D03*
X1494286Y372699D03*
X1488000Y731500D03*
X1495500Y750500D03*
X1488731Y739500D03*
X1496629Y765000D03*
X1496763Y777000D03*
X1493301Y776911D03*
X1496814Y773000D03*
X1497000Y781000D03*
X1496756Y785000D03*
X1491425Y798425D03*
X1499633Y787794D03*
X1493716Y789898D03*
X1486957Y792457D03*
X1495170Y796670D03*
X1487050Y809413D03*
X1496845Y809000D03*
X1496806Y817000D03*
X1496621Y829000D03*
X1496447Y821000D03*
X1486386Y825296D03*
X1493092Y820444D03*
X1493038Y833898D03*
X1495240Y825000D03*
X1491425Y842425D03*
X1486957Y836457D03*
X1492625Y837324D03*
X1488138Y878339D03*
Y872839D03*
X1482566Y882154D03*
X1494954Y895264D03*
X1484824Y927324D03*
X1487240Y924453D03*
X1497063Y934000D03*
X1496072Y940201D03*
X1483324Y939324D03*
X1482921Y931324D03*
X1485500Y932500D03*
X1497075Y961000D03*
X1487240Y952012D03*
X1496072Y953981D03*
X1495500Y972500D03*
X1489500D03*
X1487096Y988813D03*
X1491096D03*
X1495096D03*
X1499096D03*
X1490235Y1004816D03*
X1487266Y1002046D03*
X1486030Y1016827D03*
X1491877D03*
X1486030Y1029427D03*
X1491877D03*
X1496140Y1105091D03*
X1496185Y1102091D03*
X1496140Y1117691D03*
X1496185Y1114691D03*
Y1127291D03*
X1496140Y1130291D03*
X1496185Y1139891D03*
X1496140Y1155491D03*
Y1142891D03*
X1496185Y1152491D03*
X1496140Y1168091D03*
X1496185Y1165091D03*
X1496140Y1180691D03*
X1496185Y1177691D03*
X1482705Y1200001D03*
X1489793Y1207737D03*
X1497693Y1230407D03*
X1508670Y103411D03*
X1509064Y97667D03*
X1504460Y95111D03*
X1509310Y114655D03*
Y111255D03*
X1508829Y106561D03*
X1502010Y121742D03*
X1509310Y125428D03*
Y128828D03*
X1502010Y118342D03*
Y132515D03*
Y135915D03*
X1502741Y143762D03*
X1506689Y195176D03*
X1506207Y199248D03*
X1501689Y195176D03*
X1503207Y199248D03*
X1499189Y195176D03*
X1504189D03*
X1506207Y202048D03*
X1503207Y201748D03*
X1499270Y210509D03*
X1501043Y206806D03*
X1501770Y210509D03*
X1503543Y206806D03*
X1509807Y230117D03*
X1500962Y230556D03*
X1505217Y227824D03*
X1505823Y238714D03*
X1499947Y242078D03*
X1505304Y246874D03*
X1507524Y244297D03*
X1503884Y295549D03*
X1501500Y321000D03*
X1501000Y317500D03*
X1501684Y336561D03*
X1516838Y347422D03*
X1515909Y354601D03*
X1511950Y401513D03*
Y398113D03*
X1509550Y412287D03*
Y415687D03*
Y426460D03*
Y440633D03*
Y429860D03*
Y444033D03*
X1516636Y458711D03*
X1509550Y472787D03*
Y469387D03*
Y483560D03*
Y486960D03*
Y516921D03*
Y513521D03*
Y527694D03*
Y531094D03*
X1513284Y552466D03*
X1504495Y796844D03*
X1510527Y833500D03*
X1504938Y859711D03*
X1500353Y859855D03*
X1500638Y873839D03*
X1512712Y867418D03*
X1502158Y899479D03*
X1510527Y908951D03*
X1513927D03*
X1504208Y909740D03*
X1509274Y921226D03*
X1505337Y921240D03*
X1509500Y937000D03*
Y944138D03*
X1516500Y947500D03*
X1501812Y938397D03*
X1512161Y957541D03*
X1509500Y950500D03*
X1498973Y975443D03*
X1511000Y970500D03*
X1511096Y988813D03*
X1507096D03*
X1503096D03*
X1515096D03*
X1513286Y1012354D03*
X1507831Y1009354D03*
X1507786Y1012354D03*
Y1024954D03*
X1513286D03*
X1507831Y1021954D03*
X1503572Y1034538D03*
X1501640Y1105091D03*
Y1117691D03*
Y1130291D03*
Y1142891D03*
Y1155491D03*
Y1168091D03*
Y1180691D03*
X1508356Y1220068D03*
X1500675Y1227300D03*
X1506807Y1234921D03*
X1507692Y1224472D03*
X1507058Y1229402D03*
X1517261Y-33758D03*
Y-30358D03*
X1525172Y90615D03*
X1519860Y90650D03*
X1529493Y99961D03*
X1529543Y95236D03*
X1519610D03*
X1528355Y210478D03*
Y215478D03*
Y212978D03*
Y207978D03*
X1519321Y378600D03*
X1519952Y391001D03*
X1519321Y382600D03*
X1519952Y394401D03*
Y408574D03*
Y405174D03*
Y422747D03*
Y419347D03*
Y436921D03*
Y433521D03*
X1519436Y458711D03*
X1521963Y453682D03*
X1520200Y455921D03*
X1518780Y463600D03*
X1519952Y479899D03*
Y476499D03*
Y490673D03*
Y494073D03*
Y520633D03*
Y524033D03*
Y534806D03*
Y538206D03*
X1519185Y603600D03*
Y619600D03*
Y623600D03*
X1520729Y634190D03*
X1524200Y646098D03*
X1518517Y878898D03*
X1518452Y873780D03*
X1525022Y909558D03*
X1522881Y901034D03*
X1522954Y897951D03*
X1521085Y921094D03*
X1515179D03*
X1527267Y932647D03*
X1522209Y937846D03*
X1521500Y947500D03*
X1528500Y947612D03*
X1529128Y952978D03*
X1521085Y957340D03*
X1525583Y968500D03*
X1530767Y972981D03*
X1519863Y977637D03*
X1525005Y974323D03*
X1530594Y979952D03*
X1531096Y988813D03*
X1523096D03*
X1519096D03*
X1527096Y997860D03*
X1526810Y1025090D03*
X1522904Y1021256D03*
X1521939Y1040818D03*
X1522099Y1035521D03*
X1531993Y1056453D03*
X1531961Y1050849D03*
X1524953Y1051037D03*
X1517855Y1053457D03*
X1538407Y85539D03*
Y82939D03*
Y75139D03*
Y80339D03*
Y77739D03*
X1546732Y98551D03*
X1538451Y92874D03*
X1540478Y107649D03*
Y104249D03*
X1545044Y147540D03*
X1540100Y162368D03*
X1537500D03*
X1547200Y162793D03*
Y165393D03*
Y167993D03*
Y170493D03*
X1546197Y181426D03*
X1546405Y184221D03*
X1538811Y213213D03*
Y210713D03*
X1542883Y211695D03*
X1545383D03*
X1542883Y208695D03*
X1545683D03*
X1538811Y208213D03*
Y215713D03*
X1534184Y264180D03*
X1531684D03*
X1531609Y258880D03*
X1549060Y265701D03*
X1545878Y270026D03*
X1543378D03*
X1540578D03*
X1543378Y267526D03*
X1540578D03*
X1545878D03*
X1544736Y305156D03*
X1545583Y316363D03*
X1539140Y320863D03*
X1545636Y325363D03*
X1542797Y329863D03*
X1545846Y334363D03*
X1544951Y343363D03*
X1538133Y354553D03*
X1545434Y352363D03*
X1546183Y541863D03*
Y545263D03*
X1544375Y553407D03*
X1546875D03*
X1544375Y550907D03*
X1546875D03*
X1542704Y572162D03*
X1543946Y569928D03*
X1546293Y570962D03*
X1546036Y568475D03*
X1548080Y910757D03*
X1547644Y903060D03*
X1532067Y1041832D03*
X1531947Y1046212D03*
X1531546Y1062769D03*
X1536909Y1151870D03*
Y1159350D03*
X1540649Y1155610D03*
X1562828Y72615D03*
Y76587D03*
X1564267Y100625D03*
X1557286Y97475D03*
X1549627Y111223D03*
Y114623D03*
X1557217Y106186D03*
X1550282Y103783D03*
X1549627Y128796D03*
X1560029Y132509D03*
Y121735D03*
Y118335D03*
X1549627Y125396D03*
X1560029Y135909D03*
X1548816Y141247D03*
X1564846D03*
X1556283Y143740D03*
X1553663Y148277D03*
X1552203Y181009D03*
X1549408Y181366D03*
X1557378Y168697D03*
X1554705Y172190D03*
X1554124Y177616D03*
X1558466Y191941D03*
X1549022Y184012D03*
X1560475Y206767D03*
X1562975D03*
X1554144Y213132D03*
X1550441Y211359D03*
Y213859D03*
X1560605Y221708D03*
X1560020Y224421D03*
X1563105Y221708D03*
X1561720Y231021D03*
Y228221D03*
X1554144Y215632D03*
X1562271Y236189D03*
X1562212Y248765D03*
X1554388Y256303D03*
X1559163Y266114D03*
X1554147Y265896D03*
X1562409Y268195D03*
Y270695D03*
X1556636Y281982D03*
X1550695Y281716D03*
X1550931Y305158D03*
X1554403Y316363D03*
X1553534Y327337D03*
X1553910Y331798D03*
X1553597Y336601D03*
X1553862Y344867D03*
X1551175Y347283D03*
X1556588Y545528D03*
X1548359Y569426D03*
X1548645Y566929D03*
X1562385Y610400D03*
X1564670Y650122D03*
X1565132Y668153D03*
X1561552Y665455D03*
X1548629Y927836D03*
X1548504Y915689D03*
X1548616Y931602D03*
X1551163Y952888D03*
X1552000Y969850D03*
X1571895Y58013D03*
X1570733Y68581D03*
X1577108Y60513D03*
X1570746Y80581D03*
X1577236Y85731D03*
X1574876Y88801D03*
X1581742Y94279D03*
X1577793Y94351D03*
X1572929Y103621D03*
X1568640Y112083D03*
X1581420Y124283D03*
X1569333Y143518D03*
X1568433Y152373D03*
X1579827Y161306D03*
X1571583Y152562D03*
X1577078Y157370D03*
X1572275Y183834D03*
X1566990Y171523D03*
X1572385Y178560D03*
X1572448Y172665D03*
X1573261Y186629D03*
X1571795Y190185D03*
X1566520Y192490D03*
X1572565Y200864D03*
X1565475Y206767D03*
X1572654Y212455D03*
X1572588Y207037D03*
X1581194Y208864D03*
X1565605Y221708D03*
X1569955Y221642D03*
X1576835Y219379D03*
X1577463Y228631D03*
X1564771Y236189D03*
X1567271D03*
X1564712Y248765D03*
X1567212D03*
X1567709Y270695D03*
X1573869Y265897D03*
X1571369D03*
X1567709Y268195D03*
X1564909Y270695D03*
Y268195D03*
X1563877Y325363D03*
Y316363D03*
X1571625Y344131D03*
X1574775Y333549D03*
X1563877Y329863D03*
Y343363D03*
Y334363D03*
X1578587Y341787D03*
X1578420Y338309D03*
X1574775Y344127D03*
X1563877Y352363D03*
X1575935Y382109D03*
X1576940Y398082D03*
Y401482D03*
Y415655D03*
Y412255D03*
Y426428D03*
Y440602D03*
Y429828D03*
Y444002D03*
Y476468D03*
Y490641D03*
Y479868D03*
Y494041D03*
Y520602D03*
Y524002D03*
Y534775D03*
Y538175D03*
X1577862Y554121D03*
X1575934Y561420D03*
Y558917D03*
X1565323Y577716D03*
X1571755Y577937D03*
X1579760Y595500D03*
X1574760Y606929D03*
X1579260Y604567D03*
X1574720Y618400D03*
X1575001Y612592D03*
X1580418Y610072D03*
X1580354Y616317D03*
X1576297Y627600D03*
X1577077Y631712D03*
X1574880Y645891D03*
X1571888Y649380D03*
X1572141Y662981D03*
X1578000Y678776D03*
X1569434Y677111D03*
X1568872Y686971D03*
X1575192Y707592D03*
X1592187Y-69306D03*
Y-72706D03*
X1582187Y-33786D03*
Y-30386D03*
X1579968Y60438D03*
X1585649Y86012D03*
Y94374D03*
X1580790Y86046D03*
X1592955Y116594D03*
X1580986D03*
X1586929Y110784D03*
X1591929D03*
X1592955Y119594D03*
X1580986D03*
X1596489Y125107D03*
X1586486Y124879D03*
X1591508Y124663D03*
X1592852Y138838D03*
X1581162Y168665D03*
Y176665D03*
Y192665D03*
Y196665D03*
X1581275Y186778D03*
X1581194Y204864D03*
X1586243Y218085D03*
X1595622Y226320D03*
X1592843Y216385D03*
X1595556Y216970D03*
Y219470D03*
Y221970D03*
X1589043Y218085D03*
X1594190Y244571D03*
X1591570Y249108D03*
X1582951Y248371D03*
X1595069Y337361D03*
X1595109Y342663D03*
X1594466Y350984D03*
X1584240Y390995D03*
Y408568D03*
Y405168D03*
Y394395D03*
Y419341D03*
Y422741D03*
Y433515D03*
Y436915D03*
X1592635Y455911D03*
X1584240Y472781D03*
Y469381D03*
X1591443Y465332D03*
X1584240Y483554D03*
Y486954D03*
Y516915D03*
Y513515D03*
Y531088D03*
Y527688D03*
X1595460Y549800D03*
X1595260Y547075D03*
X1594760Y568000D03*
X1595364Y562800D03*
X1595300Y558800D03*
X1596790Y1442557D03*
X1592643Y1460707D03*
X1593019Y1457557D03*
X1591775Y1473090D03*
X1596038Y1492000D03*
X1591925Y1512075D03*
X1591333Y1501980D03*
X1590748Y1523377D03*
X1602572Y97667D03*
X1611032Y103411D03*
X1611426Y97667D03*
X1606822Y95111D03*
X1611672Y111255D03*
Y114655D03*
X1598228Y102495D03*
X1611191Y106561D03*
X1604372Y118342D03*
X1611672Y125428D03*
X1604372Y121742D03*
X1611672Y128828D03*
X1604372Y132515D03*
Y135915D03*
X1597962Y142862D03*
X1605103Y143762D03*
X1599003Y148717D03*
X1604051Y195176D03*
X1605569Y199248D03*
X1601551Y195176D03*
X1606551D03*
X1609051D03*
X1608569Y199248D03*
X1603405Y206806D03*
X1605905D03*
X1601632Y210509D03*
X1604132D03*
X1608569Y202048D03*
X1605569Y201748D03*
X1603324Y230556D03*
X1607579Y227824D03*
X1612169Y230117D03*
X1598583Y228646D03*
X1608185Y238714D03*
X1602309Y242078D03*
X1607666Y246874D03*
X1597540Y232971D03*
X1609886Y244297D03*
X1604677Y253198D03*
X1596691Y287397D03*
X1596197Y293477D03*
X1607947Y332326D03*
X1605966Y343794D03*
X1602138Y351047D03*
X1596253Y375633D03*
X1596534Y379760D03*
X1599527Y396718D03*
X1596760Y530000D03*
X1596260Y540500D03*
X1611316Y685800D03*
X1611027Y722427D03*
X1611327Y735973D03*
X1611627Y780327D03*
X1609500Y776100D03*
X1611873Y795127D03*
X1606190Y803774D03*
X1606709Y819165D03*
X1600333Y1440504D03*
X1596836Y1446488D03*
X1600333Y1449068D03*
X1601968Y1453442D03*
X1597457Y1460662D03*
X1605430Y1468023D03*
X1597039Y1475100D03*
X1599726Y1474990D03*
X1600008Y1488492D03*
X1601500Y1514500D03*
X1608500Y1506000D03*
Y1515000D03*
X1613790Y1531334D03*
X1609348Y1527334D03*
X1613790Y1523334D03*
X1604000Y1519000D03*
X1600732Y1539334D03*
X1609348Y1535334D03*
X1598574Y1543373D03*
X1622222Y90650D03*
X1627534Y90615D03*
X1621972Y95236D03*
X1626147Y351033D03*
X1628636Y422088D03*
X1623955Y442956D03*
X1625772Y438323D03*
X1621596Y456386D03*
X1625938Y445873D03*
X1620385Y465874D03*
X1627965Y474424D03*
Y488597D03*
Y477824D03*
Y491997D03*
Y521958D03*
Y518558D03*
Y536131D03*
Y532731D03*
X1616622Y546712D03*
Y542712D03*
X1627965Y571997D03*
Y568597D03*
Y582771D03*
Y586171D03*
Y596944D03*
Y600344D03*
Y614517D03*
Y611117D03*
X1618538Y618288D03*
X1614538D03*
X1627224Y643252D03*
X1613362Y656321D03*
X1621362D03*
X1617362D03*
X1616260Y678462D03*
X1619950Y678519D03*
X1615913Y692245D03*
X1628200Y711417D03*
X1612800Y705900D03*
X1620600D03*
X1620500Y723200D03*
X1628343Y747288D03*
X1616683Y744517D03*
X1620100Y738300D03*
X1624000Y760900D03*
X1612573Y761427D03*
X1628027Y801427D03*
X1613117Y828117D03*
X1640769Y85539D03*
Y82939D03*
Y75139D03*
Y80339D03*
Y77739D03*
X1640813Y92874D03*
X1631905Y95236D03*
X1631855Y99961D03*
X1642840Y104249D03*
Y107649D03*
X1639862Y162368D03*
X1642462D03*
X1641173Y213213D03*
Y210713D03*
Y208213D03*
X1630717Y210478D03*
Y215478D03*
Y212978D03*
Y207978D03*
X1641173Y215713D03*
X1634046Y264180D03*
X1636546D03*
X1633971Y258880D03*
X1642940Y267526D03*
Y270026D03*
X1629553Y329067D03*
X1629302Y334402D03*
X1640030Y335550D03*
X1636561Y343072D03*
X1629514Y331727D03*
X1630691Y347432D03*
X1640197Y374690D03*
X1638340Y379536D03*
X1641615Y379600D03*
X1635170Y442856D03*
X1632439Y452265D03*
X1633225Y458455D03*
X1636271Y453881D03*
X1635185Y446595D03*
X1635265Y470737D03*
Y467337D03*
Y484910D03*
Y481510D03*
Y514871D03*
Y511471D03*
Y529044D03*
Y525644D03*
Y564910D03*
Y561510D03*
Y575684D03*
Y579084D03*
Y593257D03*
Y604030D03*
Y589857D03*
Y607430D03*
X1635283Y728117D03*
X1630327Y774627D03*
X1629927Y787327D03*
X1644552Y871353D03*
X1635176Y886761D03*
X1644718Y909263D03*
X1635000Y919263D03*
X1644325Y942120D03*
X1637771Y952120D03*
X1640581Y1551907D03*
X1649094Y98551D03*
X1659648Y97475D03*
X1651989Y114623D03*
Y111223D03*
X1652644Y103783D03*
X1659579Y106186D03*
X1651989Y125396D03*
Y128796D03*
X1647406Y147540D03*
X1651178Y141247D03*
X1658645Y143740D03*
X1656025Y148277D03*
X1649562Y162793D03*
Y165393D03*
Y167993D03*
Y170493D03*
X1656486Y177616D03*
X1654565Y181009D03*
X1648559Y181426D03*
X1651770Y181366D03*
X1659740Y168697D03*
X1657067Y172190D03*
X1660828Y191941D03*
X1651384Y184012D03*
X1648767Y184221D03*
X1647745Y211695D03*
X1645245Y208695D03*
X1648045D03*
X1656506Y213132D03*
X1652803Y211359D03*
Y213859D03*
X1645245Y211695D03*
X1656506Y215632D03*
X1656750Y256303D03*
X1656509Y265896D03*
X1661525Y266114D03*
X1651422Y265701D03*
X1648240Y267526D03*
X1645740D03*
Y270026D03*
X1648240D03*
X1653057Y281716D03*
X1658998Y281982D03*
X1658200Y315039D03*
X1654771Y352088D03*
X1645685Y381500D03*
X1648835Y390500D03*
X1650044Y435158D03*
X1649789Y440489D03*
X1646209Y442606D03*
X1650087Y444841D03*
X1649773Y449961D03*
X1653490Y458572D03*
X1645826Y446606D03*
X1647133Y463479D03*
X1647604Y467367D03*
X1656112Y768669D03*
X1657042Y773604D03*
X1647402Y881460D03*
X1648375Y886766D03*
X1650205Y925911D03*
X1647763Y919268D03*
X1648387Y945554D03*
X1647470Y952125D03*
X1651443Y981515D03*
X1647565Y981432D03*
X1652944Y993796D03*
X1653414Y990590D03*
X1676870Y55513D03*
X1673095Y68581D03*
X1679470Y60513D03*
X1673108Y80581D03*
X1665190Y76587D03*
Y72615D03*
X1679598Y85731D03*
X1677238Y88801D03*
X1675291Y103621D03*
X1666629Y100625D03*
X1671002Y112083D03*
X1662391Y118335D03*
Y121735D03*
Y132509D03*
Y135909D03*
X1667208Y141247D03*
X1671695Y143518D03*
X1670795Y152373D03*
X1673945Y152562D03*
X1674637Y183834D03*
X1669352Y171523D03*
X1674810Y172665D03*
X1674747Y178560D03*
X1675623Y186629D03*
X1674157Y190185D03*
X1668882Y192490D03*
X1667318Y198828D03*
X1674927Y200864D03*
X1664840Y192300D03*
X1662837Y206767D03*
X1667837D03*
X1665337D03*
X1674950Y207037D03*
X1675016Y212455D03*
X1667967Y221708D03*
X1665467D03*
X1664082Y231021D03*
Y228221D03*
X1672317Y221642D03*
X1662967Y221708D03*
X1662382Y224421D03*
X1669633Y236189D03*
X1667133D03*
X1664633D03*
X1667074Y248765D03*
X1664574D03*
X1669574D03*
X1676231Y265897D03*
X1673731D03*
X1670071Y268195D03*
Y270695D03*
X1667271Y268195D03*
X1664771D03*
Y270695D03*
X1667271D03*
X1673203Y328867D03*
X1668979Y339559D03*
X1666860Y353661D03*
X1663650Y353283D03*
X1673723Y353881D03*
X1670323Y353534D03*
X1670260Y377912D03*
X1669260Y391496D03*
X1663618Y393858D03*
X1663780Y384410D03*
X1666959Y382047D03*
X1670260Y386500D03*
X1669260Y409000D03*
X1665260Y398583D03*
X1670348Y397912D03*
X1667260Y403500D03*
X1663713Y440869D03*
Y438269D03*
X1666513Y433069D03*
Y430469D03*
Y435669D03*
Y440869D03*
Y438269D03*
X1663713Y433069D03*
Y430469D03*
Y435669D03*
X1664567Y451677D03*
X1667067D03*
X1664567Y454177D03*
X1667067D03*
X1666271Y460218D03*
Y463618D03*
X1682330Y60438D03*
X1688011Y86012D03*
Y94374D03*
X1683152Y86046D03*
X1680155Y94351D03*
X1684104Y94279D03*
X1683348Y116594D03*
X1694291Y110784D03*
X1689291D03*
X1683348Y119594D03*
X1683782Y124283D03*
X1693870Y124663D03*
X1688848Y124879D03*
X1695214Y138838D03*
X1682189Y161306D03*
X1679440Y157370D03*
X1683524Y168665D03*
Y176665D03*
Y192665D03*
X1683637Y186778D03*
X1683556Y204864D03*
Y208864D03*
X1688605Y218085D03*
X1691405D03*
X1679197Y219379D03*
X1679825Y228631D03*
X1693932Y249108D03*
X1685313Y248371D03*
X1686339Y314890D03*
X1686115Y311740D03*
X1683523Y324518D03*
X1677810Y324466D03*
X1686408Y332584D03*
X1687424Y347937D03*
X1692676Y348015D03*
X1688593Y353470D03*
X1691182Y357016D03*
X1680518Y377912D03*
Y381912D03*
Y397912D03*
X1692253Y467306D03*
Y470706D03*
Y484879D03*
Y481479D03*
Y511439D03*
Y514839D03*
Y529013D03*
Y525613D03*
X1689920Y539315D03*
X1689236Y550137D03*
X1692028D03*
X1692253Y561479D03*
Y564879D03*
Y575652D03*
Y579052D03*
Y593225D03*
Y603999D03*
Y589825D03*
Y607399D03*
X1693000Y626912D03*
X1692379Y622912D03*
X1704934Y97667D03*
X1709184Y95111D03*
X1695317Y116594D03*
X1700590Y102495D03*
X1695317Y119594D03*
X1706734Y118342D03*
Y132515D03*
Y121742D03*
X1698851Y125107D03*
X1706734Y135915D03*
X1700324Y142862D03*
X1707465Y143762D03*
X1701365Y148717D03*
X1708913Y195176D03*
X1710931Y199248D03*
X1706413Y195176D03*
X1703913D03*
X1707931Y199248D03*
Y201748D03*
X1706494Y210509D03*
X1703994D03*
X1705767Y206806D03*
X1708267D03*
X1697984Y226320D03*
X1695205Y216385D03*
X1697918Y216970D03*
Y219470D03*
Y221970D03*
X1705686Y230556D03*
X1709941Y228747D03*
X1700945Y228646D03*
X1704671Y242078D03*
X1699902Y232971D03*
X1696552Y244571D03*
X1703895Y256394D03*
X1700223Y292141D03*
X1703609Y287320D03*
X1698292Y303962D03*
X1702655Y474418D03*
Y477818D03*
Y488591D03*
Y491991D03*
Y521952D03*
Y518552D03*
Y536125D03*
Y532725D03*
X1698716Y550065D03*
X1702655Y571991D03*
Y568591D03*
Y586165D03*
Y582765D03*
Y600338D03*
Y596938D03*
Y611111D03*
Y614511D03*
X1708015Y1142700D03*
X1711333Y1146609D03*
X1706450Y1173065D03*
X1703400Y1174400D03*
X1713394Y103411D03*
X1713788Y97667D03*
X1724584Y90650D03*
X1724334Y95236D03*
X1714034Y111255D03*
Y114655D03*
X1713553Y106561D03*
X1714034Y125428D03*
Y128828D03*
X1711413Y195176D03*
X1710931Y202048D03*
X1714531Y230117D03*
X1710547Y238714D03*
X1710028Y246874D03*
X1712248Y244297D03*
X1716755Y326179D03*
X1712226Y344028D03*
X1715930Y340969D03*
X1715590Y331719D03*
X1721746Y377173D03*
X1715228Y387966D03*
X1718851Y391533D03*
X1720571Y385644D03*
X1725746Y385123D03*
X1718318Y399918D03*
X1725154Y406060D03*
X1725415Y416289D03*
Y418889D03*
Y421489D03*
X1721423Y412106D03*
X1716310Y454334D03*
X1724627Y459330D03*
X1724580Y454214D03*
X1724923Y449045D03*
X1724930Y473571D03*
Y476071D03*
Y478571D03*
Y481071D03*
X1710174Y553101D03*
X1717626Y1134729D03*
X1710511Y1138130D03*
X1721008Y1134729D03*
X1723805Y1142666D03*
X1725008Y1134636D03*
X1725680Y1157544D03*
X1724191Y1167768D03*
X1713239Y1176038D03*
X1712526Y1171950D03*
X1728343Y1185205D03*
X1719692Y1187215D03*
X1719385Y1180175D03*
X1712715Y1188500D03*
X1721662Y1201043D03*
X1725658D03*
X1718625Y1199814D03*
X1712542Y1196600D03*
X1720536Y1217228D03*
X1723200Y1219895D03*
X1710825Y1231688D03*
X1712966Y1229841D03*
X1736405Y-69278D03*
Y-72678D03*
X1743175Y92874D03*
X1729896Y90615D03*
X1734267Y95236D03*
X1734217Y99961D03*
X1742224Y162368D03*
X1733079Y207978D03*
Y210478D03*
Y215478D03*
Y212978D03*
X1736408Y264180D03*
X1738908D03*
X1736333Y258880D03*
X1744524Y379429D03*
X1741746Y377173D03*
X1737786D03*
X1729751D03*
X1733746Y385123D03*
X1730746D03*
X1737746D03*
X1741420Y391569D03*
X1739847Y401066D03*
X1729508Y403300D03*
X1728915Y405889D03*
Y408489D03*
Y413689D03*
Y411089D03*
Y416289D03*
Y421489D03*
Y418889D03*
Y424089D03*
X1729302Y432718D03*
Y435518D03*
X1739179Y439318D03*
X1728915Y426689D03*
X1739179Y442118D03*
X1733014Y450091D03*
X1730014D03*
X1727404Y447209D03*
X1730404D03*
X1738824Y456034D03*
Y461034D03*
X1733014Y462060D03*
X1730014D03*
X1734952Y479217D03*
X1737646Y477213D03*
Y479713D03*
X1729002Y477053D03*
X1731502D03*
X1734952Y476717D03*
X1741800Y917900D03*
X1742029Y1116251D03*
X1739508Y1137129D03*
X1729008Y1134729D03*
X1732881D03*
X1739917Y1150087D03*
X1732137Y1157404D03*
X1737393Y1170767D03*
X1729210Y1167768D03*
X1728333Y1178240D03*
X1733052Y1187310D03*
X1737689Y1185238D03*
X1737482Y1180235D03*
X1733662Y1201039D03*
X1729628Y1201043D03*
X1737662Y1200969D03*
X1737781Y1208993D03*
X1726475Y1223170D03*
X1731533Y1228226D03*
X1729322Y1226016D03*
X1743131Y85539D03*
Y82939D03*
Y75139D03*
Y80339D03*
Y77739D03*
X1751456Y98551D03*
X1754351Y111223D03*
Y114623D03*
X1755006Y103783D03*
X1745202Y104249D03*
Y107649D03*
X1754351Y128796D03*
Y125396D03*
X1744824Y162368D03*
X1751924Y162793D03*
Y165393D03*
Y167993D03*
Y170493D03*
X1758848Y177616D03*
X1759429Y172190D03*
X1756927Y181009D03*
X1750921Y181426D03*
X1754132Y181366D03*
X1751129Y184221D03*
X1753746Y184012D03*
X1747607Y211695D03*
X1755165Y211359D03*
Y213859D03*
X1750107Y211695D03*
X1747607Y208695D03*
X1750407D03*
X1743535Y208213D03*
Y213213D03*
Y210713D03*
Y215713D03*
X1753784Y265701D03*
X1758871Y265896D03*
X1750602Y267526D03*
X1745302D03*
X1748102D03*
X1745302Y270026D03*
X1748102D03*
X1750602D03*
X1755419Y281716D03*
X1748497Y371060D03*
X1752497Y371076D03*
X1750135Y379088D03*
X1755433Y379028D03*
X1744180Y383966D03*
X1750187Y409539D03*
X1753187D03*
X1750187Y406739D03*
X1753187Y407039D03*
X1752851Y401981D03*
X1755351D03*
X1757124Y398278D03*
X1754624D03*
X1749470Y424067D03*
X1751970D03*
X1756970D03*
X1754470D03*
X1749705Y413611D03*
X1752205D03*
X1757205D03*
X1754705D03*
X1756844Y438293D03*
X1747179Y439318D03*
X1756844Y441093D03*
X1747179Y442118D03*
X1756844Y443893D03*
X1747306Y470001D03*
X1744806D03*
X1756894Y472020D03*
X1756553Y466409D03*
X1756954Y477318D03*
X1745231Y489036D03*
X1743092Y485580D03*
X1745592D03*
X1748092D03*
X1758401Y484882D03*
X1756391Y487382D03*
X1747467Y492836D03*
Y495636D03*
X1756089Y542952D03*
X1750879Y541940D03*
X1754906Y824333D03*
Y820737D03*
X1746897Y879199D03*
X1746884Y884649D03*
X1747900Y900160D03*
X1744900D03*
X1750915Y902055D03*
X1749267Y918413D03*
X1751200Y931100D03*
X1746600Y935100D03*
X1751854Y991297D03*
X1749314Y987904D03*
X1745824Y987058D03*
X1748677Y993986D03*
X1753860Y997271D03*
X1759569Y1021944D03*
X1744529Y1116251D03*
X1758390Y1577905D03*
X1759947Y1599029D03*
X1750685Y1621654D03*
X1767552Y76587D03*
Y72615D03*
X1762010Y97475D03*
X1768991Y100625D03*
X1761941Y106186D03*
X1773364Y112083D03*
X1764753Y121735D03*
Y118335D03*
Y132509D03*
Y135909D03*
X1771714Y171523D03*
X1776999Y183834D03*
X1762102Y168697D03*
X1763190Y191941D03*
X1771244Y192490D03*
X1776519Y190185D03*
X1767202Y192300D03*
X1765199Y206767D03*
X1770199D03*
X1767699D03*
X1758868Y213132D03*
X1765329Y221708D03*
X1770329D03*
X1767829D03*
X1764744Y224421D03*
X1766444Y231021D03*
Y228221D03*
X1774679Y221642D03*
X1758868Y215632D03*
X1771995Y236189D03*
X1769495D03*
X1766995D03*
X1771936Y248765D03*
X1769436D03*
X1766936D03*
X1759112Y256303D03*
X1763887Y266114D03*
X1767133Y270695D03*
X1769633D03*
X1772433Y268195D03*
Y270695D03*
X1769633Y268195D03*
X1767133D03*
X1761360Y281982D03*
X1762997Y377581D03*
X1765497Y379591D03*
X1772513Y387702D03*
X1769713D03*
X1765913Y389402D03*
X1763200Y388817D03*
Y383817D03*
Y386317D03*
X1766837Y438293D03*
Y441093D03*
Y443893D03*
X1768586Y467560D03*
X1764903Y470382D03*
X1764906Y474382D03*
X1776561Y467560D03*
X1777061Y475560D03*
X1768575D03*
X1770135Y490711D03*
X1758957Y543036D03*
X1773789Y927663D03*
X1765664Y923724D03*
X1769064D03*
X1773789Y930663D03*
X1774476Y995049D03*
X1773810Y990821D03*
X1762486Y990260D03*
X1760201Y992475D03*
X1758881Y995633D03*
X1769004Y1019395D03*
X1768844Y1023694D03*
Y1027248D03*
X1771773Y1028829D03*
X1772188Y1428369D03*
X1766313Y1580198D03*
X1761072Y1590719D03*
X1765040Y1599511D03*
X1760422Y1640303D03*
X1768422D03*
X1772422D03*
X1762041Y1631511D03*
X1768422Y1632245D03*
X1773820Y1631238D03*
X1779232Y55513D03*
X1775457Y68581D03*
X1785246Y60660D03*
X1781832Y60513D03*
X1775470Y80581D03*
X1781960Y85731D03*
X1790712Y81713D03*
X1790664Y71908D03*
X1779600Y88801D03*
X1790373Y94663D03*
X1786466Y85923D03*
Y94279D03*
X1782517Y94351D03*
X1777653Y103621D03*
X1785886Y168665D03*
Y176665D03*
X1777172Y172665D03*
X1777109Y178560D03*
X1777985Y186629D03*
X1785779Y192665D03*
X1785886Y196665D03*
X1777289Y200864D03*
X1785999Y186778D03*
X1785918Y204864D03*
X1777378Y212455D03*
X1777312Y207037D03*
X1785918Y208864D03*
X1781559Y219379D03*
X1782187Y228631D03*
X1778593Y265897D03*
X1776093D03*
X1787674Y303130D03*
X1777681Y387151D03*
Y382151D03*
Y384651D03*
X1786184Y435321D03*
Y438121D03*
X1783384Y435321D03*
Y438121D03*
X1786184Y440921D03*
X1783384D03*
X1786184Y443721D03*
X1783384D03*
X1786170Y448931D03*
X1792527Y452799D03*
X1786693Y459170D03*
X1790061Y474513D03*
X1779404Y826570D03*
X1791041Y818795D03*
X1780016Y874400D03*
X1775904Y924546D03*
X1778047Y916120D03*
X1789537Y930498D03*
X1780158Y953295D03*
X1785758Y956095D03*
Y953295D03*
X1782958D03*
Y956095D03*
X1780158D03*
X1789363Y969160D03*
X1782563Y979660D03*
X1785663D03*
X1779363D03*
X1786863Y985060D03*
X1779143Y995203D03*
X1779033Y1023432D03*
X1786740Y1019237D03*
X1780802Y1019474D03*
X1774863Y1019237D03*
X1774844Y1023694D03*
X1783844D03*
X1786844Y1027248D03*
X1780844D03*
X1774844D03*
X1789844Y1023694D03*
X1775998Y1074707D03*
Y1072207D03*
X1781198Y1074707D03*
X1778598D03*
X1783798D03*
Y1072207D03*
X1778598D03*
X1781198D03*
X1790736Y1072090D03*
Y1074590D03*
X1780326Y1089851D03*
X1777726D03*
X1782926D03*
Y1092351D03*
X1777726D03*
X1780326D03*
X1775126Y1089851D03*
Y1092351D03*
X1790639Y1082585D03*
X1790572Y1085152D03*
X1780662Y1108413D03*
X1783262D03*
X1778062D03*
X1775462D03*
X1785321Y1121122D03*
X1787921D03*
X1790521D03*
X1780566Y1111038D03*
X1783166D03*
X1777966D03*
X1775366D03*
X1790521Y1130822D03*
X1781874Y1139822D03*
X1787921Y1130822D03*
X1785321D03*
X1784374Y1139822D03*
X1781802Y1147822D03*
X1784302D03*
X1783278Y1208140D03*
X1778227Y1438099D03*
X1786091Y1443715D03*
X1787745Y1437765D03*
X1783178Y1437550D03*
X1778104Y1470289D03*
X1801761Y-33888D03*
Y-30488D03*
X1791088Y77296D03*
X1804758Y294429D03*
X1793524Y303343D03*
X1805196Y300952D03*
X1799897Y408104D03*
X1802697D03*
X1805497D03*
X1793475Y424939D03*
X1799614Y420375D03*
X1802414D03*
X1805214D03*
X1793475Y427439D03*
X1809095Y435101D03*
X1803700Y440101D03*
X1803530Y431112D03*
X1809358Y442114D03*
X1803335Y452718D03*
X1809346Y452601D03*
X1797907Y452987D03*
X1809338Y447121D03*
X1804933Y461607D03*
X1796933D03*
X1796136Y471334D03*
X1800933Y461607D03*
X1802000Y892447D03*
X1797365Y930761D03*
X1793474Y930374D03*
X1805463Y969260D03*
X1801963Y969160D03*
X1802363Y989660D03*
X1803351Y1027471D03*
X1805188Y1019078D03*
X1799646Y1018999D03*
X1793470Y1018762D03*
X1801844Y1023694D03*
X1795844D03*
X1798844Y1027248D03*
X1792844D03*
X1795936Y1072090D03*
X1793336D03*
X1798536D03*
Y1074590D03*
X1793336D03*
X1795936D03*
X1801961Y1081717D03*
X1795819Y1088553D03*
X1800813Y1103246D03*
X1806206Y1114589D03*
X1803506D03*
X1800906D03*
X1798306D03*
X1798702Y1124328D03*
X1801302D03*
X1803902D03*
X1806602D03*
X1793221Y1121122D03*
Y1130822D03*
X1804532Y1133356D03*
X1807232D03*
X1807035Y1136912D03*
Y1144912D03*
X1806835Y1214668D03*
X1800489Y1220598D03*
X1807243Y1219955D03*
X1802670Y1210905D03*
X1805126Y1225745D03*
X1799845Y1261044D03*
X1794845D03*
X1797345D03*
X1799845Y1263544D03*
X1797345D03*
X1794845D03*
X1803885Y1435046D03*
X1806428Y1444543D03*
X1795374D03*
X1802813Y1464015D03*
X1803762Y1467236D03*
X1819900Y906900D03*
X1807663Y966660D03*
Y963860D03*
X1808014Y984832D03*
X1812538Y1026859D03*
X1811468Y1021084D03*
X1807844Y1023694D03*
Y1027248D03*
X1810349Y1031264D03*
X1816756Y1089145D03*
Y1094145D03*
X1816235Y1083970D03*
X1810346Y1082250D03*
X1816756Y1097145D03*
Y1101145D03*
X1810310Y1104819D03*
X1809535Y1136912D03*
Y1144912D03*
X1812130Y1205349D03*
X1822594Y1211054D03*
Y1215324D03*
X1814741Y1217093D03*
X1811482Y1226423D03*
X1810018Y1295944D03*
X1812818D03*
X1815618Y1298744D03*
Y1295944D03*
X1812818Y1298744D03*
X1810018D03*
X1812202Y1432624D03*
X1809342Y1476733D03*
X1824706Y1085145D03*
X1824949Y1077145D03*
X1824706Y1100185D03*
Y1106145D03*
X1828272Y1095968D03*
X1824706Y1093150D03*
X1830915Y1109146D03*
X1834665Y1213239D03*
G54D22*
X51750Y617861D03*
X48207D03*
X44664D03*
X51750Y620661D03*
X48207D03*
X44664D03*
X55294Y617861D03*
Y620661D03*
X146948Y1088287D03*
X143208D03*
X146948Y1099507D03*
X143208D03*
X146948Y1106988D03*
X143208D03*
X146948Y1114468D03*
Y1121948D03*
X143208Y1114468D03*
Y1121948D03*
X146948Y1129429D03*
X143208D03*
X146948Y1136909D03*
X143208D03*
X146948Y1148129D03*
X143208D03*
X146947Y1170570D03*
X143207D03*
X146947Y1178051D03*
X143207D03*
X165649Y1073326D03*
X158169D03*
X150689D03*
X165649Y1092027D03*
X158169D03*
X150689D03*
X165649Y1077066D03*
X161909Y1084547D03*
X158169Y1077066D03*
X154429Y1084547D03*
X161909Y1080807D03*
X154429D03*
X165649Y1095767D03*
X161909Y1103247D03*
X158169Y1095767D03*
X154429Y1103247D03*
X150689Y1095767D03*
X161909Y1099507D03*
X154429D03*
X161909Y1118208D03*
Y1121948D03*
X165649Y1110728D03*
X161909D03*
X154429D03*
Y1118208D03*
X150689Y1110728D03*
Y1118208D03*
X154429Y1125688D03*
X150689D03*
Y1133169D03*
X165649D03*
X161909D03*
X154429D03*
X165649Y1148129D03*
Y1144389D03*
Y1155610D03*
X160039Y1176180D03*
X156299D03*
X169389Y1084547D03*
Y1080807D03*
Y1103247D03*
X173129Y1136909D03*
X169389D03*
X176870Y1151870D03*
Y1148129D03*
Y1144389D03*
X169389Y1151870D03*
Y1148129D03*
X176870Y1166830D03*
Y1159350D03*
X169389D03*
X176870Y1174310D03*
Y1178051D03*
Y1181791D03*
X188090Y1114468D03*
X184350D03*
X191830D03*
X195570D03*
X191830Y1140649D03*
Y1136909D03*
X195570Y1140649D03*
X184350Y1136909D03*
X191830Y1133169D03*
Y1129429D03*
Y1144389D03*
Y1151869D03*
X195570Y1148129D03*
Y1155610D03*
X184350Y1144389D03*
X188090Y1155610D03*
X184350Y1151870D03*
X188090Y1148129D03*
X191830Y1159350D03*
Y1170570D03*
X195570Y1166830D03*
X184350Y1159350D03*
Y1170570D03*
X188090Y1166830D03*
X191830Y1185531D03*
Y1178051D03*
X195570Y1181791D03*
Y1174310D03*
X184350Y1185531D03*
X188090Y1181791D03*
Y1174310D03*
X184350Y1178051D03*
X191830Y1193011D03*
X195570Y1215452D03*
X197440Y1217322D03*
X186220D03*
X189960D03*
Y1213582D03*
X203051Y1114468D03*
X199311D03*
X206791D03*
X210531D03*
X206791Y1136909D03*
X203051D03*
X199311D03*
X214271D03*
X210531D03*
X199311Y1129429D03*
X206791D03*
X214271D03*
X210531D03*
X203051D03*
X210531Y1155610D03*
X203051D03*
X206791Y1144389D03*
X203051D03*
X199311D03*
X214271D03*
X210531D03*
X214271Y1151870D03*
X210531D03*
X206791D03*
X203051D03*
X199311D03*
X214271Y1170570D03*
X210531Y1166830D03*
X214271Y1159350D03*
X206791Y1170570D03*
X203051Y1166830D03*
X199311Y1170570D03*
X206791Y1159350D03*
X199311D03*
X203051Y1174310D03*
X210531D03*
X203051Y1185531D03*
X199311D03*
X206791D03*
X214271D03*
X210531D03*
X206791Y1178051D03*
X203051D03*
X199311D03*
X214271D03*
X210531D03*
X214271Y1193011D03*
X210531D03*
X199311D03*
X203051D03*
X206791D03*
X214271Y1200491D03*
X210531D03*
X199311D03*
X206791D03*
X203051D03*
X201181Y1213582D03*
X214271Y1211712D03*
X208661Y1213582D03*
X203051Y1215452D03*
X214271D03*
X201181Y1217322D03*
X208661D03*
X210531Y1215452D03*
X204921Y1213582D03*
X225492Y1114468D03*
X221752D03*
X218011D03*
X225492Y1136909D03*
X221751D03*
X218011D03*
X229232D03*
Y1129429D03*
X218011D03*
X221751D03*
X225492D03*
X218011Y1155610D03*
X225492D03*
Y1144389D03*
X221751D03*
X218011D03*
X229232D03*
Y1151870D03*
X221752D03*
X218011D03*
X225492D03*
Y1166830D03*
X221751Y1170570D03*
X218011Y1166830D03*
X221751Y1159350D03*
X229232Y1170570D03*
Y1159350D03*
X225492Y1174310D03*
X218011D03*
X225492Y1185531D03*
X218011D03*
X221751D03*
X229232D03*
X225492Y1178051D03*
X221751D03*
X218011D03*
X229232D03*
X218011Y1193011D03*
X221751D03*
X225492D03*
X229232D03*
X218011Y1200491D03*
X221751D03*
X225492D03*
X229232D03*
X218011Y1215452D03*
X229232Y1211712D03*
Y1215452D03*
X225492Y1211712D03*
X221752D03*
Y1215452D03*
X240452Y1114468D03*
X244192D03*
X236712Y1118208D03*
X244192D03*
X236712Y1114468D03*
X240452Y1118208D03*
Y1136909D03*
X236712D03*
X244192D03*
Y1129429D03*
X240452D03*
X236712D03*
Y1155610D03*
X244192D03*
X240452Y1151869D03*
X236712D03*
X244192D03*
X240452Y1144389D03*
X236712D03*
X244192D03*
X236712Y1166830D03*
X240452Y1170570D03*
Y1159350D03*
X244192Y1166830D03*
X236712Y1174310D03*
X244192D03*
X240452Y1185531D03*
X236712D03*
X244192D03*
X240452Y1178051D03*
X236712D03*
X244192D03*
X240452Y1193011D03*
X236712D03*
X244192D03*
X236712Y1200491D03*
X244192D03*
X240452D03*
X244192Y1215452D03*
X240452D03*
X242322Y1217322D03*
X236712Y1211712D03*
Y1215452D03*
X238582Y1217322D03*
X262893Y1118208D03*
X259153Y1114468D03*
X262893D03*
X255413Y1118208D03*
Y1114468D03*
X247933D03*
X259153Y1118208D03*
X251673Y1114468D03*
X247933Y1118208D03*
X251673D03*
X255413Y1136909D03*
X251673D03*
X247933D03*
X259153D03*
X262893D03*
X247933Y1129429D03*
X259153D03*
X262893D03*
X255413D03*
X251673D03*
Y1155610D03*
X259153D03*
X251673Y1144389D03*
X247933D03*
X255413D03*
X259153Y1151869D03*
X262893D03*
X247933D03*
X255413D03*
X251673D03*
X262893Y1144389D03*
X259153D03*
X251673Y1166830D03*
X255413Y1170570D03*
X247933D03*
X255413Y1159350D03*
X247933D03*
X259153Y1166830D03*
X262893Y1170570D03*
Y1159350D03*
X251673Y1174310D03*
X259153D03*
X247933Y1185531D03*
X255413D03*
X251673D03*
X259153D03*
X262893D03*
X251673Y1178051D03*
X247933D03*
X255413D03*
X259153D03*
X262893D03*
X251673Y1193011D03*
X255413D03*
X247933D03*
X262893D03*
X259153D03*
Y1200491D03*
X262893D03*
X251673D03*
X247933D03*
X255413D03*
Y1215452D03*
X262893D03*
X247932Y1215451D03*
X259153Y1215452D03*
X251673D03*
X247932Y1211711D03*
X251673D03*
X270373Y1114468D03*
X274114D03*
X277854D03*
X266633Y1136909D03*
Y1129429D03*
X274114D03*
Y1140649D03*
Y1136909D03*
X266633Y1155610D03*
X277854D03*
X266633Y1151869D03*
Y1144389D03*
X274114D03*
X277854Y1159350D03*
Y1166830D03*
Y1170570D03*
X266633D03*
X270373D03*
X266633Y1159350D03*
X270373D03*
Y1166830D03*
X266633D03*
Y1174310D03*
X277854D03*
X266633Y1185531D03*
Y1178051D03*
X270373Y1181791D03*
X274114Y1185531D03*
Y1189271D03*
Y1178051D03*
X266633Y1193011D03*
Y1200491D03*
X274114D03*
Y1193011D03*
X277854Y1204232D03*
Y1196751D03*
Y1200491D03*
X274114Y1215452D03*
X277854D03*
X266633D03*
X274114Y1211712D03*
X277854Y1207972D03*
X285334Y1118208D03*
X281594D03*
X285334Y1114468D03*
X281594D03*
X289074Y1140649D03*
X285334D03*
Y1136909D03*
X292815Y1140649D03*
X285334Y1155610D03*
X281594Y1144389D03*
X285334Y1148129D03*
Y1144389D03*
X289074Y1148129D03*
X292815D03*
Y1155610D03*
X285334Y1170570D03*
Y1166830D03*
Y1159350D03*
X292815Y1170570D03*
X285334Y1174310D03*
X289074Y1189271D03*
X285334D03*
X281594Y1181791D03*
X285334Y1178051D03*
X289074Y1181791D03*
X285334Y1196751D03*
Y1204232D03*
X281594Y1200491D03*
X285334D03*
Y1207972D03*
Y1215452D03*
Y1211712D03*
X281594Y1215452D03*
Y1207972D03*
X311515Y1140649D03*
X304035Y1144389D03*
Y1151869D03*
X307775Y1144389D03*
Y1151869D03*
X296555Y1155610D03*
X311515Y1148129D03*
Y1155610D03*
X304035Y1166830D03*
Y1159350D03*
X307775Y1166830D03*
X296555Y1170570D03*
X311515D03*
X304035Y1174310D03*
Y1181791D03*
Y1189271D03*
X307775Y1174310D03*
Y1181791D03*
Y1189271D03*
X311515Y1178051D03*
Y1185531D03*
Y1193011D03*
X322736Y1136909D03*
X326476D03*
X315255Y1140649D03*
X322736Y1144389D03*
Y1151870D03*
X326476Y1144389D03*
X315255Y1148129D03*
X326476Y1151870D03*
X315255Y1155610D03*
X322736Y1159350D03*
X326476D03*
X315255Y1170570D03*
X322736Y1174310D03*
Y1181791D03*
Y1189271D03*
X326476Y1174310D03*
X315255Y1178051D03*
X326476Y1181791D03*
X315255Y1185531D03*
X326476Y1189271D03*
X315255Y1193011D03*
X425023Y441086D03*
Y433999D03*
Y437543D03*
X422223Y441086D03*
Y433999D03*
Y437543D03*
X425023Y444629D03*
X422223D03*
X501750Y620661D03*
X505293D03*
X501750Y617861D03*
X505293D03*
X512380D03*
X508836Y620661D03*
Y617861D03*
X512380Y620661D03*
X600295Y1088287D03*
X604035D03*
X600295Y1099507D03*
X604035D03*
X600295Y1106988D03*
X604035D03*
Y1121948D03*
X600295D03*
Y1114468D03*
X604035D03*
X600295Y1136909D03*
X604035D03*
X600295Y1129429D03*
X604035D03*
Y1148129D03*
X600295D03*
X604034Y1170570D03*
X600294D03*
X604034Y1178051D03*
X600294D03*
X615256Y1073326D03*
X607776D03*
X618996Y1084547D03*
Y1080807D03*
X615256Y1077066D03*
X611516Y1080807D03*
Y1084547D03*
X607776Y1092027D03*
X615256D03*
X607776Y1095767D03*
X615256D03*
X618996Y1103247D03*
X611516D03*
X618996Y1099507D03*
X611516D03*
X618996Y1118208D03*
Y1121948D03*
X611516Y1118208D03*
X607776D03*
X611516Y1110728D03*
X618996D03*
X607776D03*
X611516Y1125688D03*
X607776D03*
Y1133169D03*
X615256Y1178051D03*
X611516D03*
X622736Y1073326D03*
Y1077066D03*
X626476Y1084547D03*
X622736Y1092027D03*
X626476Y1080807D03*
X622736Y1095767D03*
X626476Y1103247D03*
X622736Y1118208D03*
X626476Y1114468D03*
X622736Y1110728D03*
X630216Y1114468D03*
X633957Y1151870D03*
Y1148129D03*
Y1144389D03*
X626476Y1148129D03*
X622736Y1144389D03*
Y1148129D03*
X626476Y1151870D03*
X622736Y1155610D03*
X633957Y1166830D03*
Y1159350D03*
X626476D03*
X633957Y1174310D03*
Y1178051D03*
Y1181791D03*
X645177Y1114468D03*
X641437D03*
X648917D03*
X652657D03*
X648917Y1140649D03*
Y1136909D03*
X652657Y1140649D03*
X641437Y1136909D03*
X648917Y1129429D03*
Y1133169D03*
X652657Y1148129D03*
Y1155610D03*
X648917Y1144389D03*
Y1151869D03*
X641437Y1144389D03*
Y1151870D03*
X645177Y1155610D03*
Y1148129D03*
X648917Y1159350D03*
Y1170570D03*
X652657Y1166830D03*
X641437Y1170570D03*
X645177Y1166830D03*
X641437Y1159350D03*
X648917Y1185531D03*
Y1178051D03*
X652657Y1181791D03*
Y1174310D03*
X641437Y1185531D03*
Y1178051D03*
X645177Y1181791D03*
Y1174310D03*
X648917Y1193011D03*
X652657Y1215452D03*
Y1219192D03*
X641437Y1215452D03*
X648917D03*
X645177D03*
X660138Y1114468D03*
X656398D03*
X663878D03*
X667618D03*
Y1129429D03*
X660138D03*
X656398D03*
X663878D03*
Y1136909D03*
X660138D03*
X656398D03*
X667618D03*
X660138Y1155610D03*
X667618D03*
Y1144389D03*
X663878D03*
X660138D03*
X656398D03*
X667618Y1151870D03*
X663878D03*
X660138D03*
X656398D03*
X663878Y1170570D03*
X660138Y1166830D03*
X656398Y1170570D03*
X663878Y1159350D03*
X656398D03*
X667618Y1166830D03*
Y1174310D03*
X660138D03*
X667618Y1185531D03*
X660138D03*
X656398D03*
X663878D03*
X667618Y1178051D03*
X663878D03*
X660138D03*
X656398D03*
X667618Y1200491D03*
X656398D03*
X663878D03*
X660138D03*
X663878Y1193011D03*
X660138D03*
X656398D03*
X667618D03*
X663878Y1211712D03*
X656398D03*
X660138Y1215452D03*
X656398D03*
X663878D03*
X667618D03*
X660138Y1211712D03*
X682579Y1114468D03*
X678839D03*
X675098D03*
Y1129429D03*
X671358D03*
X678838D03*
X682579D03*
Y1136909D03*
X678838D03*
X675098D03*
X671358D03*
X682579Y1155610D03*
X675098D03*
X678839Y1151870D03*
X675098D03*
X671358D03*
X682579D03*
Y1144389D03*
X671358D03*
X678838D03*
X675098D03*
X682579Y1166830D03*
X678838Y1170570D03*
X671358D03*
X675098Y1166830D03*
X671358Y1159350D03*
X678838D03*
X682579Y1174310D03*
X675098D03*
X682579Y1185531D03*
X675098D03*
X671358D03*
X678838D03*
X682579Y1178051D03*
X678838D03*
X675098D03*
X671358D03*
X675098Y1200491D03*
X671358D03*
X678838D03*
X682579D03*
Y1193011D03*
X678838D03*
X675098D03*
X671358D03*
X682579Y1211712D03*
X678839D03*
Y1215452D03*
X671358Y1211712D03*
Y1215452D03*
X675098D03*
X693799Y1114468D03*
Y1118208D03*
X701279Y1114468D03*
X697539Y1118208D03*
Y1114468D03*
X701279Y1118208D03*
Y1129429D03*
X697539D03*
X693799D03*
X686319D03*
X697539Y1136909D03*
X693799D03*
X701279D03*
X686319D03*
X701279Y1155610D03*
X693799D03*
X701279Y1151869D03*
X697539D03*
X693799D03*
X701279Y1144389D03*
X697539D03*
X693799D03*
X686319D03*
Y1151870D03*
X693799Y1166830D03*
X697539Y1170570D03*
Y1159350D03*
X701279Y1166830D03*
X686319Y1170570D03*
Y1159350D03*
X701279Y1174310D03*
X693799D03*
X701279Y1185531D03*
X697539D03*
X693799D03*
X701279Y1178051D03*
X697539D03*
X693799D03*
X686319Y1185531D03*
Y1178051D03*
X701279Y1200491D03*
X697539D03*
X693799D03*
X686319D03*
X701279Y1193011D03*
X697539D03*
X693799D03*
X686319D03*
Y1211712D03*
Y1215452D03*
X699409Y1217322D03*
X697539Y1215452D03*
X693799D03*
Y1211712D03*
X701279Y1215452D03*
X695669Y1217322D03*
X708760Y1114468D03*
X716240Y1118208D03*
X705020Y1114468D03*
X712500D03*
X716240D03*
X705020Y1118208D03*
X712500D03*
X708760D03*
X705020Y1129429D03*
X708760D03*
X712500D03*
X716240D03*
Y1136909D03*
X705020D03*
X708760D03*
X712500D03*
X708760Y1155610D03*
X716240D03*
Y1151869D03*
X708760D03*
X712500D03*
X705020D03*
X712500Y1144389D03*
X705020D03*
X708760D03*
X716240D03*
Y1166830D03*
X705020Y1159350D03*
X712500D03*
X705020Y1170570D03*
X712500D03*
X708760Y1166830D03*
X716240Y1174310D03*
X708760D03*
X716240Y1185531D03*
X708760D03*
X712500D03*
X705020D03*
X716240Y1178051D03*
X712500D03*
X705020D03*
X708760D03*
X712500Y1200491D03*
X705020D03*
X708760D03*
X716240D03*
X708760Y1193011D03*
X712500D03*
X705020D03*
X716240D03*
Y1215452D03*
X708760D03*
X712500D03*
X705019Y1215451D03*
Y1211711D03*
X708760D03*
X731201Y1114468D03*
X734941D03*
X727460D03*
X719980Y1118208D03*
Y1114468D03*
Y1129429D03*
X723720D03*
X731201D03*
X719980Y1136909D03*
X723720D03*
X731201D03*
Y1140649D03*
X723720Y1155610D03*
X719980Y1151869D03*
X723720D03*
Y1144389D03*
X719980D03*
X734941Y1155610D03*
X731201Y1144389D03*
X719980Y1159350D03*
X727460D03*
X723720D03*
Y1166830D03*
X727460D03*
X719980Y1170570D03*
X727460D03*
X723720D03*
X734941Y1159350D03*
Y1166830D03*
Y1170570D03*
X723720Y1174310D03*
X727460Y1181791D03*
X719980Y1185531D03*
Y1178051D03*
X723720D03*
Y1185531D03*
X734941Y1174310D03*
X731201Y1189271D03*
Y1185531D03*
Y1178051D03*
X719980Y1200491D03*
X723720D03*
X731201D03*
X719980Y1193011D03*
X723720D03*
X731201D03*
X734941Y1196751D03*
Y1204232D03*
Y1200491D03*
X731201Y1215452D03*
X734941D03*
X723720D03*
X719980D03*
X731201Y1211712D03*
X734941Y1207972D03*
X727461Y1215452D03*
X738681Y1118208D03*
X742421D03*
X738681Y1114468D03*
X742421D03*
Y1140649D03*
Y1136909D03*
X746161Y1140649D03*
X749902D03*
X742421Y1155610D03*
X746161Y1148129D03*
X738681Y1144389D03*
X742421Y1148129D03*
Y1144389D03*
X749902Y1155610D03*
Y1148129D03*
X742421Y1159350D03*
Y1166830D03*
Y1170570D03*
X749902D03*
X742421Y1189271D03*
X746161D03*
X742421Y1174310D03*
X738681Y1181791D03*
X746161D03*
X742421Y1178051D03*
Y1196751D03*
X738681Y1200491D03*
X742421Y1204232D03*
Y1200491D03*
Y1211712D03*
Y1215452D03*
Y1207972D03*
X738681Y1215452D03*
Y1207972D03*
Y1211712D03*
X761122Y1144389D03*
Y1151869D03*
X753642Y1155610D03*
X764862Y1151869D03*
Y1144389D03*
Y1166830D03*
X761122D03*
Y1159350D03*
X753642Y1170570D03*
X764862Y1174310D03*
X761122Y1181791D03*
X764862D03*
X761122Y1174310D03*
X768602Y1140649D03*
X772342D03*
Y1148129D03*
Y1155610D03*
X783563Y1151870D03*
X779823D03*
Y1144389D03*
X783563D03*
X768602Y1155610D03*
Y1148129D03*
X779823Y1159350D03*
X772342Y1170570D03*
X768602D03*
X783563Y1159350D03*
Y1189271D03*
X768602Y1185531D03*
X772342Y1178051D03*
X779823Y1189271D03*
X772342Y1185531D03*
X783563Y1174310D03*
X779823D03*
X783563Y1181791D03*
X768602Y1178051D03*
X779823Y1181791D03*
X768602Y1193011D03*
X772342D03*
X920349Y450340D03*
X917549D03*
X920349Y453884D03*
Y457427D03*
X917549Y453884D03*
Y457427D03*
X920349Y460970D03*
X917549D03*
X962380Y617861D03*
X958837D03*
X962380Y620661D03*
X958837D03*
X969467D03*
X965923Y617861D03*
Y620661D03*
X969467Y617861D03*
X1057381Y1088287D03*
Y1106988D03*
Y1099507D03*
Y1114468D03*
Y1121948D03*
Y1129429D03*
Y1136909D03*
Y1148129D03*
X1057380Y1170570D03*
Y1178051D03*
X1072342Y1073326D03*
X1064862D03*
Y1092027D03*
X1072342Y1077066D03*
X1068602Y1084547D03*
Y1080807D03*
X1061121Y1088287D03*
X1072342Y1092027D03*
X1068602Y1099507D03*
X1072342Y1095767D03*
X1061121Y1106988D03*
X1068602Y1103247D03*
X1064862Y1095767D03*
X1061121Y1099507D03*
Y1114468D03*
X1068602Y1110728D03*
Y1118208D03*
X1064862Y1110728D03*
Y1118208D03*
X1061121Y1121948D03*
X1064862Y1125688D03*
X1068602D03*
X1061121Y1129429D03*
X1064862Y1133169D03*
X1061121Y1136909D03*
Y1148129D03*
X1061120Y1170570D03*
X1072342Y1178051D03*
X1068602D03*
X1061120D03*
X1079822Y1073326D03*
Y1092027D03*
X1083562Y1084547D03*
X1079822Y1077066D03*
X1076082Y1084547D03*
Y1080807D03*
X1083562D03*
X1076082Y1103247D03*
X1079822Y1095767D03*
X1076082Y1099507D03*
X1083562Y1103247D03*
X1079822Y1118208D03*
X1076082Y1121948D03*
Y1118208D03*
X1079822Y1110728D03*
X1083562Y1114468D03*
X1087302D03*
X1076082Y1110728D03*
X1091043Y1151870D03*
Y1148129D03*
Y1144389D03*
X1083562Y1148129D03*
X1079822Y1144389D03*
Y1148129D03*
X1083562Y1151870D03*
X1079822Y1155610D03*
X1091043Y1166830D03*
Y1159350D03*
X1083562D03*
X1091043Y1181791D03*
Y1178051D03*
Y1174310D03*
X1102263Y1114468D03*
X1098523D03*
X1106003D03*
Y1140649D03*
Y1136909D03*
X1098523D03*
X1106003Y1129429D03*
Y1133169D03*
Y1151869D03*
Y1144389D03*
X1098523D03*
Y1151870D03*
X1102263Y1148129D03*
Y1155610D03*
X1106003Y1170570D03*
Y1159350D03*
X1102263Y1166830D03*
X1098523Y1159350D03*
Y1170570D03*
X1106003Y1178051D03*
Y1185531D03*
X1098523D03*
X1102263Y1174310D03*
X1098523Y1178051D03*
X1102263Y1181791D03*
X1106003Y1193011D03*
Y1215452D03*
X1098523D03*
X1102263D03*
X1117224Y1114468D03*
X1113484D03*
X1120964D03*
X1124704D03*
X1109743D03*
X1120964Y1129429D03*
X1113484D03*
X1117224D03*
X1124704D03*
Y1136909D03*
X1113484D03*
X1117224D03*
X1120964D03*
X1109743Y1140649D03*
X1124704Y1144389D03*
X1113484D03*
X1117224D03*
X1120964D03*
X1113484Y1151870D03*
X1117224D03*
X1120964D03*
X1124704D03*
Y1155610D03*
X1109743D03*
Y1148129D03*
X1117224Y1155610D03*
X1113484Y1159350D03*
X1120964D03*
X1109743Y1166830D03*
X1113484Y1170570D03*
X1117224Y1166830D03*
X1120964Y1170570D03*
X1124704Y1166830D03*
X1113484Y1178051D03*
X1117224D03*
X1120964D03*
X1124704D03*
X1120964Y1185531D03*
X1113484D03*
X1117224D03*
X1124704D03*
X1109743Y1174310D03*
Y1181791D03*
X1117224Y1174310D03*
X1124704D03*
X1117224Y1200491D03*
X1120964D03*
X1113484D03*
X1124704D03*
X1120964Y1193011D03*
X1117224D03*
X1113484D03*
X1124704D03*
Y1215452D03*
X1120964D03*
Y1211712D03*
X1117224Y1215452D03*
X1109743D03*
X1113484Y1211712D03*
X1111613Y1217322D03*
X1115354D03*
X1117224Y1211712D03*
X1139665Y1114468D03*
X1135925D03*
X1132184D03*
Y1129429D03*
X1128444D03*
X1135924D03*
X1139665D03*
Y1136909D03*
X1135924D03*
X1132184D03*
X1128444D03*
Y1144389D03*
X1135924D03*
X1132184D03*
X1139665D03*
X1135925Y1151870D03*
X1132184D03*
X1128444D03*
X1139665D03*
Y1155610D03*
X1132184D03*
X1139665Y1166830D03*
X1135924Y1170570D03*
X1128444D03*
X1132184Y1166830D03*
X1128444Y1159350D03*
X1135924D03*
X1139665Y1178051D03*
X1135924D03*
X1132184D03*
X1128444D03*
X1139665Y1185531D03*
X1132184D03*
X1128444D03*
X1135924D03*
X1139665Y1174310D03*
X1132184D03*
Y1200491D03*
X1128444D03*
X1135924D03*
X1139665D03*
X1128444Y1193011D03*
X1132184D03*
X1135924D03*
X1139665D03*
Y1211712D03*
X1135925D03*
Y1215452D03*
X1128444D03*
X1132184D03*
X1128444Y1211712D03*
X1154625Y1118208D03*
X1150885D03*
X1154625Y1114468D03*
X1150885D03*
X1154625Y1129429D03*
X1150885D03*
X1143405D03*
Y1136909D03*
X1154625D03*
X1150885D03*
X1143405Y1144389D03*
X1150885Y1151869D03*
X1154625D03*
Y1144389D03*
X1150885D03*
X1143405Y1151870D03*
X1150885Y1155610D03*
X1143405Y1170570D03*
X1154625Y1159350D03*
X1143405D03*
X1150885Y1166830D03*
X1154625Y1170570D03*
X1143405Y1178051D03*
Y1185531D03*
X1154625D03*
X1150885D03*
X1154625Y1178051D03*
X1150885D03*
Y1174310D03*
X1143405Y1200491D03*
X1154625D03*
X1150885D03*
Y1193011D03*
X1154625D03*
X1143405D03*
Y1211712D03*
Y1215452D03*
X1150885Y1211712D03*
Y1215452D03*
X1154625D03*
X1156495Y1217322D03*
X1152755D03*
X1162106Y1114468D03*
X1169586D03*
X1162106Y1118208D03*
X1173326Y1114468D03*
X1158365Y1118208D03*
X1173326D03*
X1165846Y1114468D03*
X1158365D03*
X1169586Y1118208D03*
X1165846D03*
X1169586Y1129429D03*
X1165846D03*
X1162106D03*
X1158365D03*
X1173326D03*
Y1136909D03*
X1169586D03*
X1165846D03*
X1158365D03*
X1162106D03*
X1173326Y1151869D03*
X1158365D03*
X1162106D03*
X1169586D03*
X1165846D03*
X1173326Y1144389D03*
X1165846D03*
X1158365D03*
X1162106D03*
X1169586D03*
X1173326Y1155610D03*
X1165846D03*
X1158365D03*
X1173326Y1166830D03*
X1165846D03*
X1169586Y1170570D03*
X1158365Y1166830D03*
X1162106Y1170570D03*
X1169586Y1159350D03*
X1162106D03*
X1158365Y1185531D03*
X1162106D03*
X1169586D03*
X1165846D03*
X1173326D03*
X1165846Y1178051D03*
X1158365D03*
X1162106D03*
X1169586D03*
X1173326D03*
X1165846Y1174310D03*
X1158365D03*
X1173326D03*
Y1200491D03*
X1165846D03*
X1162106D03*
X1158365D03*
X1169586D03*
X1165846Y1193011D03*
X1169586D03*
X1158365D03*
X1162106D03*
X1173326D03*
Y1215452D03*
X1165846D03*
X1169586D03*
X1162105Y1215451D03*
X1158365Y1215452D03*
X1162105Y1211711D03*
X1165846D03*
X1188287Y1114468D03*
X1177066D03*
Y1118208D03*
X1184546Y1114468D03*
X1180806Y1129429D03*
X1177066D03*
X1188287D03*
X1180806Y1136909D03*
X1177066D03*
X1188287D03*
Y1140649D03*
X1180806Y1151869D03*
X1177066D03*
Y1144389D03*
X1180806D03*
Y1155610D03*
X1188287Y1144389D03*
X1180806Y1170570D03*
X1184546D03*
X1177066D03*
X1184546Y1166830D03*
X1180806D03*
X1177066Y1159350D03*
X1180806D03*
X1184546D03*
X1177066Y1185531D03*
Y1178051D03*
X1180806Y1185531D03*
Y1178051D03*
Y1174310D03*
X1184546Y1181791D03*
X1188287Y1185531D03*
Y1189271D03*
Y1178051D03*
X1180806Y1200491D03*
X1177066D03*
X1188287D03*
X1177066Y1193011D03*
X1180806D03*
X1188287D03*
Y1215452D03*
X1180806D03*
X1177066D03*
X1188287Y1211712D03*
X1199507Y1118208D03*
X1195767D03*
Y1114468D03*
X1192027D03*
X1199507D03*
Y1140649D03*
Y1136909D03*
X1203247Y1140649D03*
X1199507Y1155610D03*
X1192027D03*
X1203247Y1148129D03*
X1195767Y1144389D03*
X1199507Y1148129D03*
Y1144389D03*
Y1170570D03*
Y1166830D03*
Y1159350D03*
X1192027Y1166830D03*
Y1170570D03*
Y1159350D03*
X1203247Y1189271D03*
X1199507D03*
Y1174310D03*
X1195767Y1181791D03*
X1192027Y1174310D03*
X1199507Y1178051D03*
X1203247Y1181791D03*
X1199507Y1196751D03*
Y1204232D03*
X1195767Y1200491D03*
X1192027Y1196751D03*
Y1200491D03*
Y1204232D03*
X1199507Y1200491D03*
X1192027Y1215452D03*
X1199507Y1211712D03*
Y1215452D03*
Y1207972D03*
X1195767Y1215452D03*
X1192027Y1207972D03*
X1195767D03*
Y1211712D03*
X1206988Y1140649D03*
X1218208Y1144389D03*
Y1151869D03*
X1206988Y1155610D03*
Y1148129D03*
X1210728Y1155610D03*
X1221948Y1151869D03*
Y1144389D03*
X1218208Y1166830D03*
Y1159350D03*
X1221948Y1166830D03*
X1210728Y1170570D03*
X1206988D03*
X1218208Y1189271D03*
Y1174310D03*
X1221948Y1181791D03*
Y1174310D03*
X1218208Y1181791D03*
X1221948Y1189271D03*
X1236909Y1136909D03*
X1225688Y1140649D03*
X1229428D03*
X1236909Y1151870D03*
X1225688Y1148129D03*
X1229428D03*
X1225688Y1155610D03*
X1236909Y1144389D03*
X1229428Y1155610D03*
Y1170570D03*
X1225688D03*
X1236909Y1159350D03*
Y1181791D03*
X1225688Y1185531D03*
X1236909Y1189271D03*
X1229428Y1178051D03*
Y1185531D03*
X1236909Y1174310D03*
X1225688Y1178051D03*
Y1193011D03*
X1229428D03*
X1240649Y1136909D03*
Y1151870D03*
Y1144389D03*
Y1159350D03*
Y1174310D03*
Y1181791D03*
Y1189271D03*
X1339196Y441086D03*
Y433999D03*
Y437543D03*
X1336396Y441086D03*
Y433999D03*
Y437543D03*
X1339196Y444629D03*
X1336396D03*
X1415924Y620661D03*
Y617861D03*
X1423010Y620661D03*
X1419467Y617861D03*
X1423010D03*
X1426554Y620661D03*
Y617861D03*
X1419467Y620661D03*
X1514468Y1088287D03*
Y1099507D03*
Y1106988D03*
Y1121948D03*
Y1114468D03*
Y1129429D03*
Y1136909D03*
Y1148129D03*
Y1155610D03*
X1514467Y1170570D03*
Y1178051D03*
X1521949Y1073326D03*
X1529429D03*
Y1077066D03*
X1525689Y1084547D03*
X1529429Y1092027D03*
X1521949D03*
X1518208Y1088287D03*
X1525689Y1080807D03*
X1518208Y1099507D03*
X1525689D03*
X1529429Y1095767D03*
X1525689Y1103247D03*
X1518208Y1106988D03*
X1521949Y1095767D03*
Y1110728D03*
X1518208Y1114468D03*
X1525689Y1110728D03*
X1518208Y1121948D03*
X1521949Y1118208D03*
X1525689D03*
Y1125688D03*
X1518208Y1129429D03*
X1521949Y1125688D03*
X1518208Y1136909D03*
X1521949Y1133169D03*
X1518208Y1148129D03*
Y1155610D03*
X1518207Y1170570D03*
X1527559Y1176180D03*
X1518207Y1178051D03*
X1536909Y1073326D03*
X1533169Y1080807D03*
Y1084547D03*
X1540649Y1080807D03*
X1536909Y1077066D03*
X1540649Y1084547D03*
X1536909Y1092027D03*
Y1095767D03*
X1533169Y1099507D03*
X1540649Y1103247D03*
X1533169D03*
X1536909Y1118208D03*
X1533169D03*
Y1121948D03*
X1544389Y1114468D03*
X1536909Y1110728D03*
X1533169D03*
X1540649Y1114468D03*
X1536909Y1148129D03*
X1540649Y1151870D03*
Y1148129D03*
X1536909Y1144389D03*
Y1155610D03*
X1540649Y1159350D03*
Y1170570D03*
Y1174310D03*
Y1178050D03*
X1531299Y1176180D03*
X1559350Y1114468D03*
X1555610D03*
X1563090D03*
Y1140649D03*
Y1136909D03*
X1555610D03*
X1563090Y1129429D03*
Y1133169D03*
Y1144389D03*
Y1151869D03*
X1555610Y1144389D03*
X1548130Y1151870D03*
Y1148129D03*
Y1144389D03*
X1559350Y1155610D03*
X1555610Y1151870D03*
X1559350Y1148129D03*
X1563090Y1159350D03*
Y1170570D03*
X1548130Y1166830D03*
Y1159350D03*
X1555610Y1170570D03*
X1559350Y1166830D03*
X1555610Y1159350D03*
X1548130Y1174310D03*
Y1178051D03*
Y1181791D03*
X1563090Y1185531D03*
Y1178051D03*
X1555610Y1185531D03*
X1559350Y1174310D03*
Y1181791D03*
X1555610Y1178051D03*
X1563090Y1193011D03*
X1555610Y1215452D03*
X1563090D03*
X1559350D03*
X1574311Y1114468D03*
X1570571D03*
X1578051D03*
X1566830D03*
X1578051Y1136909D03*
X1574311D03*
X1570571D03*
X1574311Y1129429D03*
X1570571D03*
X1578051D03*
X1566830Y1140649D03*
X1578051Y1144389D03*
X1574311D03*
X1570571D03*
X1578051Y1151870D03*
X1574311D03*
X1570571D03*
X1574311Y1155610D03*
X1566830Y1148129D03*
Y1155610D03*
X1578051Y1170570D03*
X1574311Y1166830D03*
X1570571Y1170570D03*
X1566830Y1166830D03*
X1578051Y1159350D03*
X1570571D03*
X1574311Y1185531D03*
X1570571D03*
X1578051D03*
Y1178051D03*
X1574311D03*
X1570571D03*
X1574311Y1174310D03*
X1566830Y1181791D03*
Y1174310D03*
X1570571Y1193011D03*
X1574311D03*
X1578051D03*
X1570571Y1200491D03*
X1578051D03*
X1574311D03*
X1578051Y1215452D03*
X1566830D03*
X1570571Y1211712D03*
X1566830Y1219192D03*
X1574311Y1215452D03*
X1570571D03*
X1578051Y1211712D03*
X1574311D03*
X1593012Y1114468D03*
X1589271D03*
X1581791D03*
X1593011Y1136909D03*
X1589271D03*
X1585531D03*
X1581791D03*
X1589271Y1129429D03*
X1585531D03*
X1581791D03*
X1593011D03*
X1585531Y1144389D03*
X1581791D03*
X1593011D03*
X1589271D03*
X1593012Y1151870D03*
X1589271D03*
X1585531D03*
X1581791D03*
Y1155610D03*
X1589271D03*
X1593011Y1170570D03*
X1585531D03*
X1589271Y1166830D03*
X1581791D03*
X1585531Y1159350D03*
X1593011D03*
X1589271Y1185531D03*
X1585531D03*
X1581791D03*
X1593011D03*
X1581791Y1178051D03*
X1593011D03*
X1589271D03*
X1585531D03*
X1589271Y1174310D03*
X1581791D03*
X1585531Y1193011D03*
X1589271D03*
X1593011D03*
X1581791D03*
X1589271Y1200491D03*
X1585531D03*
X1581791D03*
X1593011D03*
X1593012Y1211712D03*
Y1215452D03*
X1581791D03*
X1589271D03*
X1585531D03*
Y1211712D03*
X1596752Y1114468D03*
X1607972D03*
X1611712Y1118208D03*
X1607972D03*
X1611712Y1114468D03*
X1600492Y1136909D03*
X1596752D03*
X1611712D03*
X1607972D03*
X1611712Y1129429D03*
X1607972D03*
X1600492D03*
X1596752D03*
X1600492Y1144389D03*
X1596752D03*
X1611712Y1151869D03*
X1607972D03*
X1611712Y1144389D03*
X1607972D03*
X1600492Y1151870D03*
X1596752D03*
Y1155610D03*
X1607972D03*
Y1166830D03*
X1611712Y1170570D03*
X1600492D03*
X1596752Y1166830D03*
X1611712Y1159350D03*
X1600492D03*
Y1185531D03*
X1596752D03*
X1600492Y1178051D03*
X1596752D03*
X1611712Y1185531D03*
X1607972D03*
X1611712Y1178051D03*
X1607972D03*
Y1174310D03*
X1596752D03*
X1607972Y1193011D03*
X1611712D03*
X1600492D03*
X1596752D03*
X1600492Y1200491D03*
X1596752D03*
X1611712D03*
X1607972D03*
X1600492Y1211712D03*
Y1215452D03*
X1596752Y1211712D03*
X1611712Y1215452D03*
X1607972D03*
Y1211712D03*
X1609842Y1217322D03*
X1615452Y1118208D03*
X1619193D03*
X1615452Y1114468D03*
X1619193D03*
X1622933D03*
X1626673D03*
Y1118208D03*
X1622933D03*
X1626673Y1136909D03*
X1622933D03*
X1615452D03*
X1619193D03*
X1626673Y1129429D03*
X1622933D03*
X1619193D03*
X1615452D03*
Y1151869D03*
X1619193D03*
X1626673D03*
X1622933D03*
Y1144389D03*
X1615452D03*
X1619193D03*
X1626673D03*
X1622933Y1155610D03*
X1615452D03*
Y1166830D03*
X1619193Y1170570D03*
X1626673Y1159350D03*
X1619193D03*
X1622933Y1166830D03*
X1626673Y1170570D03*
X1619193Y1185531D03*
X1626673D03*
X1622933D03*
Y1178051D03*
X1615452D03*
X1619193D03*
X1626673D03*
X1615452Y1185531D03*
X1622933Y1174310D03*
X1615452D03*
X1622933Y1193011D03*
X1626673D03*
X1615452D03*
X1619193D03*
X1622933Y1200491D03*
X1619193D03*
X1615452D03*
X1626673D03*
X1622933Y1215452D03*
X1619192Y1215451D03*
X1626673Y1215452D03*
X1615452D03*
X1613582Y1217322D03*
X1619192Y1211711D03*
X1622933D03*
X1637893Y1118208D03*
Y1114468D03*
X1634153D03*
X1630413D03*
X1641633D03*
X1634153Y1118208D03*
X1630413D03*
Y1136909D03*
X1637893D03*
X1634153D03*
X1630413Y1129429D03*
X1637893D03*
X1634153D03*
X1630413Y1151869D03*
X1637893D03*
X1634153D03*
Y1144389D03*
X1630413D03*
X1637893D03*
Y1155610D03*
X1630413D03*
X1637893Y1170570D03*
X1641633D03*
X1634153D03*
X1641633Y1166830D03*
X1637893D03*
Y1159350D03*
X1641633D03*
X1634153D03*
X1630413Y1166830D03*
X1641633Y1181791D03*
X1630413Y1185531D03*
X1634153D03*
X1630413Y1178051D03*
X1634153D03*
X1637893Y1185531D03*
Y1178051D03*
Y1174310D03*
X1630413D03*
X1634153Y1193011D03*
X1637893D03*
X1630413D03*
Y1200491D03*
X1637893D03*
X1634153D03*
X1630413Y1215452D03*
X1637893D03*
X1634153D03*
X1656594Y1118208D03*
X1652854D03*
Y1114468D03*
X1645374D03*
X1649114D03*
X1656594D03*
X1645374Y1129429D03*
Y1136909D03*
Y1140649D03*
X1656594Y1133169D03*
Y1140649D03*
Y1136909D03*
X1660334Y1140649D03*
X1649114Y1155610D03*
X1656594D03*
X1645374Y1144389D03*
X1660334Y1148129D03*
X1652854Y1144389D03*
X1656594Y1148129D03*
Y1144389D03*
X1649114Y1159350D03*
Y1170570D03*
Y1166830D03*
X1656594Y1170570D03*
Y1166830D03*
Y1159350D03*
Y1189271D03*
X1649114Y1174310D03*
X1656594D03*
X1652854Y1181791D03*
X1660334Y1189271D03*
X1645374Y1185531D03*
Y1189271D03*
X1660334Y1181791D03*
X1656594Y1178051D03*
X1645374D03*
Y1200491D03*
Y1193011D03*
X1656594Y1196751D03*
Y1204232D03*
X1652854Y1200491D03*
X1649114Y1204232D03*
Y1196751D03*
Y1200491D03*
X1656594D03*
X1645374Y1215452D03*
X1649114D03*
X1652854D03*
X1656594Y1211712D03*
X1645374D03*
X1656594Y1215452D03*
Y1207972D03*
X1649114D03*
X1652854D03*
Y1211712D03*
X1664075Y1140649D03*
X1667815Y1155610D03*
X1664075Y1148129D03*
Y1155610D03*
X1675295Y1144389D03*
Y1151869D03*
Y1166830D03*
Y1159350D03*
X1664075Y1170570D03*
X1667815D03*
X1675295Y1189271D03*
Y1174310D03*
Y1181791D03*
X1686515Y1140649D03*
X1682775D03*
X1679035Y1151869D03*
Y1144389D03*
X1682775Y1148129D03*
X1686515Y1155610D03*
Y1148129D03*
X1682775Y1155610D03*
X1679035Y1166830D03*
X1686515Y1170570D03*
X1682775D03*
X1679035Y1181791D03*
Y1189271D03*
Y1174310D03*
X1686515Y1185531D03*
X1682775Y1178051D03*
X1686515D03*
X1682775Y1185531D03*
X1686515Y1193011D03*
X1682775D03*
Y1222932D03*
X1693996Y1136909D03*
X1697736D03*
X1693996Y1151870D03*
X1697736D03*
X1693996Y1144389D03*
X1697736D03*
Y1159350D03*
X1693996D03*
X1697736Y1174310D03*
X1693996Y1189271D03*
X1697736D03*
Y1181791D03*
X1693996D03*
Y1174310D03*
X1796283Y441086D03*
Y433999D03*
Y437543D03*
X1793483Y441086D03*
Y433999D03*
Y437543D03*
X1796283Y444629D03*
X1793483D03*
G54D50*
X970071Y1365652D03*
Y1409152D03*
G54D32*
X109882Y1458622D03*
Y1463741D03*
Y1473977D03*
Y1479095D03*
Y1489331D03*
Y1494449D03*
Y1504685D03*
Y1509804D03*
Y1560985D03*
Y1566103D03*
Y1576339D03*
Y1581457D03*
Y1591693D03*
Y1596811D03*
Y1607048D03*
Y1612166D03*
Y1622402D03*
X127205Y1458622D03*
Y1463741D03*
X118543Y1452717D03*
Y1462953D03*
X127205Y1473977D03*
Y1479095D03*
X118543Y1468071D03*
Y1478308D03*
X127205Y1489331D03*
Y1494449D03*
X118543Y1483426D03*
Y1493662D03*
Y1498780D03*
X127205Y1504685D03*
Y1509804D03*
X118543Y1509016D03*
Y1514134D03*
X127205Y1560985D03*
Y1566103D03*
Y1576339D03*
X118543Y1565315D03*
Y1570434D03*
X127205Y1581457D03*
Y1591693D03*
X118543Y1580670D03*
Y1585788D03*
Y1596024D03*
X127205Y1596811D03*
Y1607048D03*
Y1612166D03*
X118543Y1601142D03*
Y1611378D03*
X127205Y1622402D03*
X118543Y1616496D03*
X144528Y1458622D03*
Y1463741D03*
X135866Y1452717D03*
Y1462953D03*
X144528Y1473977D03*
Y1479095D03*
X135866Y1468071D03*
Y1478308D03*
X144528Y1489331D03*
Y1494449D03*
X135866Y1483426D03*
Y1493662D03*
Y1498780D03*
X144528Y1504685D03*
Y1509804D03*
X135866Y1509016D03*
Y1514134D03*
X144528Y1560985D03*
Y1566103D03*
Y1576339D03*
X135866Y1565315D03*
Y1570434D03*
X144528Y1581457D03*
Y1591693D03*
X135866Y1580670D03*
Y1585788D03*
Y1596024D03*
X144528Y1596811D03*
Y1607048D03*
Y1612166D03*
X135866Y1601142D03*
Y1611378D03*
X144528Y1622402D03*
X135866Y1616496D03*
X161850Y1458622D03*
Y1463741D03*
X153189Y1452717D03*
Y1462953D03*
X161850Y1473977D03*
Y1479095D03*
X153189Y1468071D03*
Y1478308D03*
X161850Y1489331D03*
Y1494449D03*
X153189Y1483426D03*
Y1493662D03*
Y1498780D03*
X161850Y1504685D03*
Y1509804D03*
X153189Y1509016D03*
Y1514134D03*
X161850Y1560985D03*
Y1566103D03*
Y1576339D03*
X153189Y1565315D03*
Y1570434D03*
X161850Y1581457D03*
Y1591693D03*
X153189Y1580670D03*
Y1585788D03*
Y1596024D03*
X161850Y1596811D03*
Y1607048D03*
Y1612166D03*
X153189Y1601142D03*
Y1611378D03*
X161850Y1622402D03*
X153189Y1616496D03*
X179173Y1458622D03*
Y1463741D03*
X170512Y1452717D03*
Y1462953D03*
X179173Y1473977D03*
Y1479095D03*
X170512Y1468071D03*
Y1478308D03*
X179173Y1489331D03*
Y1494449D03*
X170512Y1483426D03*
Y1493662D03*
Y1498780D03*
X179173Y1504685D03*
Y1509804D03*
X170512Y1509016D03*
Y1514134D03*
X179173Y1560985D03*
Y1566103D03*
Y1576339D03*
X170512Y1565315D03*
Y1570434D03*
X179173Y1581457D03*
Y1591693D03*
X170512Y1580670D03*
Y1585788D03*
Y1596024D03*
X179173Y1596811D03*
Y1607048D03*
Y1612166D03*
X170512Y1601142D03*
Y1611378D03*
X179173Y1622402D03*
X170512Y1616496D03*
X187835Y1452717D03*
Y1462953D03*
Y1468071D03*
Y1478308D03*
Y1483426D03*
Y1493662D03*
Y1498780D03*
Y1509016D03*
Y1514134D03*
Y1565315D03*
Y1570434D03*
Y1580670D03*
Y1585788D03*
Y1596024D03*
Y1601142D03*
Y1611378D03*
Y1616496D03*
X291771Y1452717D03*
X283110Y1458622D03*
X291771Y1462953D03*
X283110Y1463741D03*
X291771Y1468071D03*
X283110Y1473977D03*
X291771Y1478308D03*
X283110Y1479095D03*
X291771Y1483426D03*
X283110Y1489331D03*
X291771Y1493662D03*
X283110Y1494449D03*
X291771Y1498780D03*
X283110Y1504685D03*
X291771Y1509016D03*
X283110Y1509804D03*
X291771Y1514134D03*
X283110Y1560985D03*
X291771Y1565315D03*
X283110Y1566103D03*
X291771Y1570434D03*
X283110Y1576339D03*
X291771Y1580670D03*
X283110Y1581457D03*
X291771Y1585788D03*
X283110Y1591693D03*
X291771Y1596024D03*
X283110Y1596811D03*
X291771Y1601142D03*
X283110Y1607048D03*
X291771Y1611378D03*
X283110Y1612166D03*
X291771Y1616496D03*
X283110Y1622402D03*
X309094Y1452717D03*
X300433Y1458622D03*
X309094Y1462953D03*
X300433Y1463741D03*
X309094Y1468071D03*
X300433Y1473977D03*
X309094Y1478308D03*
X300433Y1479095D03*
X309094Y1483426D03*
X300433Y1489331D03*
X309094Y1493662D03*
X300433Y1494449D03*
X309094Y1498780D03*
X300433Y1504685D03*
X309094Y1509016D03*
X300433Y1509804D03*
X309094Y1514134D03*
X300433Y1560985D03*
X309094Y1565315D03*
X300433Y1566103D03*
X309094Y1570434D03*
X300433Y1576339D03*
X309094Y1580670D03*
X300433Y1581457D03*
X309094Y1585788D03*
X300433Y1591693D03*
X309094Y1596024D03*
X300433Y1596811D03*
X309094Y1601142D03*
X300433Y1607048D03*
X309094Y1611378D03*
X300433Y1612166D03*
X309094Y1616496D03*
X300433Y1622402D03*
X326417Y1452717D03*
X317756Y1458622D03*
X326417Y1462953D03*
X317756Y1463741D03*
X326417Y1468071D03*
X317756Y1473977D03*
X326417Y1478308D03*
X317756Y1479095D03*
X326417Y1483426D03*
X317756Y1489331D03*
X326417Y1493662D03*
X317756Y1494449D03*
X326417Y1498780D03*
X317756Y1504685D03*
X326417Y1509016D03*
X317756Y1509804D03*
X326417Y1514134D03*
X317756Y1560985D03*
X326417Y1565315D03*
X317756Y1566103D03*
X326417Y1570434D03*
X317756Y1576339D03*
X326417Y1580670D03*
X317756Y1581457D03*
X326417Y1585788D03*
X317756Y1591693D03*
X326417Y1596024D03*
X317756Y1596811D03*
X326417Y1601142D03*
X317756Y1607048D03*
X326417Y1611378D03*
X317756Y1612166D03*
X326417Y1616496D03*
X317756Y1622402D03*
X343740Y1452717D03*
X335078Y1458622D03*
X343740Y1462953D03*
X335078Y1463741D03*
X343740Y1468071D03*
X335078Y1473977D03*
X343740Y1478308D03*
X335078Y1479095D03*
X343740Y1483426D03*
X335078Y1489331D03*
X343740Y1493662D03*
X335078Y1494449D03*
X343740Y1498780D03*
X335078Y1504685D03*
X343740Y1509016D03*
X335078Y1509804D03*
X343740Y1514134D03*
X335078Y1560985D03*
X343740Y1565315D03*
X335078Y1566103D03*
X343740Y1570434D03*
X335078Y1576339D03*
X343740Y1580670D03*
X335078Y1581457D03*
X343740Y1585788D03*
X335078Y1591693D03*
X343740Y1596024D03*
X335078Y1596811D03*
X343740Y1601142D03*
X335078Y1607048D03*
X343740Y1611378D03*
X335078Y1612166D03*
X343740Y1616496D03*
X335078Y1622402D03*
X361063Y1452717D03*
X352401Y1458622D03*
Y1463741D03*
X361063Y1462953D03*
Y1468071D03*
X352401Y1473977D03*
Y1479095D03*
X361063Y1478308D03*
Y1483426D03*
X352401Y1489331D03*
Y1494449D03*
X361063Y1493662D03*
Y1498780D03*
X352401Y1504685D03*
Y1509804D03*
X361063Y1509016D03*
Y1514134D03*
X352401Y1560985D03*
Y1566103D03*
X361063Y1565315D03*
Y1570434D03*
X352401Y1576339D03*
Y1581457D03*
X361063Y1580670D03*
Y1585788D03*
X352401Y1591693D03*
X361063Y1596024D03*
X352401Y1596811D03*
X361063Y1601142D03*
X352401Y1607048D03*
Y1612166D03*
X361063Y1611378D03*
Y1616496D03*
X352401Y1622402D03*
X456339Y1458622D03*
Y1463741D03*
Y1473977D03*
Y1479095D03*
Y1489331D03*
Y1494449D03*
Y1504685D03*
Y1509804D03*
Y1560985D03*
Y1566103D03*
Y1576339D03*
Y1581457D03*
Y1591693D03*
Y1596811D03*
Y1607048D03*
Y1612166D03*
Y1622402D03*
X473662Y1458622D03*
Y1463741D03*
X465000Y1452717D03*
Y1462953D03*
X473662Y1473977D03*
Y1479095D03*
X465000Y1468071D03*
Y1478308D03*
X473662Y1489331D03*
Y1494449D03*
X465000Y1483426D03*
Y1493662D03*
Y1498780D03*
X473662Y1504685D03*
Y1509804D03*
X465000Y1509016D03*
Y1514134D03*
X473662Y1560985D03*
Y1566103D03*
Y1576339D03*
X465000Y1565315D03*
Y1570434D03*
X473662Y1581457D03*
Y1591693D03*
X465000Y1580670D03*
Y1585788D03*
Y1596024D03*
X473662Y1596811D03*
Y1607048D03*
Y1612166D03*
X465000Y1601142D03*
Y1611378D03*
X473662Y1622402D03*
X465000Y1616496D03*
X490985Y1458622D03*
Y1463741D03*
X482323Y1452717D03*
Y1462953D03*
X490985Y1473977D03*
Y1479095D03*
X482323Y1468071D03*
Y1478308D03*
X490985Y1489331D03*
Y1494449D03*
X482323Y1483426D03*
Y1493662D03*
Y1498780D03*
X490985Y1504685D03*
Y1509804D03*
X482323Y1509016D03*
Y1514134D03*
X490985Y1560985D03*
Y1566103D03*
Y1576339D03*
X482323Y1565315D03*
Y1570434D03*
X490985Y1581457D03*
Y1591693D03*
X482323Y1580670D03*
Y1585788D03*
Y1596024D03*
X490985Y1596811D03*
Y1607048D03*
Y1612166D03*
X482323Y1601142D03*
Y1611378D03*
X490985Y1622402D03*
X482323Y1616496D03*
X499646Y1452717D03*
Y1462953D03*
Y1468071D03*
Y1478308D03*
Y1483426D03*
Y1493662D03*
Y1498780D03*
Y1509016D03*
Y1514134D03*
Y1565315D03*
Y1570434D03*
Y1580670D03*
Y1585788D03*
Y1596024D03*
Y1601142D03*
Y1611378D03*
Y1616496D03*
X516969Y1452717D03*
X508307Y1458622D03*
X516969Y1462953D03*
X508307Y1463741D03*
X516969Y1468071D03*
X508307Y1473977D03*
X516969Y1478308D03*
X508307Y1479095D03*
X516969Y1483426D03*
X508307Y1489331D03*
X516969Y1493662D03*
X508307Y1494449D03*
X516969Y1498780D03*
X508307Y1504685D03*
X516969Y1509016D03*
X508307Y1509804D03*
X516969Y1514134D03*
X508307Y1560985D03*
X516969Y1565315D03*
X508307Y1566103D03*
X516969Y1570434D03*
X508307Y1576339D03*
X516969Y1580670D03*
X508307Y1581457D03*
X516969Y1585788D03*
X508307Y1591693D03*
X516969Y1596024D03*
X508307Y1596811D03*
X516969Y1601142D03*
X508307Y1607048D03*
X516969Y1611378D03*
X508307Y1612166D03*
X516969Y1616496D03*
X508307Y1622402D03*
X534292Y1452717D03*
X525630Y1458622D03*
Y1463741D03*
X534292Y1462953D03*
Y1468071D03*
X525630Y1473977D03*
Y1479095D03*
X534292Y1478308D03*
Y1483426D03*
X525630Y1489331D03*
Y1494449D03*
X534292Y1493662D03*
Y1498780D03*
X525630Y1504685D03*
Y1509804D03*
X534292Y1509016D03*
Y1514134D03*
X525630Y1560985D03*
Y1566103D03*
X534292Y1565315D03*
Y1570434D03*
X525630Y1576339D03*
Y1581457D03*
X534292Y1580670D03*
Y1585788D03*
X525630Y1591693D03*
X534292Y1596024D03*
X525630Y1596811D03*
X534292Y1601142D03*
X525630Y1607048D03*
Y1612166D03*
X534292Y1611378D03*
Y1616496D03*
X525630Y1622402D03*
X629567Y1458622D03*
Y1463741D03*
Y1473977D03*
Y1479095D03*
Y1489331D03*
Y1494449D03*
Y1504685D03*
Y1509804D03*
Y1560985D03*
Y1566103D03*
Y1576339D03*
Y1581457D03*
Y1591693D03*
Y1596811D03*
Y1607048D03*
Y1612166D03*
Y1622402D03*
X646890Y1458622D03*
Y1463741D03*
X638228Y1452717D03*
Y1462953D03*
X646890Y1473977D03*
Y1479095D03*
X638228Y1468071D03*
Y1478308D03*
X646890Y1489331D03*
Y1494449D03*
X638228Y1483426D03*
Y1493662D03*
Y1498780D03*
X646890Y1504685D03*
Y1509804D03*
X638228Y1509016D03*
Y1514134D03*
X646890Y1560985D03*
Y1566103D03*
Y1576339D03*
X638228Y1565315D03*
Y1570434D03*
X646890Y1581457D03*
Y1591693D03*
X638228Y1580670D03*
Y1585788D03*
Y1596024D03*
X646890Y1596811D03*
Y1607048D03*
Y1612166D03*
X638228Y1601142D03*
Y1611378D03*
X646890Y1622402D03*
X638228Y1616496D03*
X664213Y1458622D03*
Y1463741D03*
X655551Y1452717D03*
Y1462953D03*
X664213Y1473977D03*
Y1479095D03*
X655551Y1468071D03*
Y1478308D03*
X664213Y1489331D03*
Y1494449D03*
X655551Y1483426D03*
Y1493662D03*
Y1498780D03*
X664213Y1504685D03*
Y1509804D03*
X655551Y1509016D03*
Y1514134D03*
X664213Y1560985D03*
Y1566103D03*
Y1576339D03*
X655551Y1565315D03*
Y1570434D03*
X664213Y1581457D03*
Y1591693D03*
X655551Y1580670D03*
Y1585788D03*
Y1596024D03*
X664213Y1596811D03*
Y1607048D03*
Y1612166D03*
X655551Y1601142D03*
Y1611378D03*
X664213Y1622402D03*
X655551Y1616496D03*
X681535Y1458622D03*
Y1463741D03*
X672874Y1452717D03*
Y1462953D03*
X681535Y1473977D03*
Y1479095D03*
X672874Y1468071D03*
Y1478308D03*
X681535Y1489331D03*
Y1494449D03*
X672874Y1483426D03*
Y1493662D03*
Y1498780D03*
X681535Y1504685D03*
Y1509804D03*
X672874Y1509016D03*
Y1514134D03*
X681535Y1560985D03*
Y1566103D03*
Y1576339D03*
X672874Y1565315D03*
Y1570434D03*
X681535Y1581457D03*
Y1591693D03*
X672874Y1580670D03*
Y1585788D03*
Y1596024D03*
X681535Y1596811D03*
Y1607048D03*
Y1612166D03*
X672874Y1601142D03*
Y1611378D03*
X681535Y1622402D03*
X672874Y1616496D03*
X698858Y1458622D03*
Y1463741D03*
X690197Y1452717D03*
Y1462953D03*
X698858Y1473977D03*
Y1479095D03*
X690197Y1468071D03*
Y1478308D03*
X698858Y1489331D03*
Y1494449D03*
X690197Y1483426D03*
Y1493662D03*
Y1498780D03*
X698858Y1504685D03*
Y1509804D03*
X690197Y1509016D03*
Y1514134D03*
X698858Y1560985D03*
Y1566103D03*
Y1576339D03*
X690197Y1565315D03*
Y1570434D03*
X698858Y1581457D03*
Y1591693D03*
X690197Y1580670D03*
Y1585788D03*
Y1596024D03*
X698858Y1596811D03*
Y1607048D03*
Y1612166D03*
X690197Y1601142D03*
Y1611378D03*
X698858Y1622402D03*
X690197Y1616496D03*
X707520Y1452717D03*
Y1462953D03*
Y1468071D03*
Y1478308D03*
Y1483426D03*
Y1493662D03*
Y1498780D03*
Y1509016D03*
Y1514134D03*
Y1565315D03*
Y1570434D03*
Y1580670D03*
Y1585788D03*
Y1596024D03*
Y1601142D03*
Y1611378D03*
Y1616496D03*
X1140511Y1452717D03*
X1131850Y1458622D03*
X1140511Y1462953D03*
X1131850Y1463741D03*
X1140511Y1468071D03*
X1131850Y1473977D03*
X1140511Y1478308D03*
X1131850Y1479095D03*
X1140511Y1483426D03*
X1131850Y1489331D03*
X1140511Y1493662D03*
X1131850Y1494449D03*
X1140511Y1498780D03*
X1131850Y1504685D03*
X1140511Y1509016D03*
X1131850Y1509804D03*
X1140511Y1514134D03*
X1131850Y1560985D03*
X1140511Y1565315D03*
X1131850Y1566103D03*
X1140511Y1570434D03*
X1131850Y1576339D03*
X1140511Y1580670D03*
X1131850Y1581457D03*
X1140511Y1585788D03*
X1131850Y1591693D03*
X1140511Y1596024D03*
X1131850Y1596811D03*
X1140511Y1601142D03*
X1131850Y1607048D03*
X1140511Y1611378D03*
X1131850Y1612166D03*
X1140511Y1616496D03*
X1131850Y1622402D03*
X1149173Y1458622D03*
Y1463741D03*
Y1473977D03*
Y1479095D03*
Y1489331D03*
Y1494449D03*
Y1504685D03*
Y1509804D03*
Y1560985D03*
Y1566103D03*
Y1576339D03*
Y1581457D03*
Y1591693D03*
Y1596811D03*
Y1607048D03*
Y1612166D03*
Y1622402D03*
X1166496Y1458622D03*
Y1463741D03*
X1157834Y1452717D03*
Y1462953D03*
X1166496Y1473977D03*
Y1479095D03*
X1157834Y1468071D03*
Y1478308D03*
X1166496Y1489331D03*
Y1494449D03*
X1157834Y1483426D03*
Y1493662D03*
Y1498780D03*
X1166496Y1504685D03*
Y1509804D03*
X1157834Y1509016D03*
Y1514134D03*
X1166496Y1560985D03*
Y1566103D03*
Y1576339D03*
X1157834Y1565315D03*
Y1570434D03*
X1166496Y1581457D03*
Y1591693D03*
X1157834Y1580670D03*
Y1585788D03*
Y1596024D03*
X1166496Y1596811D03*
Y1607048D03*
Y1612166D03*
X1157834Y1601142D03*
Y1611378D03*
X1166496Y1622402D03*
X1157834Y1616496D03*
X1183818Y1458622D03*
Y1463741D03*
X1175157Y1452717D03*
Y1462953D03*
X1183818Y1473977D03*
Y1479095D03*
X1175157Y1468071D03*
Y1478308D03*
X1183818Y1489331D03*
Y1494449D03*
X1175157Y1483426D03*
Y1493662D03*
Y1498780D03*
X1183818Y1504685D03*
Y1509804D03*
X1175157Y1509016D03*
Y1514134D03*
X1183818Y1560985D03*
Y1566103D03*
Y1576339D03*
X1175157Y1565315D03*
Y1570434D03*
X1183818Y1581457D03*
Y1591693D03*
X1175157Y1580670D03*
Y1585788D03*
Y1596024D03*
X1183818Y1596811D03*
Y1607048D03*
Y1612166D03*
X1175157Y1601142D03*
Y1611378D03*
X1183818Y1622402D03*
X1175157Y1616496D03*
X1201141Y1458622D03*
Y1463741D03*
X1192480Y1452717D03*
Y1462953D03*
X1201141Y1473977D03*
Y1479095D03*
X1192480Y1468071D03*
Y1478308D03*
X1201141Y1489331D03*
Y1494449D03*
X1192480Y1483426D03*
Y1493662D03*
Y1498780D03*
X1201141Y1504685D03*
Y1509804D03*
X1192480Y1509016D03*
Y1514134D03*
X1201141Y1560985D03*
Y1566103D03*
Y1576339D03*
X1192480Y1565315D03*
Y1570434D03*
X1201141Y1581457D03*
Y1591693D03*
X1192480Y1580670D03*
Y1585788D03*
Y1596024D03*
X1201141Y1596811D03*
Y1607048D03*
Y1612166D03*
X1192480Y1601142D03*
Y1611378D03*
X1201141Y1622402D03*
X1192480Y1616496D03*
X1209803Y1452717D03*
Y1462953D03*
Y1468071D03*
Y1478308D03*
Y1483426D03*
Y1493662D03*
Y1498780D03*
Y1509016D03*
Y1514134D03*
Y1565315D03*
Y1570434D03*
Y1580670D03*
Y1585788D03*
Y1596024D03*
Y1601142D03*
Y1611378D03*
Y1616496D03*
X1313740Y1452717D03*
X1305079Y1458622D03*
X1313740Y1462953D03*
X1305079Y1463741D03*
X1313740Y1468071D03*
X1305079Y1473977D03*
X1313740Y1478308D03*
X1305079Y1479095D03*
X1313740Y1483426D03*
X1305079Y1489331D03*
X1313740Y1493662D03*
X1305079Y1494449D03*
X1313740Y1498780D03*
X1305079Y1504685D03*
X1313740Y1509016D03*
X1305079Y1509804D03*
X1313740Y1514134D03*
X1305079Y1560985D03*
X1313740Y1565315D03*
X1305079Y1566103D03*
X1313740Y1570434D03*
X1305079Y1576339D03*
X1313740Y1580670D03*
X1305079Y1581457D03*
X1313740Y1585788D03*
X1305079Y1591693D03*
X1313740Y1596024D03*
X1305079Y1596811D03*
X1313740Y1601142D03*
X1305079Y1607048D03*
X1313740Y1611378D03*
X1305079Y1612166D03*
X1313740Y1616496D03*
X1305079Y1622402D03*
X1331063Y1452717D03*
X1322402Y1458622D03*
X1331063Y1462953D03*
X1322402Y1463741D03*
X1331063Y1468071D03*
X1322402Y1473977D03*
X1331063Y1478308D03*
X1322402Y1479095D03*
X1331063Y1483426D03*
X1322402Y1489331D03*
X1331063Y1493662D03*
X1322402Y1494449D03*
X1331063Y1498780D03*
X1322402Y1504685D03*
X1331063Y1509016D03*
X1322402Y1509804D03*
X1331063Y1514134D03*
X1322402Y1560985D03*
X1331063Y1565315D03*
X1322402Y1566103D03*
X1331063Y1570434D03*
X1322402Y1576339D03*
X1331063Y1580670D03*
X1322402Y1581457D03*
X1331063Y1585788D03*
X1322402Y1591693D03*
X1331063Y1596024D03*
X1322402Y1596811D03*
X1331063Y1601142D03*
X1322402Y1607048D03*
X1331063Y1611378D03*
X1322402Y1612166D03*
X1331063Y1616496D03*
X1322402Y1622402D03*
X1348386Y1452717D03*
X1339725Y1458622D03*
X1348386Y1462953D03*
X1339725Y1463741D03*
X1348386Y1468071D03*
X1339725Y1473977D03*
X1348386Y1478308D03*
X1339725Y1479095D03*
X1348386Y1483426D03*
X1339725Y1489331D03*
X1348386Y1493662D03*
X1339725Y1494449D03*
X1348386Y1498780D03*
X1339725Y1504685D03*
X1348386Y1509016D03*
X1339725Y1509804D03*
X1348386Y1514134D03*
X1339725Y1560985D03*
X1348386Y1565315D03*
X1339725Y1566103D03*
X1348386Y1570434D03*
X1339725Y1576339D03*
X1348386Y1580670D03*
X1339725Y1581457D03*
X1348386Y1585788D03*
X1339725Y1591693D03*
X1348386Y1596024D03*
X1339725Y1596811D03*
X1348386Y1601142D03*
X1339725Y1607048D03*
X1348386Y1611378D03*
X1339725Y1612166D03*
X1348386Y1616496D03*
X1339725Y1622402D03*
X1365709Y1452717D03*
X1357047Y1458622D03*
X1365709Y1462953D03*
X1357047Y1463741D03*
X1365709Y1468071D03*
X1357047Y1473977D03*
X1365709Y1478308D03*
X1357047Y1479095D03*
X1365709Y1483426D03*
X1357047Y1489331D03*
X1365709Y1493662D03*
X1357047Y1494449D03*
X1365709Y1498780D03*
X1357047Y1504685D03*
X1365709Y1509016D03*
X1357047Y1509804D03*
X1365709Y1514134D03*
X1357047Y1560985D03*
X1365709Y1565315D03*
X1357047Y1566103D03*
X1365709Y1570434D03*
X1357047Y1576339D03*
X1365709Y1580670D03*
X1357047Y1581457D03*
X1365709Y1585788D03*
X1357047Y1591693D03*
X1365709Y1596024D03*
X1357047Y1596811D03*
X1365709Y1601142D03*
X1357047Y1607048D03*
X1365709Y1611378D03*
X1357047Y1612166D03*
X1365709Y1616496D03*
X1357047Y1622402D03*
X1383032Y1452717D03*
X1374370Y1458622D03*
Y1463741D03*
X1383032Y1462953D03*
Y1468071D03*
X1374370Y1473977D03*
Y1479095D03*
X1383032Y1478308D03*
Y1483426D03*
X1374370Y1489331D03*
Y1494449D03*
X1383032Y1493662D03*
Y1498780D03*
X1374370Y1504685D03*
Y1509804D03*
X1383032Y1509016D03*
Y1514134D03*
X1374370Y1560985D03*
Y1566103D03*
X1383032Y1565315D03*
Y1570434D03*
X1374370Y1576339D03*
Y1581457D03*
X1383032Y1580670D03*
Y1585788D03*
X1374370Y1591693D03*
X1383032Y1596024D03*
X1374370Y1596811D03*
X1383032Y1601142D03*
X1374370Y1607048D03*
Y1612166D03*
X1383032Y1611378D03*
Y1616496D03*
X1374370Y1622402D03*
X1478307Y1458622D03*
Y1463741D03*
Y1473977D03*
Y1479095D03*
Y1489331D03*
Y1494449D03*
Y1504685D03*
Y1509804D03*
Y1560985D03*
Y1566103D03*
Y1576339D03*
Y1581457D03*
Y1591693D03*
Y1596811D03*
Y1607048D03*
Y1612166D03*
Y1622402D03*
X1495630Y1458622D03*
Y1463741D03*
X1486968Y1452717D03*
Y1462953D03*
X1495630Y1473977D03*
Y1479095D03*
X1486968Y1468071D03*
Y1478308D03*
X1495630Y1489331D03*
Y1494449D03*
X1486968Y1483426D03*
Y1493662D03*
Y1498780D03*
X1495630Y1504685D03*
Y1509804D03*
X1486968Y1509016D03*
Y1514134D03*
X1495630Y1560985D03*
Y1566103D03*
Y1576339D03*
X1486968Y1565315D03*
Y1570434D03*
X1495630Y1581457D03*
Y1591693D03*
X1486968Y1580670D03*
Y1585788D03*
Y1596024D03*
X1495630Y1596811D03*
Y1607048D03*
Y1612166D03*
X1486968Y1601142D03*
Y1611378D03*
X1495630Y1622402D03*
X1486968Y1616496D03*
X1512953Y1458622D03*
Y1463741D03*
X1504291Y1452717D03*
Y1462953D03*
X1512953Y1473977D03*
Y1479095D03*
X1504291Y1468071D03*
Y1478308D03*
X1512953Y1489331D03*
Y1494449D03*
X1504291Y1483426D03*
Y1493662D03*
Y1498780D03*
X1512953Y1504685D03*
Y1509804D03*
X1504291Y1509016D03*
Y1514134D03*
X1512953Y1560985D03*
Y1566103D03*
Y1576339D03*
X1504291Y1565315D03*
Y1570434D03*
X1512953Y1581457D03*
Y1591693D03*
X1504291Y1580670D03*
Y1585788D03*
Y1596024D03*
X1512953Y1596811D03*
Y1607048D03*
Y1612166D03*
X1504291Y1601142D03*
Y1611378D03*
X1512953Y1622402D03*
X1504291Y1616496D03*
X1530275Y1458622D03*
Y1463741D03*
X1521614Y1452717D03*
Y1462953D03*
X1530275Y1473977D03*
Y1479095D03*
X1521614Y1468071D03*
Y1478308D03*
X1530275Y1489331D03*
Y1494449D03*
X1521614Y1483426D03*
Y1493662D03*
Y1498780D03*
X1530275Y1504685D03*
Y1509804D03*
X1521614Y1509016D03*
Y1514134D03*
X1530275Y1560985D03*
Y1566103D03*
Y1576339D03*
X1521614Y1565315D03*
Y1570434D03*
X1530275Y1581457D03*
Y1591693D03*
X1521614Y1580670D03*
Y1585788D03*
Y1596024D03*
X1530275Y1596811D03*
Y1607048D03*
Y1612166D03*
X1521614Y1601142D03*
Y1611378D03*
X1530275Y1622402D03*
X1521614Y1616496D03*
X1538937Y1452717D03*
Y1462953D03*
Y1468071D03*
Y1478308D03*
Y1483426D03*
Y1493662D03*
Y1498780D03*
Y1509016D03*
Y1514134D03*
Y1565315D03*
Y1570434D03*
Y1580670D03*
Y1585788D03*
Y1596024D03*
Y1601142D03*
Y1611378D03*
Y1616496D03*
X1556260Y1452717D03*
X1547598Y1458622D03*
Y1463741D03*
X1556260Y1462953D03*
Y1468071D03*
X1547598Y1473977D03*
Y1479095D03*
X1556260Y1478308D03*
Y1483426D03*
X1547598Y1489331D03*
Y1494449D03*
X1556260Y1493662D03*
Y1498780D03*
X1547598Y1504685D03*
Y1509804D03*
X1556260Y1509016D03*
Y1514134D03*
X1547598Y1560985D03*
Y1566103D03*
X1556260Y1565315D03*
Y1570434D03*
X1547598Y1576339D03*
Y1581457D03*
X1556260Y1580670D03*
Y1585788D03*
X1547598Y1591693D03*
X1556260Y1596024D03*
X1547598Y1596811D03*
X1556260Y1601142D03*
X1547598Y1607048D03*
Y1612166D03*
X1556260Y1611378D03*
Y1616496D03*
X1547598Y1622402D03*
X1660196Y1452717D03*
X1651535Y1458622D03*
X1660196Y1462953D03*
X1651535Y1463741D03*
X1660196Y1468071D03*
X1651535Y1473977D03*
X1660196Y1478308D03*
X1651535Y1479095D03*
X1660196Y1483426D03*
X1651535Y1489331D03*
X1660196Y1493662D03*
X1651535Y1494449D03*
X1660196Y1498780D03*
X1651535Y1504685D03*
X1660196Y1509016D03*
X1651535Y1509804D03*
X1660196Y1514134D03*
X1651535Y1560985D03*
X1660196Y1565315D03*
X1651535Y1566103D03*
X1660196Y1570434D03*
X1651535Y1576339D03*
X1660196Y1580670D03*
X1651535Y1581457D03*
X1660196Y1585788D03*
X1651535Y1591693D03*
X1660196Y1596024D03*
X1651535Y1596811D03*
X1660196Y1601142D03*
X1651535Y1607048D03*
X1660196Y1611378D03*
X1651535Y1612166D03*
X1660196Y1616496D03*
X1651535Y1622402D03*
X1668858Y1458622D03*
Y1463741D03*
Y1473977D03*
Y1479095D03*
Y1489331D03*
Y1494449D03*
Y1504685D03*
Y1509804D03*
Y1560985D03*
Y1566103D03*
Y1576339D03*
Y1581457D03*
Y1591693D03*
Y1596811D03*
Y1607048D03*
Y1612166D03*
Y1622402D03*
X1686181Y1458622D03*
Y1463741D03*
X1677519Y1452717D03*
Y1462953D03*
X1686181Y1473977D03*
Y1479095D03*
X1677519Y1468071D03*
Y1478308D03*
X1686181Y1489331D03*
Y1494449D03*
X1677519Y1483426D03*
Y1493662D03*
Y1498780D03*
X1686181Y1504685D03*
Y1509804D03*
X1677519Y1509016D03*
Y1514134D03*
X1686181Y1560985D03*
Y1566103D03*
Y1576339D03*
X1677519Y1565315D03*
Y1570434D03*
X1686181Y1581457D03*
Y1591693D03*
X1677519Y1580670D03*
Y1585788D03*
Y1596024D03*
X1686181Y1596811D03*
Y1607048D03*
Y1612166D03*
X1677519Y1601142D03*
Y1611378D03*
X1686181Y1622402D03*
X1677519Y1616496D03*
X1703503Y1458622D03*
Y1463741D03*
X1694842Y1452717D03*
Y1462953D03*
X1703503Y1473977D03*
Y1479095D03*
X1694842Y1468071D03*
Y1478308D03*
X1703503Y1489331D03*
Y1494449D03*
X1694842Y1483426D03*
Y1493662D03*
Y1498780D03*
X1703503Y1504685D03*
Y1509804D03*
X1694842Y1509016D03*
Y1514134D03*
X1703503Y1560985D03*
Y1566103D03*
Y1576339D03*
X1694842Y1565315D03*
Y1570434D03*
X1703503Y1581457D03*
Y1591693D03*
X1694842Y1580670D03*
Y1585788D03*
Y1596024D03*
X1703503Y1596811D03*
Y1607048D03*
Y1612166D03*
X1694842Y1601142D03*
Y1611378D03*
X1703503Y1622402D03*
X1694842Y1616496D03*
X1720826Y1458622D03*
Y1463741D03*
X1712165Y1452717D03*
Y1462953D03*
X1720826Y1473977D03*
Y1479095D03*
X1712165Y1468071D03*
Y1478308D03*
X1720826Y1489331D03*
Y1494449D03*
X1712165Y1483426D03*
Y1493662D03*
Y1498780D03*
X1720826Y1504685D03*
Y1509804D03*
X1712165Y1509016D03*
Y1514134D03*
X1720826Y1560985D03*
Y1566103D03*
Y1576339D03*
X1712165Y1565315D03*
Y1570434D03*
X1720826Y1581457D03*
Y1591693D03*
X1712165Y1580670D03*
Y1585788D03*
Y1596024D03*
X1720826Y1596811D03*
Y1607048D03*
Y1612166D03*
X1712165Y1601142D03*
Y1611378D03*
X1720826Y1622402D03*
X1712165Y1616496D03*
X1729488Y1452717D03*
Y1462953D03*
Y1468071D03*
Y1478308D03*
Y1483426D03*
Y1493662D03*
Y1498780D03*
Y1509016D03*
Y1514134D03*
Y1565315D03*
Y1570434D03*
Y1580670D03*
Y1585788D03*
Y1596024D03*
Y1601142D03*
Y1611378D03*
Y1616496D03*
G54D52*
X1030635Y754546D03*
Y774546D03*
Y784546D03*
Y794546D03*
Y804546D03*
Y814546D03*
Y824546D03*
G54D27*
X76112Y1348187D03*
X79512D03*
X76112Y1360099D03*
X79512D03*
Y1372385D03*
X76112D03*
Y1384297D03*
X79512D03*
X88352Y1348187D03*
X91752D03*
X100592D03*
X91752Y1360099D03*
X88352D03*
X100592D03*
Y1384297D03*
Y1372385D03*
X91752D03*
X88352D03*
Y1384297D03*
X91752D03*
Y1396583D03*
X88352D03*
X100592D03*
X91752Y1408495D03*
X88352D03*
X100592D03*
X116232Y1348187D03*
X112832D03*
X103992D03*
X112832Y1360099D03*
X116232D03*
X103992D03*
Y1372385D03*
Y1384297D03*
X112832D03*
X116232Y1372385D03*
Y1384297D03*
X112832Y1372385D03*
X116232Y1396583D03*
X112832D03*
X103992D03*
X112832Y1408495D03*
X116232D03*
X103992D03*
X125072Y1348187D03*
X128472D03*
Y1360099D03*
X125072D03*
Y1384297D03*
X128472D03*
X125072Y1372385D03*
X128472D03*
X125072Y1396583D03*
X128472D03*
X125072Y1408495D03*
X128472D03*
X140712Y1348187D03*
X137312D03*
X149552D03*
X137312Y1360099D03*
X140712D03*
X149552D03*
Y1384297D03*
Y1372385D03*
X140712D03*
Y1384297D03*
X137312D03*
Y1372385D03*
X140712Y1396583D03*
X137312D03*
X149552D03*
X140712Y1408495D03*
X137312D03*
X149552D03*
X165192Y1348187D03*
X161792D03*
X152952D03*
X165192Y1360099D03*
X161792D03*
X152952D03*
Y1384297D03*
Y1372385D03*
X161792Y1384297D03*
X165192Y1372385D03*
Y1384297D03*
X161792Y1372385D03*
X165192Y1396583D03*
X161792D03*
X152952D03*
X165192Y1408495D03*
X161792D03*
X152952D03*
X177432Y1348187D03*
X174032D03*
Y1360099D03*
X177432D03*
Y1384297D03*
X174032D03*
Y1372385D03*
X177432D03*
Y1396583D03*
X174032D03*
X177432Y1408495D03*
X174032D03*
X189672Y1348187D03*
X186272D03*
X198512D03*
X189672Y1360099D03*
X186272D03*
X198512D03*
Y1384297D03*
Y1372385D03*
X186272Y1384297D03*
X189672D03*
Y1372385D03*
X186272D03*
Y1396583D03*
X189672D03*
X198512D03*
X189672Y1408495D03*
X186272D03*
X198512D03*
X201912Y1348187D03*
Y1360099D03*
Y1384297D03*
Y1372385D03*
Y1396583D03*
Y1408495D03*
X241623Y1348187D03*
X245023D03*
Y1360099D03*
X241623D03*
X245023Y1372385D03*
X241623D03*
Y1384297D03*
X245023D03*
X253863Y1348187D03*
X257263D03*
X253863Y1360099D03*
X257263D03*
X253863Y1372385D03*
X257263D03*
X253863Y1384297D03*
X257263D03*
X253863Y1396583D03*
X257263D03*
Y1408495D03*
X253863D03*
X281594Y1211712D03*
X270374Y1215452D03*
X269503Y1348187D03*
X278343D03*
X266103D03*
X278343Y1360099D03*
X266103D03*
X269503D03*
Y1372385D03*
X266103D03*
X278343D03*
X266103Y1384297D03*
X269503D03*
X278343D03*
Y1396583D03*
X269503D03*
X266103D03*
X278343Y1408495D03*
X269503D03*
X266103D03*
X281743Y1348187D03*
X293983D03*
X290583D03*
X281743Y1360099D03*
X293983D03*
X290583D03*
X293983Y1372385D03*
X281743D03*
X290583Y1384297D03*
X293983D03*
X290583Y1372385D03*
X281743Y1384297D03*
X293983Y1396583D03*
X290583D03*
X281743D03*
Y1408495D03*
X293983D03*
X290583D03*
X302823Y1348187D03*
X306223D03*
Y1360099D03*
X302823D03*
X306223Y1372385D03*
X302823D03*
X306223Y1384297D03*
X302823D03*
Y1396583D03*
X306223D03*
X302823Y1408495D03*
X306223D03*
X327303Y1348187D03*
X315063D03*
X318463D03*
X327303Y1360099D03*
X315063D03*
X318463D03*
X315063Y1372385D03*
X318463Y1384297D03*
X315063D03*
X327303Y1372385D03*
X318463D03*
X327303Y1384297D03*
Y1396583D03*
X315063D03*
X318463D03*
X327303Y1408495D03*
X318463D03*
X315063D03*
X339543Y1348187D03*
X342943D03*
X330703D03*
Y1360099D03*
X342943D03*
X339543D03*
Y1372385D03*
X342943D03*
X330703D03*
X342943Y1384297D03*
X339543D03*
X330703D03*
Y1396583D03*
X339543D03*
X342943D03*
X330703Y1408495D03*
X342943D03*
X339543D03*
X351783Y1348187D03*
X355183D03*
Y1360099D03*
X351783D03*
Y1372385D03*
X355183D03*
Y1384297D03*
X351783D03*
Y1396583D03*
X355183D03*
X351783Y1408495D03*
X355183D03*
X364023Y1348187D03*
X367423D03*
Y1360099D03*
X364023D03*
Y1372385D03*
X367423Y1384297D03*
X364023D03*
X367423Y1372385D03*
X364023Y1396583D03*
X367423D03*
X364023Y1408495D03*
X367423D03*
X393094Y1423600D03*
X395894D03*
X440402Y1348187D03*
Y1360099D03*
Y1372385D03*
Y1384297D03*
X452642Y1348187D03*
X456042D03*
X443802D03*
X456042Y1360099D03*
X452642D03*
X443802D03*
Y1372385D03*
X452642D03*
X456042D03*
X452642Y1384297D03*
X456042D03*
X443802D03*
X452642Y1396583D03*
X456042D03*
X452642Y1408495D03*
X456042D03*
X468282Y1348187D03*
X464882D03*
X468282Y1360099D03*
X464882D03*
Y1372385D03*
X468282D03*
X464882Y1384297D03*
X468282D03*
Y1396583D03*
X464882D03*
Y1408495D03*
X468282D03*
X489362Y1348187D03*
X480522D03*
X477122D03*
X480522Y1360099D03*
X477122D03*
X489362D03*
X477122Y1372385D03*
X480522D03*
X489362D03*
Y1384297D03*
X480522D03*
X477122D03*
X480522Y1396583D03*
X477122D03*
X489362D03*
X477122Y1408495D03*
X480522D03*
X489362D03*
X492762Y1348187D03*
X501602D03*
X505002D03*
X501602Y1360099D03*
X505002D03*
X492762D03*
X505002Y1372385D03*
X492762D03*
X501602D03*
X492762Y1384297D03*
X505002D03*
X501602D03*
X505002Y1396583D03*
X492762D03*
X501602D03*
X505002Y1408495D03*
X501602D03*
X492762D03*
X517242Y1348187D03*
X513842D03*
Y1360099D03*
X517242D03*
Y1372385D03*
X513842D03*
X517242Y1384297D03*
X513842D03*
X517242Y1396583D03*
X513842D03*
X517242Y1408495D03*
X513842D03*
X529482Y1348187D03*
X526082D03*
X538322D03*
Y1360099D03*
X529482D03*
X526082D03*
X529482Y1372385D03*
X538322Y1384297D03*
X529482D03*
X538322Y1372385D03*
X526082D03*
Y1384297D03*
Y1396583D03*
X538322D03*
X529482D03*
Y1408495D03*
X526082D03*
X538322D03*
X553962Y1348187D03*
X541722D03*
X550562D03*
X553962Y1360099D03*
X550562D03*
X541722D03*
Y1372385D03*
X550562D03*
X541722Y1384297D03*
X553962D03*
X550562D03*
X553962Y1372385D03*
Y1396583D03*
X541722D03*
X550562D03*
X553962Y1408495D03*
X550562D03*
X541722D03*
X562802Y1348187D03*
X566202D03*
Y1360099D03*
X562802D03*
X566202Y1372385D03*
Y1384297D03*
X562802D03*
Y1372385D03*
X566202Y1396583D03*
X562802D03*
X566202Y1408495D03*
X562802D03*
X629688Y1396583D03*
X626288D03*
Y1408495D03*
X629688D03*
X650768Y1348187D03*
Y1360099D03*
Y1384297D03*
Y1372385D03*
X638528D03*
X641928D03*
X638528Y1384297D03*
X641928D03*
Y1396583D03*
X638528D03*
X650768D03*
X638528Y1408495D03*
X641928D03*
X650768D03*
X666408Y1348187D03*
X663008D03*
X654168D03*
X666408Y1360099D03*
X663008D03*
X654168D03*
Y1384297D03*
Y1372385D03*
X663008D03*
X666408D03*
X663008Y1384297D03*
X666408D03*
Y1396583D03*
X663008D03*
X654168D03*
X666408Y1408495D03*
X663008D03*
X654168D03*
X678648Y1348187D03*
X675248D03*
X678648Y1360099D03*
X675248D03*
Y1384297D03*
X678648D03*
Y1372385D03*
X675248D03*
Y1396583D03*
X678648D03*
Y1408495D03*
X675248D03*
X690888Y1348187D03*
X687488D03*
X699728D03*
X687488Y1360099D03*
X690888D03*
X699728D03*
Y1372385D03*
Y1384297D03*
X690888Y1372385D03*
X687488D03*
Y1384297D03*
X690888D03*
Y1396583D03*
X687488D03*
X699728D03*
X687488Y1408495D03*
X690888D03*
X699728D03*
X715368Y1348187D03*
X711968D03*
X703128D03*
X715368Y1360099D03*
X711968D03*
X703128D03*
Y1372385D03*
Y1384297D03*
X715368Y1372385D03*
X711968D03*
X715368Y1384297D03*
X711968D03*
X715368Y1396583D03*
X711968D03*
X703128D03*
X715368Y1408495D03*
X711968D03*
X703128D03*
X727608Y1348187D03*
X724208D03*
Y1360099D03*
X727608D03*
X724208Y1372385D03*
Y1384297D03*
X727608D03*
Y1372385D03*
X724208Y1396489D03*
X727608D03*
X724208Y1408401D03*
X727608D03*
X739848Y1348187D03*
X736448D03*
X748688D03*
X736448Y1360099D03*
X739848D03*
X748688D03*
Y1372385D03*
Y1384297D03*
X739848Y1372385D03*
X736448D03*
X739848Y1384297D03*
X736448D03*
X739848Y1396489D03*
X736448D03*
X739848Y1408401D03*
X736448D03*
X760928Y1348187D03*
X764328D03*
X752088D03*
X764328Y1360099D03*
X760928D03*
X752088D03*
Y1372385D03*
Y1384297D03*
X764328Y1372385D03*
X760928D03*
X764328Y1384297D03*
X760928D03*
X776568Y1348187D03*
X773168D03*
Y1360099D03*
X776568D03*
X878220Y848442D03*
Y845293D03*
Y835844D03*
Y851592D03*
X877800Y876500D03*
X897118Y848442D03*
X881370Y835844D03*
X893968Y845293D03*
X884519Y848442D03*
X897118Y842143D03*
X893968D03*
X887669Y848442D03*
X886093Y835318D03*
X897118Y845293D03*
X893968Y838994D03*
X890818Y842143D03*
X893968Y835846D03*
X887669Y845293D03*
X890818D03*
X893968Y848442D03*
X884519Y845293D03*
X881370D03*
X884519Y842143D03*
X887669D03*
X881370Y848442D03*
X890818D03*
X887669Y851592D03*
X890818Y854742D03*
X887669D03*
X897118Y851592D03*
X890818Y864189D03*
Y857891D03*
X887669Y864189D03*
X884519Y854742D03*
Y851592D03*
Y857891D03*
X887669D03*
X890818Y851592D03*
X893967Y851591D03*
X881370Y851592D03*
X887669Y867338D03*
X890818Y870488D03*
X887669D03*
X897118Y876787D03*
X890818Y867338D03*
X881370D03*
X897118Y879937D03*
X884519Y873638D03*
X887669D03*
X884519Y876787D03*
X890818Y879937D03*
X881370Y876787D03*
X887669Y879937D03*
X884519Y867338D03*
X890818Y873638D03*
X893968Y876787D03*
Y879937D03*
X890818Y876787D03*
X884519Y879937D03*
Y870488D03*
X881370D03*
Y883086D03*
X884585Y886354D03*
X885126Y889742D03*
X881370Y886236D03*
X906565Y848442D03*
X900267D03*
X906565Y838994D03*
X900267Y838992D03*
X909714Y848442D03*
X906565Y842143D03*
X900267Y845293D03*
Y842143D03*
X906565Y845293D03*
X900266Y835844D03*
X900267Y851592D03*
X906565D03*
X909714D03*
Y876787D03*
X900267Y879937D03*
Y876787D03*
X906565D03*
X912864Y873638D03*
Y879937D03*
X909714D03*
X906565D03*
X912864Y876787D03*
X922313Y845293D03*
X919163Y848442D03*
X916014D03*
Y842143D03*
X919163Y845293D03*
X922313Y842143D03*
X916014Y845293D03*
X919163Y835844D03*
Y838994D03*
Y842143D03*
X925462Y845293D03*
X919163Y854742D03*
Y857891D03*
X922313Y854742D03*
X916014Y857891D03*
Y854742D03*
X919163Y851592D03*
X916014D03*
Y864189D03*
X925462Y851592D03*
X922313Y864189D03*
Y857891D03*
X925462D03*
X928612Y864189D03*
X919163D03*
X925462D03*
X916014Y870488D03*
X925462Y873638D03*
X922313Y876787D03*
X928612Y870488D03*
X925462D03*
X916014Y873638D03*
X922313D03*
X916014Y876787D03*
X928612Y873638D03*
X925462Y876787D03*
X928612D03*
Y879937D03*
X916014D03*
X922313D03*
X919163D03*
X925462D03*
X916014Y867338D03*
X919163Y873638D03*
Y870488D03*
X922313D03*
X919163Y876787D03*
X922313Y867338D03*
X919163D03*
X925462D03*
X922313Y883086D03*
Y886236D03*
X925462D03*
X919163Y883086D03*
X928612Y886236D03*
X925462Y883086D03*
X928612D03*
X1058113Y1348187D03*
X1054713D03*
X1058113Y1360099D03*
X1054713D03*
X1058113Y1372385D03*
X1054713D03*
Y1384297D03*
X1058113D03*
X1066953Y1348187D03*
X1070353D03*
X1066953Y1360099D03*
X1070353D03*
X1066953Y1384297D03*
Y1372385D03*
X1070353D03*
Y1384297D03*
Y1396583D03*
X1066953D03*
Y1408495D03*
X1070353D03*
X1091433Y1348187D03*
X1082593D03*
X1079193D03*
X1091433Y1360099D03*
X1082593D03*
X1079193D03*
Y1372385D03*
X1082593D03*
Y1384297D03*
X1079193D03*
X1091433D03*
Y1372385D03*
Y1396583D03*
X1082593D03*
X1079193D03*
X1091433Y1408495D03*
X1082593D03*
X1079193D03*
X1094833Y1348187D03*
X1107073D03*
X1103673D03*
X1094833Y1360099D03*
X1103673D03*
X1107073D03*
Y1372385D03*
X1103673D03*
X1107073Y1384297D03*
X1103673D03*
X1094833D03*
Y1372385D03*
Y1396583D03*
X1107073D03*
X1103673D03*
X1094833Y1408495D03*
X1107073D03*
X1103673D03*
X1115913Y1348187D03*
X1119313D03*
X1115913Y1360099D03*
X1119313D03*
Y1384297D03*
X1115913Y1372385D03*
X1119313D03*
X1115913Y1384297D03*
Y1396583D03*
X1119313D03*
X1115913Y1408495D03*
X1119313D03*
X1140393Y1348187D03*
X1131553D03*
X1128153D03*
X1140393Y1360099D03*
X1131553D03*
X1128153D03*
Y1384297D03*
X1131553D03*
X1128153Y1372385D03*
X1131553D03*
X1140393Y1384297D03*
Y1372385D03*
Y1396583D03*
X1131553D03*
X1128153D03*
X1140393Y1408495D03*
X1128153D03*
X1131553D03*
X1143793Y1348187D03*
X1156033D03*
X1152633D03*
X1143793Y1360099D03*
X1152633D03*
X1156033D03*
Y1384297D03*
X1152633D03*
X1156033Y1372385D03*
X1152633D03*
X1143793D03*
Y1384297D03*
Y1396583D03*
X1156033D03*
X1152633D03*
X1143793Y1408495D03*
X1152633D03*
X1156033D03*
X1168273Y1348187D03*
X1164873D03*
Y1360099D03*
X1168273D03*
Y1384297D03*
X1164873D03*
X1168273Y1372385D03*
X1164873D03*
Y1396583D03*
X1168273D03*
Y1408495D03*
X1164873D03*
X1184547Y1215452D03*
X1177113Y1348187D03*
X1180513D03*
X1177113Y1360099D03*
X1180513D03*
X1177113Y1384297D03*
X1180513D03*
X1177113Y1372385D03*
X1180513D03*
Y1396583D03*
X1177113D03*
Y1408495D03*
X1180513D03*
X1230326Y1348187D03*
X1233726D03*
X1230326Y1360099D03*
X1233726D03*
X1230326Y1372385D03*
X1233726D03*
X1230326Y1384297D03*
X1233726D03*
X1245966Y1348187D03*
X1242566D03*
X1254806D03*
Y1360099D03*
X1242566D03*
X1245966D03*
X1254806Y1372385D03*
X1242566D03*
X1245966D03*
X1242566Y1384297D03*
X1245966D03*
X1254806D03*
X1245966Y1396583D03*
X1254806D03*
X1242566D03*
X1254806Y1408495D03*
X1242566D03*
X1245966D03*
X1267046Y1348187D03*
X1270446D03*
X1258206D03*
Y1360099D03*
X1270446D03*
X1267046D03*
X1258206Y1372385D03*
X1270446D03*
X1267046D03*
X1270446Y1384297D03*
X1267046D03*
X1258206D03*
X1267046Y1396583D03*
X1270446D03*
X1258206D03*
Y1408495D03*
X1270446D03*
X1267046D03*
X1282686Y1348187D03*
X1279286D03*
Y1360099D03*
X1282686D03*
X1279286Y1372385D03*
X1282686D03*
Y1384297D03*
X1279286D03*
Y1396583D03*
X1282686D03*
X1279286Y1408495D03*
X1282686D03*
X1291526Y1348187D03*
X1294926D03*
X1291526Y1360099D03*
X1294926D03*
X1291526Y1372385D03*
X1294926D03*
X1291526Y1384297D03*
X1294926D03*
Y1396583D03*
X1291526D03*
Y1408495D03*
X1294926D03*
X1316906Y829871D03*
Y833021D03*
Y848769D03*
X1313756Y833021D03*
Y836170D03*
X1316906Y839320D03*
X1310555Y848675D03*
X1313756Y848769D03*
X1316906Y836170D03*
X1313756Y842470D03*
Y858218D03*
X1316906Y855068D03*
X1313756Y855066D03*
X1316906Y858218D03*
X1319406Y1348187D03*
X1316006D03*
X1307166D03*
X1303766D03*
X1319406Y1360099D03*
X1316006D03*
X1307166D03*
X1303766D03*
X1316006Y1372385D03*
X1307166D03*
X1303766D03*
Y1384297D03*
X1307166D03*
X1319406Y1372385D03*
X1316006Y1384297D03*
X1319406D03*
Y1396583D03*
X1316006D03*
X1303766D03*
X1307166D03*
X1316006Y1408495D03*
X1319406D03*
X1307166D03*
X1303766D03*
X1335803Y829871D03*
X1323205D03*
X1326355Y839320D03*
X1335803D03*
X1329504Y833021D03*
X1332654Y842470D03*
X1329504Y845619D03*
X1332654D03*
X1326355Y836170D03*
X1335803Y842470D03*
X1329504Y836170D03*
X1335803Y845619D03*
Y848769D03*
X1329504Y839320D03*
X1323205Y836170D03*
X1335803D03*
X1329504Y842470D03*
X1335803Y833021D03*
X1323205D03*
X1320055Y845619D03*
X1326355D03*
X1320055Y836170D03*
X1326355Y842470D03*
X1320055Y848769D03*
X1323205Y845619D03*
X1332654Y848769D03*
X1320055Y839320D03*
X1326355Y848769D03*
X1323205D03*
X1329504D03*
X1323204Y839319D03*
X1332654Y839320D03*
X1320055Y842470D03*
X1323205D03*
X1329504Y855068D03*
Y858218D03*
X1320055Y851918D03*
X1332654Y855068D03*
X1326355D03*
Y858218D03*
X1329504Y861367D03*
X1323205Y858218D03*
X1320055D03*
X1332654Y861367D03*
X1329504Y851918D03*
X1323205D03*
X1326355Y861367D03*
X1320055Y855068D03*
X1332654Y858218D03*
X1335803Y855068D03*
Y858218D03*
Y861367D03*
X1320055D03*
X1323204Y855067D03*
X1326355Y851918D03*
X1332654D03*
X1326355Y880263D03*
X1329504Y877114D03*
X1335803Y880263D03*
X1326355Y867665D03*
Y870814D03*
X1323205D03*
X1320055D03*
X1329504Y867665D03*
X1326355Y873964D03*
X1332654Y880263D03*
X1329504D03*
X1332654Y877114D03*
X1326355D03*
X1329504Y870814D03*
X1320055Y873964D03*
X1332654Y870814D03*
X1323204Y873965D03*
X1332654Y867665D03*
X1320055Y880263D03*
Y867665D03*
X1323205Y880263D03*
Y877114D03*
X1320055D03*
X1335803Y867665D03*
Y873964D03*
Y870814D03*
X1332654Y873964D03*
X1329504D03*
X1323205Y867665D03*
Y886562D03*
X1326355Y889712D03*
X1335803Y883413D03*
X1329504Y892862D03*
X1332654Y889712D03*
X1335803Y892862D03*
Y889712D03*
X1326355Y892862D03*
X1329504Y889712D03*
X1320055Y892862D03*
X1323205D03*
X1329504Y886562D03*
X1332654Y883413D03*
X1320055Y886562D03*
X1326355Y883413D03*
X1323205D03*
X1332654Y892862D03*
X1320055Y883413D03*
X1332654Y886562D03*
X1335803D03*
X1320055Y889712D03*
X1323204Y889713D03*
X1329504Y883413D03*
X1328246Y1348187D03*
X1331646D03*
X1328246Y1360099D03*
X1331646D03*
Y1384297D03*
Y1372385D03*
X1328246D03*
Y1384297D03*
X1331646Y1396583D03*
X1328246D03*
X1331646Y1408495D03*
X1328246D03*
X1342103Y845619D03*
X1345252Y836170D03*
X1338953Y845619D03*
X1345252Y833021D03*
X1342103Y836170D03*
X1351550D03*
X1342103Y842470D03*
X1345252Y845619D03*
X1342103Y839320D03*
X1338953Y848769D03*
X1338952Y839319D03*
X1345252Y842470D03*
X1342103Y848769D03*
X1338953Y842470D03*
X1345252Y848769D03*
X1338953Y836170D03*
X1351550Y842470D03*
Y848769D03*
Y845619D03*
X1345252Y839320D03*
X1351550Y858218D03*
X1345252D03*
Y861367D03*
X1342103Y858218D03*
X1351550Y861367D03*
X1338953Y851918D03*
X1342103D03*
X1345252D03*
X1351550D03*
X1338953Y880263D03*
X1351550D03*
X1345252D03*
X1342103Y870814D03*
X1345252D03*
Y867665D03*
X1351550Y870814D03*
Y867665D03*
X1338953Y877114D03*
X1345252D03*
X1351550D03*
X1342103Y880263D03*
X1338953Y883413D03*
X1345252Y889712D03*
Y886562D03*
X1342103Y883413D03*
X1345252D03*
X1338952Y889713D03*
X1338953Y892862D03*
X1342103Y886562D03*
Y892862D03*
Y889712D03*
X1338953Y886562D03*
X1351550Y883413D03*
Y889712D03*
Y886562D03*
Y892862D03*
X1343886Y1348187D03*
X1340486D03*
X1343886Y1360099D03*
X1340486D03*
X1343886Y1372385D03*
X1340486D03*
Y1384297D03*
X1343886D03*
X1340486Y1396583D03*
X1343886D03*
Y1408495D03*
X1340486D03*
X1364148Y829871D03*
X1367298D03*
X1359425Y829000D03*
X1354699Y842470D03*
Y848769D03*
X1357849D03*
X1364148Y845619D03*
X1354699Y836170D03*
X1357849Y833021D03*
X1367298Y845619D03*
X1364148Y842470D03*
X1357850Y839319D03*
X1357849Y836170D03*
X1360999Y842470D03*
X1354699Y845619D03*
X1357849D03*
X1360999Y839320D03*
X1367298Y842470D03*
X1360999Y848769D03*
Y845619D03*
X1367298Y833021D03*
X1354699Y839320D03*
X1360999Y836170D03*
X1367298Y848769D03*
X1364148Y839320D03*
X1357849Y842470D03*
X1364148Y833021D03*
X1367298Y836170D03*
Y839320D03*
X1364148Y848769D03*
Y851918D03*
X1367298Y861367D03*
X1364148Y858218D03*
Y855068D03*
Y861367D03*
X1367298Y858218D03*
Y851918D03*
X1354699Y858218D03*
X1367298Y855068D03*
X1360999D03*
Y858218D03*
Y861367D03*
X1354699Y851918D03*
X1357849D03*
X1364148Y867665D03*
X1367298Y877114D03*
X1364148Y870814D03*
X1367298Y873964D03*
X1364148D03*
Y877114D03*
X1367298Y870814D03*
X1364148Y880263D03*
X1367298D03*
X1357849D03*
X1360999D03*
X1367298Y867665D03*
X1354699Y870814D03*
X1357849Y877114D03*
X1354699Y880263D03*
X1360999Y867665D03*
Y870814D03*
Y873964D03*
X1367298Y883413D03*
X1354699Y892862D03*
X1360999D03*
X1367298D03*
X1360999Y883413D03*
X1357850Y889713D03*
X1364148Y889712D03*
X1357849Y883413D03*
X1367298Y889712D03*
X1354699D03*
X1357849Y886562D03*
X1364148D03*
X1357849Y892862D03*
X1360999Y889712D03*
X1354699Y883413D03*
X1360999Y886562D03*
X1364148Y892862D03*
Y883413D03*
X1367298Y886562D03*
X1354699D03*
X1356126Y1348187D03*
X1352726D03*
X1356126Y1360099D03*
X1352726D03*
Y1384297D03*
X1356126Y1372385D03*
Y1384297D03*
X1352726Y1372385D03*
X1356126Y1396583D03*
X1352726D03*
Y1408495D03*
X1356126D03*
X1370447Y829871D03*
Y839320D03*
X1383046Y845619D03*
X1379896D03*
X1373597D03*
Y842470D03*
X1370447Y848769D03*
X1379896D03*
Y839320D03*
X1373597Y848769D03*
X1376747D03*
X1373597Y833021D03*
X1370447D03*
X1373597Y836170D03*
X1370447D03*
X1373598Y839319D03*
X1370447Y842470D03*
Y845619D03*
X1383046Y842470D03*
X1376747Y836170D03*
Y842470D03*
X1379896Y833021D03*
X1383046Y839320D03*
X1376747Y845619D03*
Y839320D03*
X1379896Y855068D03*
Y861367D03*
X1376747Y858218D03*
Y851918D03*
X1373597Y861367D03*
X1376747Y855068D03*
X1373597Y858218D03*
X1376747Y861367D03*
X1383046Y851918D03*
X1373597D03*
X1373598Y855067D03*
X1379896Y851918D03*
X1370447D03*
Y858218D03*
X1383046D03*
Y861367D03*
X1370447Y855068D03*
Y861367D03*
X1383046Y873964D03*
X1376747Y880263D03*
X1370447Y877114D03*
X1373598Y873965D03*
X1370447Y873964D03*
X1379896Y877114D03*
X1373597Y880263D03*
X1383046Y877114D03*
X1370447Y880263D03*
X1376747Y873964D03*
X1383046Y880263D03*
X1370447Y870814D03*
X1376747D03*
X1373597D03*
X1376747Y867665D03*
Y877114D03*
X1373597Y867665D03*
X1379896D03*
X1383046Y870814D03*
X1379896Y880263D03*
X1373597Y877114D03*
X1379896Y873964D03*
X1383046Y892862D03*
X1379896Y886562D03*
X1370447Y883413D03*
X1373598Y889713D03*
X1376747Y886562D03*
X1383046Y883413D03*
X1376747Y889712D03*
X1383046D03*
X1379896D03*
X1373597Y883413D03*
Y886562D03*
X1370447Y892862D03*
X1376747D03*
X1370447Y889712D03*
X1373597Y892862D03*
X1383046Y886562D03*
X1379896Y892862D03*
X1376747Y883413D03*
X1464770Y1348187D03*
X1461370D03*
X1464770Y1360099D03*
X1461370D03*
X1464770Y1372385D03*
X1461370D03*
X1464770Y1384297D03*
X1461370D03*
X1477010Y1348187D03*
X1473610D03*
Y1360099D03*
X1477010D03*
X1473610Y1372385D03*
X1477010D03*
X1473610Y1384297D03*
X1477010D03*
Y1396583D03*
X1473610D03*
Y1408495D03*
X1477010D03*
X1489250Y1348187D03*
X1485850D03*
X1498090D03*
Y1360099D03*
X1485850D03*
X1489250D03*
Y1372385D03*
X1485850D03*
X1498090D03*
X1485850Y1384297D03*
X1498090D03*
X1489250D03*
X1498090Y1396583D03*
X1485850D03*
X1489250D03*
X1498090Y1408495D03*
X1489250D03*
X1485850D03*
X1513730Y1348187D03*
X1510330D03*
X1501490D03*
X1510330Y1360099D03*
X1501490D03*
X1513730D03*
X1510330Y1372385D03*
X1513730D03*
X1501490D03*
Y1384297D03*
X1513730D03*
X1510330D03*
Y1396583D03*
X1513730D03*
X1501490D03*
X1510330Y1408495D03*
X1513730D03*
X1501490D03*
X1525970Y1348187D03*
X1522570D03*
Y1360099D03*
X1525970D03*
Y1372385D03*
X1522570D03*
X1525970Y1384297D03*
X1522570D03*
Y1396583D03*
X1525970D03*
Y1408495D03*
X1522570D03*
X1538210Y1348187D03*
X1547050D03*
X1534810D03*
X1538210Y1360099D03*
X1534810D03*
X1547050D03*
X1538210Y1372385D03*
X1534810D03*
X1547050D03*
Y1384297D03*
X1534810D03*
X1538210D03*
Y1396583D03*
X1534810D03*
X1547050D03*
X1538210Y1408495D03*
X1534810D03*
X1547050D03*
X1550450Y1348187D03*
X1559290D03*
X1562690D03*
X1559290Y1360099D03*
X1562690D03*
X1550450D03*
X1562690Y1372385D03*
X1559290D03*
X1550450D03*
X1562690Y1384297D03*
X1559290D03*
X1550450D03*
Y1396583D03*
X1562690D03*
X1559290D03*
Y1408495D03*
X1562690D03*
X1550450D03*
X1574930Y1348187D03*
X1571530D03*
X1574930Y1360099D03*
X1571530D03*
X1574930Y1372385D03*
X1571530D03*
Y1384297D03*
X1574930D03*
X1571530Y1396583D03*
X1574930D03*
X1571530Y1408495D03*
X1574930D03*
X1587170Y1348187D03*
X1583770D03*
X1587170Y1360099D03*
X1583770D03*
X1587170Y1372385D03*
X1583770D03*
Y1384297D03*
X1587170D03*
X1583770Y1396583D03*
X1587170D03*
X1583770Y1408495D03*
X1587170D03*
X1611398Y1348187D03*
Y1360099D03*
Y1384297D03*
Y1372385D03*
X1614798Y1348187D03*
X1623638D03*
X1627038D03*
X1614798Y1360099D03*
X1623638D03*
X1627038D03*
Y1372385D03*
X1623638D03*
X1627038Y1384297D03*
X1623638D03*
X1614798Y1372385D03*
Y1384297D03*
X1627038Y1396583D03*
X1623638D03*
X1627038Y1408495D03*
X1623638D03*
X1641634Y1215452D03*
X1639278Y1348187D03*
X1635878D03*
X1639278Y1360099D03*
X1635878D03*
Y1384297D03*
X1639278D03*
Y1372385D03*
X1635878D03*
X1639278Y1396583D03*
X1635878D03*
Y1408495D03*
X1639278D03*
X1660358Y1348187D03*
X1651518D03*
X1648118D03*
X1660358Y1360099D03*
X1651518D03*
X1648118D03*
Y1372385D03*
X1651518D03*
X1648118Y1384297D03*
X1651518D03*
X1660358D03*
Y1372385D03*
Y1396583D03*
X1651518D03*
X1648118D03*
X1660358Y1408495D03*
X1648118D03*
X1651518D03*
X1663758Y1348187D03*
X1672598D03*
X1675998D03*
X1663758Y1360099D03*
X1675998D03*
X1672598D03*
X1675998Y1372385D03*
X1672598D03*
Y1384297D03*
X1675998D03*
X1663758D03*
Y1372385D03*
Y1396583D03*
X1675998D03*
X1672598D03*
X1663758Y1408495D03*
X1675998D03*
X1672598D03*
X1688238Y1348187D03*
X1684838D03*
X1688238Y1360099D03*
X1684838D03*
Y1384297D03*
X1688238D03*
X1684838Y1372385D03*
X1688238D03*
X1684838Y1396583D03*
X1688238D03*
Y1408495D03*
X1684838D03*
X1709318Y1348187D03*
X1700478D03*
X1697078D03*
X1709318Y1360099D03*
X1697078D03*
X1700478D03*
X1697078Y1372385D03*
X1700478D03*
X1697078Y1384297D03*
X1700478D03*
X1709318D03*
Y1372385D03*
Y1396583D03*
X1700478D03*
X1697078D03*
X1709318Y1408495D03*
X1697078D03*
X1700478D03*
X1712718Y1348187D03*
X1721558D03*
X1724958D03*
X1712718Y1360099D03*
X1724958D03*
X1721558D03*
Y1372385D03*
X1724958D03*
Y1384297D03*
X1721558D03*
X1712718Y1372385D03*
Y1384297D03*
Y1396583D03*
X1721558D03*
X1724958D03*
X1712718Y1408495D03*
X1721558D03*
X1724958D03*
X1733798Y1348187D03*
X1737198D03*
X1733798Y1360099D03*
X1737198D03*
Y1384297D03*
X1733798D03*
Y1372385D03*
X1737198D03*
Y1396583D03*
X1733798D03*
X1737198Y1408495D03*
X1733798D03*
G54D28*
X116731Y1052235D03*
X106619Y1056423D03*
X102431Y1066535D03*
X106619Y1076647D03*
X116731Y1080835D03*
Y1249086D03*
X106619Y1253274D03*
X102431Y1263386D03*
X106619Y1273498D03*
X116731Y1277686D03*
X126843Y1056423D03*
Y1076647D03*
X131031Y1066535D03*
X126843Y1253274D03*
X131031Y1263386D03*
X126843Y1273498D03*
X342840Y1056423D03*
X338652Y1066535D03*
X342840Y1076647D03*
Y1253274D03*
X338652Y1263386D03*
X342840Y1273498D03*
X352952Y1052235D03*
Y1080835D03*
Y1249086D03*
Y1277686D03*
X363064Y1056423D03*
Y1076647D03*
X367252Y1066535D03*
X363064Y1253274D03*
X367252Y1263386D03*
X363064Y1273498D03*
X563706Y1056423D03*
X559518Y1066535D03*
X563706Y1076647D03*
Y1253274D03*
X559518Y1263386D03*
X563706Y1273498D03*
X583930Y1056423D03*
X573818Y1052235D03*
X583930Y1076647D03*
X588118Y1066535D03*
X573818Y1080835D03*
X583930Y1253274D03*
X573818Y1249086D03*
X588118Y1263386D03*
X573818Y1277686D03*
X583930Y1273498D03*
X760433Y1480906D03*
X756274Y1490945D03*
X760433Y1500984D03*
X780511Y1480906D03*
X770472Y1476747D03*
Y1505143D03*
X780511Y1500984D03*
X799926Y1056423D03*
X795738Y1066535D03*
X799926Y1076647D03*
Y1253274D03*
X795738Y1263386D03*
X799926Y1273498D03*
X784670Y1490945D03*
X810040Y378544D03*
X805881Y388583D03*
X810040Y398622D03*
X810038Y1052235D03*
Y1080835D03*
Y1249086D03*
Y1277686D03*
X820079Y374385D03*
X830118Y378544D03*
X820079Y402781D03*
X830118Y398622D03*
X820150Y1056423D03*
Y1076647D03*
X824338Y1066535D03*
X820150Y1253274D03*
X824338Y1263386D03*
X820150Y1273498D03*
X834277Y388583D03*
X1010827Y378544D03*
X1006668Y388583D03*
X1010827Y398622D03*
X1020866Y374385D03*
Y402781D03*
X1020793Y1056423D03*
X1016605Y1066535D03*
X1020793Y1076647D03*
Y1253274D03*
X1016605Y1263386D03*
X1020793Y1273498D03*
X1030905Y378544D03*
X1035064Y388583D03*
X1030905Y398622D03*
X1041017Y1056423D03*
X1030905Y1052235D03*
X1041017Y1076647D03*
X1030905Y1080835D03*
X1041017Y1253274D03*
X1030905Y1249086D03*
Y1277686D03*
X1041017Y1273498D03*
X1045205Y1066535D03*
Y1263386D03*
X1060433Y1480906D03*
X1056274Y1490945D03*
X1060433Y1500984D03*
X1070472Y1476747D03*
Y1505143D03*
X1080511Y1480906D03*
X1084670Y1490945D03*
X1080511Y1500984D03*
X1252825Y1066535D03*
Y1263386D03*
X1267125Y1052235D03*
X1257013Y1056423D03*
Y1076647D03*
X1267125Y1080835D03*
Y1249086D03*
X1257013Y1253274D03*
Y1273498D03*
X1267125Y1277686D03*
X1277237Y1056423D03*
Y1076647D03*
X1281425Y1066535D03*
X1277237Y1253274D03*
X1281425Y1263386D03*
X1277237Y1273498D03*
X1477879Y1056423D03*
X1473691Y1066535D03*
X1477879Y1076647D03*
Y1253274D03*
X1473691Y1263386D03*
X1477879Y1273498D03*
X1498103Y1056423D03*
X1487991Y1052235D03*
X1498103Y1076647D03*
X1487991Y1080835D03*
X1498103Y1253274D03*
X1487991Y1249086D03*
Y1277686D03*
X1498103Y1273498D03*
X1502291Y1066535D03*
Y1263386D03*
X1709912Y1066535D03*
Y1263386D03*
X1724212Y1052235D03*
X1714100Y1056423D03*
Y1076647D03*
X1724212Y1080835D03*
Y1249086D03*
X1714100Y1253274D03*
Y1273498D03*
X1724212Y1277686D03*
X1734324Y1056423D03*
Y1076647D03*
X1738512Y1066535D03*
X1734324Y1253274D03*
X1738512Y1263386D03*
X1734324Y1273498D03*
G54D42*
X710406Y-26826D03*
Y-36826D03*
D03*
Y-26826D03*
X735406D03*
Y-36826D03*
D03*
Y-26826D03*
X830406Y-76006D03*
D03*
Y-66006D03*
D03*
X855406Y-76006D03*
D03*
Y-66006D03*
D03*
X939542Y-36798D03*
Y-26798D03*
D03*
Y-36798D03*
X964386Y-75978D03*
D03*
Y-65978D03*
D03*
X964542Y-36798D03*
Y-26798D03*
D03*
Y-36798D03*
X989386Y-75978D03*
D03*
Y-65978D03*
D03*
X993906Y-46826D03*
Y-36826D03*
D03*
Y-26826D03*
X1018906Y-46826D03*
Y-36826D03*
D03*
Y-26826D03*
X1063906Y-76006D03*
Y-86006D03*
Y-76006D03*
Y-66006D03*
X1088906Y-76006D03*
Y-86006D03*
Y-76006D03*
Y-66006D03*
X1217686Y-85978D03*
Y-75978D03*
D03*
Y-65978D03*
X1223042Y-46928D03*
Y-36928D03*
Y-26928D03*
Y-36928D03*
X1242686Y-85978D03*
Y-75978D03*
D03*
Y-65978D03*
X1248042Y-46928D03*
Y-36928D03*
Y-26928D03*
Y-36928D03*
X1280406Y-46956D03*
Y-36956D03*
D03*
Y-26956D03*
X1305406Y-46956D03*
Y-36956D03*
D03*
Y-26956D03*
X1320406Y-76006D03*
Y-86006D03*
Y-76006D03*
Y-66006D03*
X1345406Y-76006D03*
Y-86006D03*
Y-76006D03*
Y-66006D03*
X1474186Y-85978D03*
Y-75978D03*
D03*
Y-65978D03*
X1499186Y-85978D03*
Y-75978D03*
D03*
Y-65978D03*
X1509542Y-47058D03*
Y-37058D03*
Y-27058D03*
Y-37058D03*
X1534542Y-47058D03*
Y-37058D03*
Y-27058D03*
Y-37058D03*
X1564906Y-47086D03*
Y-37086D03*
D03*
Y-27086D03*
X1574906Y-76006D03*
Y-86006D03*
Y-76006D03*
Y-66006D03*
X1589906Y-47086D03*
Y-37086D03*
D03*
Y-27086D03*
X1599906Y-76006D03*
Y-86006D03*
Y-76006D03*
Y-66006D03*
X1728686Y-85978D03*
Y-75978D03*
D03*
Y-65978D03*
X1753686Y-85978D03*
Y-75978D03*
D03*
Y-65978D03*
X1794042Y-47188D03*
Y-37188D03*
Y-27188D03*
Y-37188D03*
X1819042Y-47188D03*
Y-37188D03*
Y-27188D03*
Y-37188D03*
G54D10*
X3704Y5374D03*
X3017Y24773D03*
Y44773D03*
Y64773D03*
Y84773D03*
Y104773D03*
Y124773D03*
Y144773D03*
Y164773D03*
Y184773D03*
Y204773D03*
Y224773D03*
Y244773D03*
Y264773D03*
Y284773D03*
Y304773D03*
X3221Y324773D03*
X3035Y978036D03*
Y998036D03*
Y1018036D03*
Y1038036D03*
Y1058036D03*
Y1078036D03*
Y1098036D03*
Y1118036D03*
Y1138036D03*
Y1158036D03*
Y1178036D03*
Y1198036D03*
Y1238036D03*
Y1258036D03*
Y1278036D03*
Y1298036D03*
Y1318036D03*
Y1338036D03*
Y1358036D03*
Y1378036D03*
Y1398036D03*
Y1418036D03*
Y1438036D03*
Y1458036D03*
Y1478036D03*
Y1498036D03*
Y1538036D03*
Y1558036D03*
X15972Y3000D03*
X10971Y333342D03*
X17964Y349298D03*
Y369298D03*
Y389298D03*
Y409298D03*
Y429298D03*
Y449298D03*
Y469298D03*
Y489298D03*
Y509298D03*
Y529298D03*
Y549298D03*
Y569298D03*
Y589298D03*
Y609298D03*
Y629298D03*
Y649298D03*
Y669298D03*
Y689298D03*
Y709298D03*
Y729298D03*
Y749298D03*
Y769298D03*
Y789298D03*
Y809298D03*
Y829298D03*
Y849298D03*
Y869298D03*
Y889298D03*
Y909298D03*
Y929298D03*
X9554Y961954D03*
X17964Y949298D03*
X6161Y1075991D03*
X6108Y1070611D03*
Y1065318D03*
X6059Y1091964D03*
X6055Y1086546D03*
X6053Y1081305D03*
X8042Y1522199D03*
X7922Y1532494D03*
X26956Y4469D03*
X28317Y24773D03*
Y44773D03*
X35638Y53597D03*
X36692Y641817D03*
X27934Y1204311D03*
X30934D03*
X27934Y1215511D03*
X30934D03*
X27934Y1212711D03*
Y1209911D03*
Y1207111D03*
X30934Y1212711D03*
Y1209911D03*
Y1207111D03*
X21544Y1479662D03*
X33536Y1467485D03*
X21544Y1489648D03*
X42192Y641817D03*
X51449Y822718D03*
X47949D03*
X44960Y1190619D03*
X49638Y1203884D03*
X40996Y1467703D03*
X40195Y1511279D03*
X55638Y53597D03*
X66371Y482134D03*
Y484634D03*
X60233Y521804D03*
X68202Y522129D03*
X60233Y524304D03*
X56540Y531378D03*
Y528878D03*
X68202Y527129D03*
Y524629D03*
Y529629D03*
X62789Y608311D03*
X66510Y628242D03*
X60849Y826818D03*
X64649D03*
X58949Y821018D03*
X64849Y840418D03*
X60249D03*
X74432Y5374D03*
X73745Y24773D03*
Y44773D03*
X73509Y110445D03*
Y115401D03*
X83911Y117557D03*
X80660Y103783D03*
X73509Y129574D03*
Y124618D03*
X83911Y122513D03*
Y131731D03*
Y136687D03*
X69816Y475946D03*
Y478446D03*
X78033Y478586D03*
Y481086D03*
Y476086D03*
Y483586D03*
X72549Y838818D03*
X93334Y3000D03*
X95943Y377953D03*
X113334Y3000D03*
X129318Y4469D03*
X130679Y24773D03*
Y44773D03*
X138000Y53597D03*
X146196Y390223D03*
X138194Y397335D03*
X146196Y395179D03*
Y404396D03*
Y409352D03*
X138194Y402291D03*
X135794Y416465D03*
Y411509D03*
X146196Y418569D03*
Y423525D03*
X135794Y425682D03*
Y430638D03*
X146196Y432743D03*
Y437699D03*
X135794Y439855D03*
Y444811D03*
Y468609D03*
Y473565D03*
X146196Y489895D03*
X135794Y487738D03*
X146196Y480677D03*
Y475721D03*
X135794Y482782D03*
X146196Y494851D03*
X135794Y512743D03*
Y517699D03*
X146196Y519855D03*
X135794Y526916D03*
Y531872D03*
X146196Y524811D03*
Y538984D03*
Y534028D03*
X158000Y53597D03*
X176794Y5374D03*
X176107Y24773D03*
Y44773D03*
X195697Y3000D03*
X183022Y103783D03*
X215697Y3000D03*
X231681Y4469D03*
X229745Y1446675D03*
X224753D03*
Y1462631D03*
X229745Y1457675D03*
X224753D03*
X229745Y1451631D03*
Y1462631D03*
X224753Y1451631D03*
X233042Y24773D03*
Y44773D03*
X240363Y53597D03*
X260363D03*
X279156Y5374D03*
X278469Y24773D03*
Y44773D03*
X265945Y440098D03*
Y437598D03*
Y435098D03*
Y432598D03*
Y430098D03*
X294959Y11097D03*
X285384Y103783D03*
X298059Y3000D03*
X301943Y332017D03*
X318059Y3000D03*
X318497Y466528D03*
Y471484D03*
X328899Y473640D03*
Y487813D03*
Y478596D03*
X318497Y480701D03*
Y485657D03*
X328899Y492769D03*
Y517774D03*
X318497Y510661D03*
Y515617D03*
X328899Y522730D03*
X318497Y524835D03*
X328899Y536903D03*
Y531947D03*
X318497Y529791D03*
X328899Y572769D03*
X318497Y565657D03*
Y560701D03*
X328899Y567813D03*
X318497Y579830D03*
Y574874D03*
X328899Y581987D03*
X318497Y589047D03*
X328899Y586943D03*
X318497Y594003D03*
X328899Y596160D03*
X318497Y603221D03*
X328899Y601116D03*
Y610333D03*
X318497Y608177D03*
X328899Y615289D03*
X334043Y4469D03*
X335404Y24773D03*
Y44773D03*
X342725Y53597D03*
X348737Y375386D03*
X354486Y377173D03*
X357173Y392183D03*
X357218Y396866D03*
X361234Y402867D03*
X358042Y442518D03*
Y439718D03*
X362725Y53597D03*
X361767Y392228D03*
X376992Y395248D03*
X368587Y409016D03*
X364551Y409032D03*
X361811Y396866D03*
X375919Y449118D03*
Y446318D03*
X367919Y449118D03*
Y446318D03*
X376099Y458309D03*
Y454309D03*
Y462309D03*
X369282Y468088D03*
Y465288D03*
X367816Y1310586D03*
Y1315542D03*
X388059Y3000D03*
X381518Y5374D03*
X388487Y24069D03*
X380831Y24773D03*
X383612Y30618D03*
X380831Y44773D03*
X387746Y103783D03*
X389237Y371070D03*
X385237Y370976D03*
X396373Y407104D03*
X385584Y450041D03*
Y452841D03*
Y455641D03*
X387587Y1296675D03*
X387644Y1302089D03*
X389458Y1365466D03*
X389188Y1369033D03*
X388600Y1395500D03*
X389985Y1405762D03*
X408059Y3000D03*
X396373Y409904D03*
X395577Y455641D03*
Y450041D03*
Y452841D03*
X397315Y479560D03*
X400914Y762675D03*
X408300Y755487D03*
X407965Y770196D03*
X408400Y795200D03*
Y792200D03*
X406600Y789000D03*
X402376Y842677D03*
X399876D03*
X402376Y850677D03*
X399876D03*
X395959Y1352153D03*
X403029Y1379716D03*
X403111Y1384920D03*
X408212Y1379695D03*
X394657Y1377875D03*
X403111Y1390103D03*
X408212Y1390083D03*
X410152Y1410928D03*
X398112Y1403741D03*
X415453Y455039D03*
X419040Y533690D03*
Y528390D03*
Y530990D03*
Y536290D03*
Y538890D03*
X423266Y631438D03*
X420266D03*
X417666D03*
X420266Y637038D03*
Y634238D03*
X417666Y637038D03*
Y634238D03*
X423266Y637038D03*
Y634238D03*
Y642638D03*
X420266D03*
X417666D03*
X423266Y639838D03*
X420266D03*
X417666D03*
X415696Y762466D03*
X424649Y842644D03*
X422149D03*
Y850644D03*
X424649D03*
X422149Y858644D03*
X424649D03*
X414280Y1362561D03*
X413437Y1379736D03*
Y1384899D03*
X413395Y1390062D03*
X428059Y3000D03*
X433724Y433975D03*
X432310Y436164D03*
X428740Y533690D03*
X442704Y533790D03*
X428740Y528390D03*
Y530990D03*
X442704Y528490D03*
Y531090D03*
X428740Y536290D03*
Y538890D03*
X442704Y536390D03*
Y538990D03*
X436369Y622883D03*
X441612Y631011D03*
X435881Y1394934D03*
Y1398800D03*
X448059Y3000D03*
X452404Y533690D03*
Y528390D03*
Y530990D03*
Y536290D03*
Y538890D03*
X468059Y3000D03*
X468850Y537507D03*
X461849Y668016D03*
X459349D03*
X466849D03*
X469349D03*
X464349D03*
X469349Y678016D03*
X466849D03*
X459349D03*
X461849D03*
X464349D03*
X484043Y4469D03*
X485404Y24773D03*
Y44773D03*
X482193Y472784D03*
Y468784D03*
Y476784D03*
X484341Y700528D03*
Y705484D03*
X492725Y53597D03*
X499278Y641817D03*
X493778D03*
X512725Y53597D03*
X523457Y482134D03*
Y484634D03*
X517319Y521804D03*
X513626Y528578D03*
Y531378D03*
X517319Y524304D03*
X519875Y608311D03*
X523596Y628242D03*
X531518Y5374D03*
X530831Y24773D03*
Y44773D03*
X537747Y103783D03*
X535119Y483886D03*
Y481086D03*
Y478586D03*
X526902Y478446D03*
Y475946D03*
X535119Y476086D03*
X525288Y522129D03*
Y524629D03*
Y527129D03*
Y529929D03*
X542275Y760782D03*
X532449Y782389D03*
X534672Y785037D03*
X536641Y838649D03*
X550421Y3000D03*
X542599Y782389D03*
X542546Y784911D03*
X554357Y784889D03*
X551524D03*
X570421Y3000D03*
X562231Y784911D03*
X558294D03*
X560263Y829989D03*
X568503Y936807D03*
X565003D03*
X586405Y4469D03*
X587766Y24773D03*
Y44773D03*
X583501Y800831D03*
X577903Y940907D03*
X581703D03*
X576003Y935107D03*
X581903Y954507D03*
X577303D03*
X595087Y53597D03*
X603282Y390223D03*
Y395179D03*
Y404396D03*
Y409352D03*
X595280Y402291D03*
Y397335D03*
X592880Y416465D03*
Y411509D03*
X603282Y418569D03*
Y423525D03*
X592880Y425682D03*
X603282Y432743D03*
Y437699D03*
X592880Y439855D03*
Y430638D03*
Y444811D03*
Y468609D03*
Y473565D03*
X603282Y489895D03*
X592880Y487738D03*
X603282Y480677D03*
Y475721D03*
X592880Y482782D03*
X603282Y494851D03*
X592880Y517699D03*
X603282Y519855D03*
X592880Y526916D03*
Y531872D03*
X603282Y524811D03*
Y538984D03*
Y534028D03*
X589603Y952907D03*
X615087Y53597D03*
X633248Y44884D03*
X640109Y103783D03*
X690073Y44662D03*
X697387Y53619D03*
X717387D03*
X723031Y440098D03*
Y437598D03*
Y435098D03*
Y432598D03*
Y430098D03*
X736242Y5374D03*
X735555Y24773D03*
Y44773D03*
X742471Y103783D03*
X755145Y3000D03*
X759029Y332017D03*
X775145Y3000D03*
X775584Y466528D03*
X775583Y471484D03*
Y480701D03*
Y485657D03*
Y515617D03*
Y510661D03*
Y524835D03*
Y529791D03*
Y560701D03*
Y565657D03*
Y579830D03*
Y574874D03*
Y589047D03*
Y594003D03*
Y603221D03*
Y608177D03*
X791129Y4469D03*
X792490Y24773D03*
Y44773D03*
X799811Y53597D03*
X785985Y473640D03*
Y487813D03*
Y478596D03*
Y492769D03*
Y517774D03*
Y522730D03*
Y531947D03*
Y536903D03*
Y572769D03*
Y567813D03*
Y581987D03*
Y586943D03*
Y601116D03*
Y596160D03*
Y615289D03*
Y610333D03*
X806318Y1401661D03*
X806874Y1447457D03*
X812474D03*
X806874Y1452587D03*
Y1457717D03*
X812474D03*
X815096Y1464387D03*
X812009Y1473432D03*
Y1470432D03*
X815096Y1467387D03*
X812096Y1479587D03*
Y1476587D03*
X815096Y1473387D03*
Y1479587D03*
Y1476587D03*
Y1470387D03*
X819811Y53597D03*
X829791Y839020D03*
X825721Y836666D03*
X823234Y867680D03*
X825774Y895553D03*
X816648Y1377608D03*
X817974Y1447457D03*
Y1452587D03*
Y1457717D03*
X818096Y1464387D03*
X821096D03*
X818096Y1473387D03*
X821096D03*
X824096D03*
X818096Y1479587D03*
X821096D03*
X824096D03*
X818096Y1476587D03*
X821096D03*
X824096D03*
X818096Y1467387D03*
Y1470387D03*
X821096D03*
Y1467387D03*
X824096D03*
Y1470387D03*
X838606Y5374D03*
X837919Y24773D03*
Y44773D03*
X844833Y103783D03*
X833185Y456309D03*
Y452309D03*
Y448309D03*
X850145Y3000D03*
X857973Y404867D03*
X862522Y400229D03*
X862566Y404867D03*
X857928Y400184D03*
X862020Y410899D03*
X862882Y468791D03*
Y465991D03*
X854882D03*
Y468791D03*
X861468Y491303D03*
X859071Y1447459D03*
X864671D03*
X859071Y1452589D03*
Y1457719D03*
X864671D03*
X864644Y1464759D03*
X861644D03*
X855644D03*
X858644D03*
Y1467759D03*
X855644Y1470759D03*
X858644D03*
X864644Y1467759D03*
Y1470759D03*
X861644Y1467759D03*
Y1470759D03*
X855644Y1467759D03*
Y1473759D03*
X858644D03*
X864644D03*
X861644D03*
X855644Y1476759D03*
X858644D03*
X864644D03*
X861644D03*
X872736Y383125D03*
X872318Y408589D03*
X866128Y417532D03*
X869342Y417399D03*
X880910Y471982D03*
Y469182D03*
Y466382D03*
X870882Y465991D03*
Y468791D03*
X878610Y747171D03*
X871294Y771809D03*
X871624Y1213314D03*
X874624D03*
X871624Y1221714D03*
Y1218914D03*
Y1216114D03*
X874624Y1221714D03*
Y1218914D03*
Y1216114D03*
X871624Y1224514D03*
X874624D03*
X870171Y1447459D03*
Y1452589D03*
Y1457719D03*
X867644Y1464759D03*
X870644D03*
X867644Y1467759D03*
X870644D03*
X867644Y1470759D03*
X870644D03*
X867644Y1473759D03*
X870644D03*
X867644Y1476759D03*
X870644D03*
X884736Y383125D03*
X893736D03*
X888736D03*
X891699Y420445D03*
Y423245D03*
X890903Y469182D03*
Y471982D03*
Y466382D03*
X896431Y534093D03*
X897118Y857891D03*
Y864189D03*
Y854742D03*
X893968Y864189D03*
Y857891D03*
Y854742D03*
X897118Y873638D03*
Y870488D03*
Y867338D03*
X893968Y870488D03*
Y873638D03*
Y867338D03*
X887669Y876787D03*
X888650Y1199622D03*
X893328Y1212887D03*
X912278Y343881D03*
X910779Y471380D03*
X903431Y534093D03*
X912462Y695770D03*
X912864Y848442D03*
Y845293D03*
Y842143D03*
X909714Y845293D03*
Y842143D03*
X900267Y864189D03*
X909714Y854742D03*
X906565Y857891D03*
X909714D03*
X906565Y864189D03*
X909714D03*
X906565Y854742D03*
X900267Y857891D03*
Y854742D03*
X912864Y851592D03*
Y857891D03*
Y854742D03*
X909714Y873638D03*
Y870488D03*
X906565Y873638D03*
Y870488D03*
Y867338D03*
X900267Y873638D03*
Y870488D03*
Y867338D03*
X909714D03*
X912171Y1447459D03*
X906671D03*
X901071D03*
X912171Y1457719D03*
Y1452589D03*
X906671Y1457719D03*
X901071D03*
Y1452589D03*
X908370Y1464583D03*
X905370D03*
X899370D03*
X902370D03*
X911370D03*
X905370Y1476583D03*
X908370D03*
X902370D03*
X899370D03*
X905370Y1473583D03*
X908370D03*
X902370D03*
X899370D03*
X902370Y1467583D03*
X899370Y1470583D03*
X902370D03*
X908370Y1467583D03*
Y1470583D03*
X905370Y1467583D03*
Y1470583D03*
X899370Y1467583D03*
X911370Y1476583D03*
Y1473583D03*
Y1467583D03*
Y1470583D03*
X930145Y3000D03*
X921847Y346622D03*
X927636Y452505D03*
X929050Y450316D03*
X928612Y835844D03*
X922313Y851592D03*
X929611Y858669D03*
X914370Y1464583D03*
Y1476583D03*
Y1473583D03*
Y1467583D03*
Y1470583D03*
X941129Y4469D03*
X942490Y24773D03*
Y44773D03*
X931620Y584417D03*
X931594Y599420D03*
X931647Y593271D03*
X931578Y590669D03*
X933810Y972433D03*
X935601Y1221714D03*
Y1218914D03*
Y1216114D03*
Y1213314D03*
X938601Y1221714D03*
Y1218914D03*
Y1216114D03*
Y1213314D03*
X935601Y1224514D03*
X938601D03*
X949811Y53597D03*
X956365Y641817D03*
X950865D03*
X950567Y927654D03*
X952627Y1199622D03*
X957305Y1212887D03*
X969811Y53597D03*
X976763Y307303D03*
X969623Y405614D03*
X963577Y426391D03*
X974406Y521804D03*
Y524304D03*
X970713Y531378D03*
Y528878D03*
X976962Y608311D03*
X980683Y628242D03*
X972278Y934429D03*
X988606Y5374D03*
X987919Y24773D03*
Y44773D03*
X994833Y103783D03*
X993132Y310942D03*
X993243Y321325D03*
X987055Y320273D03*
X993920Y335454D03*
X993420Y337954D03*
X992206Y478586D03*
Y481086D03*
Y483886D03*
X980544Y482134D03*
Y484634D03*
X992206Y476086D03*
X983989Y475946D03*
Y478446D03*
X982375Y522129D03*
Y527129D03*
Y524629D03*
Y529929D03*
X1007508Y3000D03*
X1004635Y300276D03*
X1008635D03*
X998667Y322239D03*
X1000420Y348954D03*
X1010119Y933822D03*
X1006619D03*
X1013683Y-44304D03*
Y-39348D03*
Y-29348D03*
Y-34304D03*
X1027508Y3000D03*
X1021895Y771974D03*
X1019519Y937922D03*
X1023319D03*
X1017619Y932122D03*
X1023519Y951522D03*
X1018919D03*
X1043492Y4469D03*
X1041496Y300276D03*
X1031354Y322905D03*
X1031219Y949922D03*
X1044853Y24773D03*
Y44773D03*
X1052174Y53597D03*
X1046674Y340031D03*
X1045966Y346808D03*
X1052367Y402291D03*
Y397335D03*
X1049967Y416465D03*
Y411509D03*
Y425682D03*
Y439855D03*
Y430638D03*
Y444811D03*
Y468609D03*
Y473565D03*
Y487738D03*
Y482782D03*
Y512743D03*
Y517699D03*
Y526916D03*
Y531872D03*
X1072174Y53597D03*
X1060369Y390223D03*
Y395179D03*
Y404396D03*
Y409352D03*
Y418569D03*
Y423525D03*
Y432743D03*
Y437699D03*
Y489895D03*
Y480677D03*
Y475721D03*
Y494851D03*
Y519855D03*
Y524811D03*
Y538984D03*
Y534028D03*
X1083683Y-78528D03*
Y-83484D03*
Y-73484D03*
Y-68528D03*
X1090280Y44773D03*
X1083483Y1523433D03*
X1097195Y103783D03*
X1147214Y44773D03*
X1154535Y53597D03*
X1174535D03*
X1176858Y306534D03*
X1180118Y430098D03*
Y440098D03*
Y437598D03*
Y435098D03*
Y432598D03*
X1193330Y5374D03*
X1192643Y24773D03*
Y44773D03*
X1199557Y103783D03*
X1192500Y322400D03*
X1199615Y950670D03*
X1201794Y985289D03*
X1212232Y3000D03*
X1221337Y332017D03*
X1232232Y3000D03*
X1232670Y466528D03*
Y471484D03*
Y480701D03*
Y485657D03*
Y515617D03*
Y510661D03*
Y524835D03*
Y529791D03*
Y565657D03*
Y560701D03*
Y579830D03*
Y589047D03*
Y574874D03*
Y603221D03*
Y594003D03*
Y608177D03*
X1248216Y4469D03*
X1249577Y24773D03*
Y44773D03*
X1243072Y473640D03*
Y487813D03*
Y478596D03*
Y492769D03*
Y522730D03*
Y517774D03*
Y536903D03*
Y531947D03*
Y567813D03*
Y572769D03*
Y586943D03*
Y581987D03*
Y601116D03*
Y596160D03*
Y610333D03*
Y615289D03*
X1256898Y53597D03*
X1266219Y374300D03*
X1268659Y377173D03*
X1276898Y53597D03*
X1275940Y392228D03*
X1271346Y392183D03*
X1275407Y402867D03*
X1271391Y396866D03*
X1275984D03*
X1282760Y409016D03*
X1278724Y409032D03*
X1272215Y442518D03*
Y439718D03*
X1282092Y449118D03*
Y446318D03*
X1283455Y468088D03*
Y465288D03*
X1300183Y-44434D03*
Y-29478D03*
Y-34434D03*
Y-39478D03*
X1302232Y3000D03*
X1295692Y5374D03*
X1303229Y23274D03*
X1295005Y24773D03*
X1297785Y30618D03*
X1295005Y44773D03*
X1301919Y103783D03*
X1303158Y371043D03*
X1299410Y370976D03*
X1291165Y395248D03*
X1290092Y449118D03*
Y446318D03*
X1299757Y450041D03*
Y452841D03*
Y455641D03*
X1290272Y458309D03*
Y454309D03*
Y462309D03*
X1310546Y409904D03*
Y407104D03*
X1309750Y455641D03*
Y450041D03*
Y452841D03*
X1311488Y479560D03*
X1309856Y899161D03*
X1305761D03*
X1313756D03*
X1322232Y3000D03*
X1320903Y370995D03*
X1333331Y370905D03*
X1329064Y370951D03*
X1329626Y455039D03*
X1340183Y-83484D03*
Y-78528D03*
Y-68528D03*
Y-73484D03*
X1342232Y3000D03*
X1338287Y370905D03*
X1347897Y433975D03*
X1346483Y436164D03*
X1362232Y3000D03*
X1382232D03*
X1373748Y397758D03*
X1375375Y428995D03*
X1398216Y4469D03*
X1399577Y24773D03*
Y44773D03*
X1397550Y390484D03*
X1387814Y397136D03*
X1389295Y408443D03*
X1386809Y414173D03*
X1388788Y428348D03*
X1406898Y53597D03*
X1416830Y407134D03*
X1411400Y398032D03*
X1413889Y415642D03*
X1413452Y641817D03*
X1407952D03*
X1426898Y53597D03*
X1431493Y521804D03*
X1427800Y528578D03*
X1431493Y524304D03*
X1427800Y531378D03*
X1422176Y1491198D03*
X1423806Y1524252D03*
X1445692Y5374D03*
X1445005Y24773D03*
Y44773D03*
X1440568Y369566D03*
X1449619Y363290D03*
X1438588Y380589D03*
X1437631Y482134D03*
Y484634D03*
X1449293Y476086D03*
X1441076Y475946D03*
Y478446D03*
X1449293Y478586D03*
Y481086D03*
Y483886D03*
X1439462Y522129D03*
Y529929D03*
Y527129D03*
Y524629D03*
X1434049Y608311D03*
X1437770Y628242D03*
X1464594Y3000D03*
X1462675Y14334D03*
X1451920Y103783D03*
X1455979Y391756D03*
X1458212Y403374D03*
X1473364Y410724D03*
X1472403Y417338D03*
X1469293Y428815D03*
X1484594Y3000D03*
X1498446Y912370D03*
X1497208Y909740D03*
X1500578Y4469D03*
X1501939Y24773D03*
Y44773D03*
X1509260Y53597D03*
X1509454Y402291D03*
Y397335D03*
X1507054Y416465D03*
Y411509D03*
Y425682D03*
Y439855D03*
Y430638D03*
Y444811D03*
Y468609D03*
Y473565D03*
Y487738D03*
Y482782D03*
Y517699D03*
Y512743D03*
Y526916D03*
Y531872D03*
X1507034Y888133D03*
X1507358Y909740D03*
X1507305Y912262D03*
X1501400Y966000D03*
X1529260Y53597D03*
X1517456Y390223D03*
Y395179D03*
Y404396D03*
Y409352D03*
Y418569D03*
Y423525D03*
Y432743D03*
Y437699D03*
Y489895D03*
Y480677D03*
Y475721D03*
Y494851D03*
Y519855D03*
Y538984D03*
Y524811D03*
Y534028D03*
X1516283Y912240D03*
X1519116D03*
X1523053Y912262D03*
X1525022Y957340D03*
X1547367Y44773D03*
X1554282Y103783D03*
X1594683Y-83484D03*
Y-78528D03*
Y-68528D03*
Y-73484D03*
X1584683Y-44564D03*
Y-29608D03*
Y-34564D03*
Y-39608D03*
X1604301Y44773D03*
X1611622Y53597D03*
X1631622D03*
X1637205Y440098D03*
Y437598D03*
Y435098D03*
Y432598D03*
Y430098D03*
X1650417Y5374D03*
X1649730Y24773D03*
Y44773D03*
X1656644Y103783D03*
X1669319Y3001D03*
X1673203Y332017D03*
X1689319Y3001D03*
X1689757Y466528D03*
Y471484D03*
Y480701D03*
Y485657D03*
Y515617D03*
Y510661D03*
Y524835D03*
Y529791D03*
Y565657D03*
Y560701D03*
Y589047D03*
Y574874D03*
Y579830D03*
Y603221D03*
Y594003D03*
Y608177D03*
X1705303Y4470D03*
X1706664Y24774D03*
Y44774D03*
X1700159Y473640D03*
Y487813D03*
Y478596D03*
Y492769D03*
Y517774D03*
Y522730D03*
Y536903D03*
Y531947D03*
Y572769D03*
Y567813D03*
Y586943D03*
Y581987D03*
Y601116D03*
Y596160D03*
Y610333D03*
Y615289D03*
X1713985Y53598D03*
X1725746Y377173D03*
X1723964Y370935D03*
X1733985Y53598D03*
X1733027Y392228D03*
X1728433Y392183D03*
X1739847Y409016D03*
X1735811Y409032D03*
X1732494Y402867D03*
X1728478Y396866D03*
X1733071D03*
X1729302Y439718D03*
Y442518D03*
X1739179Y449118D03*
Y446318D03*
X1740542Y468088D03*
Y465288D03*
X1752778Y5374D03*
X1752091Y24773D03*
Y44773D03*
X1756497Y370976D03*
X1748252Y395248D03*
X1756844Y450041D03*
Y452841D03*
Y455641D03*
X1747179Y449118D03*
Y446318D03*
X1747359Y454309D03*
Y458309D03*
Y462309D03*
X1765559Y3001D03*
X1759006Y103783D03*
X1760497Y371070D03*
X1767633Y409904D03*
Y407104D03*
X1766837Y450041D03*
Y452841D03*
Y455641D03*
X1768575Y479560D03*
X1773600Y888100D03*
X1773614Y895275D03*
X1773600Y902800D03*
X1786713Y455039D03*
X1788400Y888100D03*
X1781000Y888087D03*
X1788396Y895066D03*
X1788300Y902800D03*
X1780665Y902796D03*
X1781263Y964660D03*
X1784763D03*
X1779581Y1222200D03*
Y1219400D03*
Y1216600D03*
Y1213800D03*
X1782581Y1222200D03*
Y1219400D03*
Y1216600D03*
Y1213800D03*
X1779581Y1225000D03*
X1782581D03*
X1804984Y433975D03*
X1803570Y436164D03*
X1794163Y968760D03*
X1797963D03*
X1792263Y962960D03*
X1798163Y982360D03*
X1793563D03*
X1805863Y980760D03*
X1796607Y1200108D03*
X1801285Y1213373D03*
X1822983Y346053D03*
Y366053D03*
Y386053D03*
Y406053D03*
Y426053D03*
Y446053D03*
Y466053D03*
Y486053D03*
Y506053D03*
Y526053D03*
Y546053D03*
Y566053D03*
Y586053D03*
Y606053D03*
Y626053D03*
Y646053D03*
Y666053D03*
Y686053D03*
Y706053D03*
Y726053D03*
Y746053D03*
Y766053D03*
Y786053D03*
Y806053D03*
Y826053D03*
Y846053D03*
Y866053D03*
Y886053D03*
Y906053D03*
Y926053D03*
Y946053D03*
X1825559Y3001D03*
X1836543Y4470D03*
X1837904Y24774D03*
Y44774D03*
Y64774D03*
Y84774D03*
Y104774D03*
Y124774D03*
Y144774D03*
Y164774D03*
Y184774D03*
Y204774D03*
Y224774D03*
Y244774D03*
Y264774D03*
Y284774D03*
Y304774D03*
X1837728Y324733D03*
X1830094Y333210D03*
X1830472Y960970D03*
X1837937Y973244D03*
Y993244D03*
Y1013244D03*
Y1033244D03*
Y1053244D03*
Y1073244D03*
X1824733Y1102830D03*
X1837937Y1093244D03*
X1825832Y1097589D03*
X1837937Y1113244D03*
Y1133244D03*
Y1153244D03*
Y1173244D03*
Y1193244D03*
Y1213244D03*
Y1253244D03*
Y1273244D03*
Y1293244D03*
Y1313244D03*
Y1333244D03*
Y1353244D03*
Y1373244D03*
Y1393244D03*
Y1433244D03*
Y1453244D03*
Y1473244D03*
Y1493244D03*
Y1513244D03*
Y1533244D03*
Y1553244D03*
Y1573244D03*
G54D14*
X20408Y51296D03*
Y55296D03*
X9057Y138939D03*
X19184Y144728D03*
X15184D03*
X15520Y195176D03*
X18320D03*
X13020D03*
X10520D03*
X12880Y203393D03*
X10380D03*
X19068Y206838D03*
X16568D03*
X13606Y1476707D03*
X19365Y1494298D03*
X24316Y67527D03*
Y63527D03*
Y59527D03*
X23184Y144728D03*
X35650Y487982D03*
Y478982D03*
Y483982D03*
Y499982D03*
X25819Y531726D03*
Y536726D03*
Y552726D03*
Y540726D03*
X30410Y1218497D03*
Y1220997D03*
Y1234797D03*
Y1232297D03*
Y1227897D03*
Y1225397D03*
Y1241697D03*
Y1239197D03*
X25674Y1486291D03*
X32195Y1511279D03*
X32079Y1521641D03*
X31237Y1532096D03*
X46240Y109410D03*
X45988Y102323D03*
X46240Y116496D03*
X46931Y130670D03*
X49236Y121658D03*
X46932Y137756D03*
X49839Y546830D03*
X44195Y1511279D03*
X39237Y1532096D03*
X64098Y102323D03*
Y109410D03*
Y116496D03*
Y123583D03*
Y130670D03*
Y137756D03*
X69139Y236611D03*
X68841Y248891D03*
X66224Y473045D03*
X58224D03*
X53643Y472905D03*
X59670Y500086D03*
X64495Y527449D03*
X61695D03*
X60554Y1612002D03*
X66291Y1633801D03*
X74139Y236611D03*
X71639D03*
X71341Y248891D03*
X73841D03*
X74326Y480705D03*
X71995Y532749D03*
X74795D03*
X74291Y1633801D03*
X86291D03*
X119582Y102249D03*
X111582D03*
X115582D03*
X115382Y195176D03*
X112882D03*
X117882D03*
X115242Y203393D03*
X112742D03*
X120682Y195176D03*
X118930Y206838D03*
X121430D03*
X148602Y109410D03*
Y116496D03*
X148350Y102323D03*
X148774Y124576D03*
X149827Y130670D03*
X149822Y137756D03*
X166460Y116496D03*
Y109410D03*
Y102323D03*
Y123583D03*
Y130670D03*
Y137756D03*
X174001Y236611D03*
X176501D03*
X171501D03*
X176203Y248891D03*
X173703D03*
X171203D03*
X185169Y389154D03*
Y396240D03*
X186448Y404911D03*
X186589Y426299D03*
X185402Y412571D03*
X186900Y445847D03*
X185169Y467539D03*
Y474626D03*
X185430Y480828D03*
X187380Y498834D03*
X185169Y518760D03*
Y511673D03*
Y525847D03*
X191125Y602400D03*
Y598400D03*
Y594400D03*
Y606400D03*
Y614400D03*
X203591Y91951D03*
X213944Y102249D03*
X215244Y195176D03*
X215104Y203393D03*
X203280Y389154D03*
Y396240D03*
Y403327D03*
Y410413D03*
Y417500D03*
Y424586D03*
Y431673D03*
Y438760D03*
Y445847D03*
Y467539D03*
Y474626D03*
Y488799D03*
Y481713D03*
Y495886D03*
Y511673D03*
Y518760D03*
Y525847D03*
Y532933D03*
Y540020D03*
Y547106D03*
Y554193D03*
Y602205D03*
Y595118D03*
X221944Y102249D03*
X217944D03*
X220244Y195176D03*
X217744D03*
X223044D03*
X223792Y206838D03*
X221292D03*
X217604Y203393D03*
X228267Y392718D03*
Y408718D03*
Y400718D03*
Y404718D03*
Y412718D03*
X250964Y109410D03*
X250712Y102323D03*
X250964Y116496D03*
X251136Y124576D03*
X252189Y130670D03*
X252184Y137756D03*
X268822Y116496D03*
Y109410D03*
Y102323D03*
Y130670D03*
Y123583D03*
Y137756D03*
X276363Y236611D03*
X278863D03*
X273863D03*
X276065Y248891D03*
X273565D03*
X278565D03*
X274205Y466027D03*
X274347Y475262D03*
Y489435D03*
Y482666D03*
X274163Y495088D03*
X274205Y509626D03*
X274820Y522134D03*
X274898Y514608D03*
X275463Y529136D03*
X275302Y535677D03*
X274586Y565574D03*
X274205Y559665D03*
X274233Y574338D03*
X274332Y616358D03*
X292500Y410394D03*
Y403307D03*
X284295Y430760D03*
X284316Y433570D03*
X284132Y437072D03*
X284173Y439963D03*
X284417Y443180D03*
X284437Y454744D03*
X284379Y452018D03*
X292316Y458406D03*
Y465492D03*
Y472579D03*
Y479665D03*
Y486752D03*
Y493839D03*
Y523799D03*
Y516713D03*
Y509626D03*
Y537973D03*
Y530886D03*
Y559665D03*
Y566752D03*
Y573839D03*
Y588012D03*
Y580925D03*
Y595099D03*
Y602185D03*
Y616358D03*
Y609272D03*
X324306Y102249D03*
X320306D03*
X316306D03*
X322606Y195176D03*
X325406D03*
X320106D03*
X317606D03*
X323654Y206838D03*
X319966Y203393D03*
X317466D03*
X326154Y206838D03*
X319857Y321649D03*
X324291Y556775D03*
X353074Y102323D03*
X353326Y109410D03*
Y116496D03*
X353498Y124576D03*
X354551Y130670D03*
X354546Y137756D03*
X371184Y116496D03*
Y109410D03*
Y102323D03*
Y130670D03*
Y123583D03*
Y137756D03*
X376225Y236611D03*
X375927Y248891D03*
X373101Y779608D03*
X376300Y779800D03*
X370214Y959812D03*
Y967812D03*
X381225Y236611D03*
X378725D03*
X378427Y248891D03*
X380927D03*
X379800Y778000D03*
X387692Y790056D03*
X393547D03*
X386614Y868286D03*
X385512Y955356D03*
X390150Y955312D03*
Y959905D03*
X385467Y959950D03*
X409268Y408240D03*
X409386Y420393D03*
X400900Y755400D03*
Y770100D03*
X407193Y883566D03*
X396182Y955858D03*
X402682Y948536D03*
X402815Y951750D03*
X404004Y1198321D03*
Y1200821D03*
X407469Y1495035D03*
X407854Y1492118D03*
X406377Y1499142D03*
X411768Y408240D03*
X414268D03*
X411847Y424240D03*
X414386Y420393D03*
X411886D03*
X411847Y426740D03*
X415700Y755400D03*
Y770200D03*
X422430Y834800D03*
X422379Y867229D03*
X420661Y1119422D03*
X423141Y1113822D03*
Y1119422D03*
X418181Y1113822D03*
Y1119422D03*
X420661Y1113822D03*
X417469Y1200821D03*
Y1198321D03*
X439804Y536682D03*
Y539182D03*
X430934Y1200821D03*
Y1198321D03*
X430657Y1563562D03*
X446179Y447101D03*
X448726Y653288D03*
Y646480D03*
Y648980D03*
Y655788D03*
X450244Y1090268D03*
Y1093068D03*
X455269Y1119422D03*
X450309Y1113822D03*
Y1119422D03*
X452789Y1113822D03*
Y1119422D03*
X455269Y1113822D03*
X474307Y102249D03*
X470307D03*
X466307D03*
X470107Y195176D03*
X467607D03*
X472607D03*
X475407D03*
X473655Y206838D03*
X467467Y203393D03*
X469967D03*
X463104Y536582D03*
Y539082D03*
X476155Y206838D03*
X492736Y478982D03*
X482905Y531726D03*
X482737Y537215D03*
X482905Y552726D03*
Y540726D03*
X488728Y1119422D03*
X483768Y1113822D03*
X486248D03*
Y1119422D03*
X483768D03*
X488728Y1113822D03*
X477206Y1198321D03*
X490671D03*
Y1200821D03*
X477206D03*
X503075Y102323D03*
X503327Y109410D03*
Y116496D03*
X506653Y121652D03*
X504552Y130670D03*
X504547Y137756D03*
X493485Y439903D03*
X492736Y487982D03*
Y483982D03*
Y499982D03*
X506925Y546830D03*
X504136Y1198321D03*
Y1200821D03*
X521185Y116496D03*
Y109410D03*
Y102323D03*
Y130670D03*
Y123583D03*
Y137756D03*
X508729Y469905D03*
X521310Y470045D03*
X513310D03*
X516756Y500086D03*
X518781Y527449D03*
X521581D03*
X518812Y665867D03*
X515831Y1090568D03*
Y1093068D03*
X518376Y1113822D03*
Y1119422D03*
X520856Y1113822D03*
Y1119422D03*
X515896Y1113822D03*
Y1119422D03*
X526226Y236611D03*
X531226D03*
X528726D03*
X528428Y248891D03*
X530928D03*
X525928D03*
X531412Y480705D03*
X528612D03*
X529481Y532849D03*
X532281D03*
X533486Y664052D03*
X538442D03*
X524941Y661387D03*
X530796D03*
X572669Y102249D03*
X568669D03*
X572469Y195176D03*
X572329Y203393D03*
X567559Y812850D03*
X576669Y102249D03*
X574969Y195176D03*
X577769D03*
X578517Y206838D03*
X576017D03*
X605437Y102323D03*
X605689Y109410D03*
Y116496D03*
X605861Y124576D03*
X606914Y130670D03*
X606909Y137756D03*
X623547Y109410D03*
Y116496D03*
Y102323D03*
Y123583D03*
Y130670D03*
Y137756D03*
X633588Y236611D03*
X631088D03*
X628588D03*
X630790Y248891D03*
X633290D03*
X628290D03*
X642255Y389154D03*
Y396240D03*
X643534Y404911D03*
X642488Y412571D03*
X643675Y426299D03*
X643986Y445847D03*
X642255Y467539D03*
Y474626D03*
X642516Y480828D03*
X644466Y498834D03*
X642255Y518760D03*
Y511673D03*
Y525847D03*
X648211Y602400D03*
Y598400D03*
Y594400D03*
Y606400D03*
Y614400D03*
X660366Y389154D03*
Y403327D03*
Y410413D03*
Y396240D03*
Y417500D03*
Y424586D03*
Y431673D03*
Y438760D03*
Y445847D03*
Y467539D03*
Y474626D03*
Y488799D03*
Y481713D03*
Y495886D03*
Y511673D03*
Y518760D03*
Y525847D03*
Y532933D03*
Y540020D03*
Y554193D03*
Y547106D03*
Y602205D03*
Y595118D03*
X679031Y102249D03*
X672331Y195176D03*
X674831D03*
X680131D03*
X672191Y203393D03*
X674691D03*
X678379Y206838D03*
X680879D03*
X685353Y392718D03*
Y408718D03*
Y400718D03*
Y404718D03*
Y412718D03*
X707799Y102323D03*
X708051Y109410D03*
Y116496D03*
X708223Y124576D03*
X709276Y130670D03*
X709271Y137756D03*
X725909Y102323D03*
Y116496D03*
Y109410D03*
Y130670D03*
Y123583D03*
Y137756D03*
X733450Y236611D03*
X730950D03*
X733152Y248891D03*
X730652D03*
X731291Y466027D03*
X731433Y475262D03*
Y489435D03*
Y482666D03*
X731249Y495088D03*
X731984Y514608D03*
X731906Y522134D03*
X731291Y509626D03*
X732549Y529136D03*
X732388Y535677D03*
X731291Y559665D03*
X731672Y565574D03*
X731319Y574338D03*
X731418Y616358D03*
X735950Y236611D03*
X735652Y248891D03*
X749586Y410394D03*
Y403307D03*
X741259Y439963D03*
X741381Y430760D03*
X741402Y433570D03*
X741218Y437072D03*
X741503Y443180D03*
X741523Y454744D03*
X741465Y452018D03*
X749402Y458406D03*
Y465492D03*
Y472579D03*
Y479665D03*
Y486752D03*
Y493839D03*
Y523799D03*
Y516713D03*
Y509626D03*
Y537973D03*
Y530886D03*
Y559665D03*
Y566752D03*
Y573839D03*
Y588012D03*
Y580925D03*
Y602185D03*
Y595099D03*
Y609272D03*
Y616358D03*
X751140Y1581335D03*
X740640Y1586885D03*
X748924Y1617709D03*
X735878Y1617010D03*
X763040Y91951D03*
X781393Y102249D03*
X777393D03*
X773393D03*
X779693Y195176D03*
X777193D03*
X782493D03*
X774693D03*
X780741Y206838D03*
X783241D03*
X777053Y203393D03*
X774553D03*
X776943Y321649D03*
X778985Y442498D03*
X778881Y446510D03*
X779029Y450510D03*
X777033Y1595215D03*
X781545Y1602835D03*
X774658Y1601012D03*
X792564Y406410D03*
X784586Y421000D03*
Y418500D03*
Y413500D03*
Y416000D03*
X784665Y564843D03*
X787447Y1593586D03*
X791610Y1593708D03*
X810161Y102323D03*
X810413Y109410D03*
Y116496D03*
X810585Y124576D03*
X811638Y130670D03*
X811633Y137756D03*
X828271Y116496D03*
Y109410D03*
Y102323D03*
Y130670D03*
Y123583D03*
Y137756D03*
X835812Y236611D03*
X838312D03*
X833312D03*
X833014Y248891D03*
X838014D03*
X835514D03*
X867093Y570703D03*
Y582828D03*
Y558703D03*
Y562703D03*
Y566703D03*
Y578703D03*
X872440Y1230083D03*
Y1227583D03*
Y1234483D03*
Y1236983D03*
Y1243883D03*
Y1241383D03*
Y1248283D03*
Y1250783D03*
X889436Y715970D03*
X905094Y424581D03*
X902594D03*
X907594D03*
X905212Y436734D03*
X902712D03*
X907712D03*
X907173Y440581D03*
Y443081D03*
X909024Y578394D03*
Y574394D03*
X909714Y838994D03*
X931393Y102249D03*
X923393D03*
X927393D03*
X925359Y180347D03*
X927859D03*
X925219Y188564D03*
X927719D03*
X919606Y231000D03*
X919577Y245669D03*
Y233858D03*
X919682Y236921D03*
X919577Y259843D03*
Y255118D03*
X919729Y274580D03*
X930359Y180347D03*
X933159D03*
X931407Y192009D03*
X933907D03*
X941505Y463442D03*
X939827Y531104D03*
X939992Y536726D03*
Y540726D03*
Y552726D03*
X936417Y1234483D03*
Y1236983D03*
Y1230083D03*
Y1227583D03*
Y1243883D03*
Y1241383D03*
Y1248283D03*
Y1250783D03*
X956460Y-35982D03*
X953207Y-35996D03*
X956445Y-38497D03*
X953192Y-38511D03*
X950167Y-37191D03*
X960161Y102323D03*
X960413Y109410D03*
Y116496D03*
X961638Y130670D03*
X961633Y137756D03*
X950315Y464851D03*
X949823Y487982D03*
X949876Y478486D03*
X949823Y483982D03*
Y499982D03*
X978036Y-77691D03*
X978051Y-75176D03*
X975011Y-76371D03*
X978271Y109410D03*
Y102323D03*
Y116496D03*
Y130670D03*
Y123583D03*
X963360Y121459D03*
X978271Y137756D03*
X977150Y328472D03*
Y335472D03*
X967816Y472905D03*
X972397Y472954D03*
X973843Y500086D03*
X978668Y527449D03*
X975868D03*
X964012Y546830D03*
X978857Y1360945D03*
X981289Y-77677D03*
X981304Y-75162D03*
X985812Y236611D03*
X988312D03*
X983312D03*
X983014Y248891D03*
X988014D03*
X985514D03*
X980397Y473045D03*
X985699Y480705D03*
X988499D03*
X989068Y532949D03*
X986268D03*
X981857Y1360945D03*
X978944Y1413859D03*
X981944D03*
X1007611Y1561247D03*
Y1558247D03*
Y1555247D03*
Y1552247D03*
X1004611Y1561247D03*
Y1558247D03*
Y1555247D03*
Y1552247D03*
X1015402Y91951D03*
X1025755Y102249D03*
X1027055Y195176D03*
X1033755Y102249D03*
X1029755D03*
X1032055Y195176D03*
X1029555D03*
X1034855D03*
X1033103Y206838D03*
X1035603D03*
X1029415Y203393D03*
X1062523Y102323D03*
X1062775Y109410D03*
Y116496D03*
X1062947Y124576D03*
X1064000Y130670D03*
X1063995Y137756D03*
X1080633Y102323D03*
Y116496D03*
Y109410D03*
Y130670D03*
Y123583D03*
Y137756D03*
X1085674Y236611D03*
X1088174D03*
X1090674D03*
X1090376Y248891D03*
X1087876D03*
X1085376D03*
X1077855Y327478D03*
X1077252Y323521D03*
Y318565D03*
X1077855Y332434D03*
X1099342Y389154D03*
Y396240D03*
X1100621Y404911D03*
X1099575Y412571D03*
X1100762Y426299D03*
X1101073Y445847D03*
X1099342Y467539D03*
Y474626D03*
X1099603Y480828D03*
X1101553Y498834D03*
X1099342Y518760D03*
Y511673D03*
Y525847D03*
X1105298Y598400D03*
Y602400D03*
Y594400D03*
Y614400D03*
Y606400D03*
X1117764Y91951D03*
X1117453Y389154D03*
Y396240D03*
Y403327D03*
Y410413D03*
Y417500D03*
Y424586D03*
Y431673D03*
Y438760D03*
Y445847D03*
Y467539D03*
Y474626D03*
Y488799D03*
Y481713D03*
Y495886D03*
Y511673D03*
Y518760D03*
Y525847D03*
Y532933D03*
Y540020D03*
Y554193D03*
Y547106D03*
Y602205D03*
Y595118D03*
X1136117Y102249D03*
X1132117D03*
X1128117D03*
X1134417Y195176D03*
X1131917D03*
X1137217D03*
X1129417D03*
X1137965Y206838D03*
X1131777Y203393D03*
X1135465Y206838D03*
X1142440Y404718D03*
Y412718D03*
X1125287Y592897D03*
X1142440Y392718D03*
Y400718D03*
Y408718D03*
X1164885Y102323D03*
X1165137Y109410D03*
Y116496D03*
X1165309Y124576D03*
X1166362Y130670D03*
X1166357Y137756D03*
X1182995Y116496D03*
Y109410D03*
Y102323D03*
Y130670D03*
Y123583D03*
Y137756D03*
X1188036Y236611D03*
X1187738Y248891D03*
X1188378Y466027D03*
X1188520Y475262D03*
Y489435D03*
Y482666D03*
X1188336Y495088D03*
X1189071Y514608D03*
X1188993Y522134D03*
X1188378Y509626D03*
X1189475Y535677D03*
X1189636Y529136D03*
X1188378Y559665D03*
X1188759Y565574D03*
X1188406Y574338D03*
X1188505Y616358D03*
X1190536Y236611D03*
X1193036D03*
X1192738Y248891D03*
X1190238D03*
X1198468Y430760D03*
X1198489Y433570D03*
X1198305Y437072D03*
X1198346Y439963D03*
X1198552Y452018D03*
X1198590Y443180D03*
X1198610Y454744D03*
X1220126Y91951D03*
X1206673Y410394D03*
Y403307D03*
X1206489Y458406D03*
Y465492D03*
Y472579D03*
Y479665D03*
Y486752D03*
Y493839D03*
Y523799D03*
Y516713D03*
Y509626D03*
Y537973D03*
Y530886D03*
Y566752D03*
Y559665D03*
Y580925D03*
Y588012D03*
Y573839D03*
Y602185D03*
Y595099D03*
Y616358D03*
Y609272D03*
X1231336Y-87691D03*
X1234589Y-87777D03*
X1231351Y-85176D03*
X1234604Y-85262D03*
X1228311Y-86371D03*
X1236692Y-48727D03*
X1236707Y-46212D03*
X1233667Y-47421D03*
X1238479Y102249D03*
X1230479D03*
X1234479D03*
X1236779Y195176D03*
X1234279D03*
X1239579D03*
X1231779D03*
X1234139Y203393D03*
X1231639D03*
X1237827Y206838D03*
X1234100Y322924D03*
X1239945Y-48727D03*
X1239960Y-46212D03*
X1240327Y206838D03*
X1241752Y564843D03*
X1267499Y116496D03*
X1267247Y102323D03*
X1267499Y109410D03*
X1267671Y124576D03*
X1268724Y130670D03*
X1268719Y137756D03*
X1259500Y330000D03*
X1285357Y116496D03*
Y109410D03*
Y102323D03*
Y123583D03*
Y130670D03*
Y137756D03*
X1281834Y374839D03*
X1290398Y236611D03*
X1295398D03*
X1292898D03*
X1290100Y248891D03*
X1292600D03*
X1295100D03*
X1301500Y329000D03*
X1292731Y331820D03*
X1300400Y339619D03*
Y344575D03*
X1290066Y804246D03*
X1319000Y566500D03*
Y582500D03*
Y613000D03*
Y629000D03*
Y657500D03*
Y673500D03*
Y704500D03*
Y720500D03*
X1305412Y799061D03*
X1318178Y1198321D03*
Y1200821D03*
X1325941Y408240D03*
X1328441D03*
X1323441D03*
X1326059Y420393D03*
X1326020Y424240D03*
X1323559Y420393D03*
X1328559D03*
X1326020Y426740D03*
X1335802Y896011D03*
X1332355Y1113822D03*
Y1119422D03*
X1334835Y1113822D03*
Y1119422D03*
X1331643Y1200821D03*
Y1198321D03*
X1344768Y769675D03*
X1337315Y1113822D03*
Y1119422D03*
X1345108Y1200821D03*
Y1198321D03*
X1361039Y327099D03*
Y332055D03*
X1364039Y334973D03*
Y339929D03*
X1361039Y342847D03*
X1364039Y350721D03*
X1361039Y347803D03*
X1364039Y355677D03*
X1360352Y447101D03*
X1364148Y896011D03*
X1364418Y1090568D03*
Y1093068D03*
X1366963Y1119422D03*
Y1113822D03*
X1364483Y1119422D03*
Y1113822D03*
X1380480Y102249D03*
X1384480D03*
X1384280Y195176D03*
X1381780D03*
X1384140Y203393D03*
X1381640D03*
X1384253Y346826D03*
X1384447Y356871D03*
X1384174Y362641D03*
X1379896Y870814D03*
Y883413D03*
X1383046Y899161D03*
X1369443Y1119422D03*
Y1113822D03*
X1388480Y102249D03*
X1389580Y195176D03*
X1386780D03*
X1390328Y206838D03*
X1387828D03*
X1385943Y323222D03*
X1385971Y327688D03*
X1386143Y331982D03*
X1386057Y341200D03*
X1385971Y336791D03*
X1386286Y350218D03*
X1397079Y531726D03*
Y536726D03*
Y552726D03*
Y540726D03*
X1397942Y1119422D03*
X1400422D03*
Y1113822D03*
X1397942D03*
X1391380Y1200821D03*
Y1198321D03*
X1417248Y102323D03*
X1416347Y384373D03*
X1406910Y487982D03*
Y478982D03*
Y483982D03*
Y499982D03*
X1410000Y689000D03*
Y705000D03*
Y733000D03*
Y749000D03*
X1402902Y1119422D03*
Y1113822D03*
X1404845Y1198321D03*
Y1200821D03*
X1404239Y1547755D03*
X1403747Y1570433D03*
X1417500Y109410D03*
Y116496D03*
X1421700Y122900D03*
X1418725Y130670D03*
X1418720Y137756D03*
X1427484Y470045D03*
X1422903Y469905D03*
X1430930Y500086D03*
X1432955Y527449D03*
X1421099Y546830D03*
X1427000Y774500D03*
Y790500D03*
Y818500D03*
Y834500D03*
X1430005Y1090568D03*
Y1093068D03*
X1432550Y1119422D03*
Y1113822D03*
X1430070Y1119422D03*
Y1113822D03*
X1418310Y1198321D03*
Y1200821D03*
X1435358Y116496D03*
Y109410D03*
Y102323D03*
Y130670D03*
Y123583D03*
Y137756D03*
X1440399Y236611D03*
X1442899D03*
X1445399D03*
X1440101Y248891D03*
X1442601D03*
X1445101D03*
X1435484Y470045D03*
X1442786Y480705D03*
X1445586D03*
X1435755Y527449D03*
X1443555Y532949D03*
X1446355D03*
X1435030Y1119422D03*
Y1113822D03*
X1437293Y1546125D03*
X1436801Y1568803D03*
X1451215Y323193D03*
X1451330Y327588D03*
X1451272Y340971D03*
X1451344Y336620D03*
X1451300Y332225D03*
X1451387Y345609D03*
X1451186Y350447D03*
X1472489Y91951D03*
X1479500Y706500D03*
Y750500D03*
X1487836Y-87777D03*
X1491089D03*
X1487851Y-85262D03*
X1491104D03*
X1484811Y-86371D03*
X1490842Y102249D03*
X1486842D03*
X1482842D03*
X1486642Y195176D03*
X1489142D03*
X1484142D03*
X1491942D03*
X1492690Y206838D03*
X1490190D03*
X1484002Y203393D03*
X1486502D03*
X1484796Y320359D03*
X1484968Y325025D03*
X1484876Y329377D03*
X1488255Y342921D03*
X1484682Y338394D03*
X1497760Y336543D03*
X1487926Y347387D03*
X1496500Y792000D03*
Y836000D03*
X1500480Y295727D03*
X1523192Y-48857D03*
X1526445D03*
X1523207Y-46342D03*
X1526460D03*
X1520167Y-47451D03*
X1519610Y102323D03*
X1519862Y109410D03*
Y116496D03*
X1520034Y124576D03*
X1521087Y130670D03*
X1521082Y137756D03*
X1527876Y939439D03*
X1537720Y116496D03*
Y109410D03*
Y102323D03*
Y130670D03*
Y123583D03*
Y137756D03*
X1542761Y236611D03*
X1545261D03*
X1542463Y248891D03*
X1544963D03*
X1541534Y322850D03*
X1547761Y236611D03*
X1547463Y248891D03*
X1547972Y304906D03*
X1556151Y318596D03*
X1556294Y327814D03*
X1556437Y332022D03*
X1556380Y336917D03*
X1556498Y340958D03*
X1556353Y345636D03*
X1556429Y389154D03*
Y396240D03*
X1557708Y404911D03*
X1556662Y412571D03*
X1557849Y426299D03*
X1558160Y445847D03*
X1556429Y467539D03*
Y474626D03*
X1556690Y480828D03*
X1558640Y498834D03*
X1556429Y518760D03*
Y511673D03*
Y525847D03*
X1562385Y598400D03*
Y602400D03*
Y594400D03*
Y614400D03*
Y606400D03*
X1574851Y91951D03*
X1574845Y338843D03*
X1574540Y389154D03*
Y396240D03*
Y403327D03*
Y410413D03*
Y417500D03*
Y424586D03*
Y438760D03*
Y431673D03*
Y445847D03*
Y467539D03*
Y474626D03*
Y488799D03*
Y481713D03*
Y495886D03*
Y511673D03*
Y518760D03*
Y540020D03*
Y525847D03*
Y532933D03*
Y547106D03*
Y554193D03*
Y602205D03*
Y595118D03*
X1593204Y102249D03*
X1585204D03*
X1589204D03*
X1586504Y195176D03*
X1594304D03*
X1589004D03*
X1591504D03*
X1586364Y203393D03*
X1588864D03*
X1595052Y206838D03*
X1592552D03*
X1593290Y339876D03*
X1597006Y290417D03*
X1599527Y392718D03*
Y408718D03*
Y400718D03*
Y404718D03*
Y412718D03*
X1621972Y102323D03*
X1622224Y109410D03*
Y116496D03*
X1622396Y124576D03*
X1623449Y130670D03*
X1623444Y137756D03*
X1640082Y116496D03*
Y109410D03*
Y102323D03*
Y130670D03*
Y123583D03*
Y137756D03*
X1644825Y248891D03*
X1632230Y330400D03*
X1645123Y236611D03*
X1650123D03*
X1647623D03*
X1647325Y248891D03*
X1649825D03*
X1655555Y430760D03*
X1655576Y433570D03*
X1655392Y437072D03*
X1655433Y439963D03*
X1655677Y443180D03*
X1655697Y454744D03*
X1655639Y452018D03*
X1645465Y466027D03*
X1645607Y475262D03*
Y489435D03*
Y482666D03*
X1645423Y495088D03*
X1646158Y514608D03*
X1646080Y522134D03*
X1645465Y509626D03*
X1646562Y535677D03*
X1646723Y529136D03*
X1645465Y559665D03*
X1645846Y565574D03*
X1645493Y574338D03*
X1645592Y616358D03*
X1677213Y91951D03*
X1663760Y410394D03*
Y403307D03*
X1663576Y458406D03*
Y465492D03*
Y472579D03*
Y479665D03*
Y486752D03*
Y493839D03*
Y523799D03*
Y516713D03*
Y509626D03*
Y537973D03*
Y530886D03*
Y559665D03*
Y566752D03*
Y580925D03*
Y588012D03*
Y573839D03*
Y602185D03*
Y595099D03*
Y616358D03*
Y609272D03*
X1695566Y102249D03*
X1687566D03*
X1691566D03*
X1691366Y195176D03*
X1688866D03*
X1691226Y203393D03*
X1688726D03*
X1691117Y321649D03*
X1696666Y195176D03*
X1693866D03*
X1697414Y206838D03*
X1694914D03*
X1698839Y564843D03*
X1724334Y102323D03*
X1724586Y109410D03*
Y116496D03*
X1724758Y124576D03*
X1725811Y130670D03*
X1725806Y137756D03*
X1715705Y328692D03*
X1712734Y340534D03*
X1742336Y-87777D03*
X1739311Y-86371D03*
X1734826Y376499D03*
X1745589Y-87777D03*
X1742351Y-85262D03*
X1745604D03*
X1742444Y102323D03*
Y116496D03*
Y109410D03*
Y130670D03*
Y123583D03*
Y137756D03*
X1752485Y236611D03*
X1749985D03*
X1747485D03*
X1747187Y248891D03*
X1749687D03*
X1752187D03*
X1747561Y385161D03*
X1758583Y1581027D03*
X1750685Y1618504D03*
X1756422Y1640303D03*
X1770680Y926322D03*
X1763818Y926241D03*
X1765294Y1575434D03*
X1759092Y1588137D03*
X1767142Y1588219D03*
X1764422Y1640303D03*
X1779575Y91951D03*
X1790533Y303750D03*
X1783028Y408240D03*
X1785528D03*
X1780528D03*
X1783107Y424240D03*
X1780646Y420393D03*
X1785646D03*
X1783146D03*
X1783107Y426740D03*
X1780397Y1237469D03*
Y1230569D03*
Y1228069D03*
Y1234969D03*
Y1241869D03*
Y1244369D03*
Y1248769D03*
Y1251269D03*
X1776422Y1640303D03*
X1804667Y-47581D03*
X1804993Y297591D03*
X1807692Y-49001D03*
X1810945Y-48987D03*
X1807707Y-46486D03*
X1810960Y-46472D03*
X1817439Y447101D03*
G54D30*
X106586Y1204932D03*
X563673D03*
X1020434Y1205579D03*
X1477846Y1204932D03*
G54D36*
X190325Y368760D03*
Y455492D03*
Y503760D03*
Y583957D03*
Y636752D03*
X647411Y368760D03*
Y455492D03*
Y503760D03*
Y583957D03*
Y636752D03*
X1104498Y368760D03*
Y455492D03*
Y503760D03*
Y583957D03*
Y636752D03*
X1561585Y368760D03*
Y455492D03*
Y503760D03*
Y583957D03*
Y636752D03*
G54D40*
X515573Y692515D03*
X518299Y692384D03*
X520799D03*
X529493Y692443D03*
Y697443D03*
Y699943D03*
X529501Y702622D03*
X526993Y692443D03*
X529493Y694943D03*
X524493Y692443D03*
X1809078Y2165771D03*
X1806706Y2180760D03*
X1812366Y2063809D03*
X1822066Y2054109D03*
X1812366D03*
X1813087Y2087512D03*
X1825427Y2104853D03*
X1817378Y2165771D03*
X1815006Y2180760D03*
X1841295Y2065122D03*
X1832995D03*
X1833649Y2057507D03*
X1830872Y2083503D03*
X1840875Y2083215D03*
X1837649Y2072324D03*
X1829349D03*
X1833727Y2104853D03*
X1835862Y2121040D03*
X1833506Y2185252D03*
X1852032Y2052576D03*
X1854559Y2077931D03*
X1851762Y2121040D03*
X1854796Y2170548D03*
X1846496D03*
X1855978Y2185118D03*
X1847678D03*
X1859032Y2052576D03*
X1870505Y2064156D03*
X1860338Y2071384D03*
X1874505Y2078973D03*
X1860234Y2157701D03*
X1867072Y2174962D03*
X1864547Y2185020D03*
X1890039Y2066092D03*
X1878805Y2064156D03*
X1886128Y2075919D03*
X1882805Y2078973D03*
X1876497Y2070684D03*
X1884535Y2155415D03*
X1882972Y2174962D03*
X1882111Y2179074D03*
X1874932Y2180585D03*
X1881852Y2196600D03*
X1886699Y2183170D03*
X1876697D03*
X1905939Y2066092D03*
X1893118Y2054585D03*
X1905944Y2055424D03*
X1898342Y2062143D03*
X1901295Y2072745D03*
X1892835Y2155415D03*
X1902872Y2178531D03*
X1894572D03*
X1893087Y2168011D03*
X1896403Y2185019D03*
X1917195Y2072745D03*
X1917550Y2158451D03*
X1909250D03*
X1922010Y2151829D03*
X1913710D03*
X1921855Y2172152D03*
X1936295Y2074343D03*
X1935195Y2155918D03*
X1936377Y2163810D03*
X1924735Y2178131D03*
X1936212Y2173508D03*
X1930155Y2172152D03*
X1931738Y2182647D03*
X1923438D03*
X1941040Y2070124D03*
X1951095Y2155918D03*
X1946077Y2163810D03*
X1969128Y2161283D03*
X1959428D03*
X1969128Y2151583D03*
X1959428D03*
G54D48*
X909360Y230906D03*
Y274606D03*
G54D21*
X51043Y144095D03*
X57933Y66811D03*
X160295D03*
X153405Y144095D03*
X183435Y630650D03*
X190325Y374862D03*
X262657Y66811D03*
X255767Y144095D03*
X279360Y630650D03*
X286250Y374862D03*
X358129Y144095D03*
X365019Y66811D03*
X508130Y144095D03*
X515020Y66811D03*
X617382D03*
X610492Y144095D03*
X647411Y374862D03*
X640521Y630650D03*
X719744Y66811D03*
X712854Y144095D03*
X736446Y630650D03*
X743336Y374862D03*
X815216Y144095D03*
X822106Y66811D03*
X972106D03*
X965216Y144095D03*
X1074468Y66811D03*
X1067578Y144095D03*
X1104498Y374862D03*
X1097608Y630650D03*
X1169940Y144095D03*
X1176830Y66811D03*
X1200423Y374862D03*
X1193533Y630650D03*
X1272302Y144095D03*
X1279192Y66811D03*
X1429193D03*
X1422303Y144095D03*
X1531555Y66811D03*
X1524665Y144095D03*
X1561585Y374862D03*
X1554695Y630650D03*
X1627027Y144095D03*
X1633917Y66811D03*
X1657510Y374862D03*
X1650620Y630650D03*
X1736279Y66811D03*
X1729389Y144095D03*
G54D24*
X46248Y1760941D03*
Y1750941D03*
Y1806941D03*
Y1796941D03*
X143208Y1084547D03*
Y1092027D03*
X146948Y1077066D03*
Y1084547D03*
Y1092027D03*
X143208Y1095767D03*
X146948D03*
X143208Y1110728D03*
Y1118208D03*
X146948Y1110728D03*
Y1118208D03*
X146949Y1166830D03*
X154429Y1073326D03*
X161909D03*
X154429Y1092027D03*
X161909Y1077066D03*
X165649Y1080807D03*
Y1088287D03*
X161909D03*
Y1092027D03*
X154429Y1077066D03*
X158169Y1080807D03*
X150689D03*
X158169Y1084547D03*
X150689D03*
X158169Y1088287D03*
X154429D03*
X150689D03*
X165649Y1084547D03*
X158169Y1099507D03*
X150689D03*
X158169Y1103247D03*
X150689D03*
X161909Y1095767D03*
X165649Y1099507D03*
Y1103247D03*
X154429Y1106988D03*
X150689D03*
X154429Y1095767D03*
X158169Y1110728D03*
Y1114468D03*
X154429D03*
X150689D03*
X158169Y1129429D03*
X165649Y1166830D03*
Y1170570D03*
Y1178050D03*
Y1174310D03*
X163779Y1213582D03*
X160039D03*
X214271Y1114468D03*
X238582Y1078936D03*
X242322Y1082677D03*
X238582Y1097637D03*
X246062Y1254724D03*
X238582D03*
Y1250984D03*
X234842Y1247243D03*
X242322Y1243503D03*
Y1247243D03*
X246062Y1250984D03*
X249803Y1082677D03*
X257283D03*
X249803Y1101377D03*
X253543Y1250984D03*
Y1254724D03*
X249803Y1247243D03*
X253543Y1239763D03*
X249803D03*
X257283Y1247243D03*
X261023Y1250984D03*
Y1239763D03*
Y1254724D03*
X279724Y1082677D03*
Y1086417D03*
X275984Y1078936D03*
X264763Y1082677D03*
X275984Y1097637D03*
X274114Y1121948D03*
X277854Y1133169D03*
Y1125688D03*
X274114Y1204232D03*
X279724Y1247243D03*
X272244Y1243503D03*
Y1247243D03*
X264763D03*
X268503Y1250984D03*
X264763Y1243503D03*
X272244Y1239763D03*
X275984Y1250984D03*
X279724Y1243503D03*
X268503Y1254724D03*
X275984D03*
X294684Y1082677D03*
Y1090157D03*
X294685Y1086417D03*
X290944Y1078936D03*
X287204Y1082677D03*
X283464Y1093897D03*
X290944Y1097637D03*
X294685Y1247243D03*
Y1243503D03*
X283464Y1250984D03*
X287204Y1247243D03*
Y1243503D03*
Y1239763D03*
X290944Y1250984D03*
X283464Y1254724D03*
X290944D03*
X302164Y1082677D03*
X302165Y1086417D03*
X309644Y1082677D03*
X309645Y1086417D03*
X298425Y1097637D03*
X305905D03*
X300295Y1155610D03*
X309645Y1247243D03*
Y1243503D03*
X298425Y1250984D03*
X302165Y1247243D03*
Y1243503D03*
Y1239763D03*
X305905Y1250984D03*
X298425Y1254724D03*
X305905D03*
X320866Y1086417D03*
X317126D03*
X317125Y1082677D03*
X324606Y1086417D03*
X320866Y1093897D03*
X324606D03*
Y1105117D03*
Y1097637D03*
X320866Y1105117D03*
Y1097637D03*
X313385D03*
X324606Y1112598D03*
Y1120078D03*
X320866Y1112598D03*
Y1120078D03*
X317125Y1108858D03*
X320866Y1127558D03*
Y1135039D03*
X322736Y1140649D03*
X324606Y1127558D03*
Y1135039D03*
X326476Y1140649D03*
X322736Y1155610D03*
X326476Y1148129D03*
Y1155610D03*
X322736Y1148129D03*
X326476Y1170570D03*
Y1178051D03*
Y1185531D03*
X320866Y1250984D03*
X313385D03*
X317125Y1247243D03*
Y1243503D03*
X313385Y1254724D03*
X317125Y1239763D03*
X320866Y1254724D03*
X333286Y1728583D03*
Y1738583D03*
X333212Y1774624D03*
Y1784624D03*
X438162Y1348187D03*
Y1360099D03*
Y1384297D03*
Y1372385D03*
X450402Y1348187D03*
Y1360099D03*
Y1384297D03*
Y1372385D03*
Y1396583D03*
Y1408495D03*
X462642Y1348187D03*
X474882D03*
X462642Y1360099D03*
X474882D03*
X462642Y1384297D03*
X474882D03*
X462642Y1372385D03*
X474882D03*
Y1396583D03*
X462642D03*
X474882Y1408495D03*
X462642D03*
X487122Y1348187D03*
Y1360099D03*
Y1372385D03*
Y1384297D03*
Y1396583D03*
Y1408495D03*
X499362Y1348187D03*
Y1360099D03*
Y1372385D03*
Y1384297D03*
Y1396583D03*
Y1408495D03*
X511602Y1348187D03*
Y1360099D03*
Y1372385D03*
Y1384297D03*
Y1396583D03*
Y1408495D03*
X536082Y1348187D03*
X523842D03*
X536082Y1360099D03*
X523842D03*
Y1384297D03*
Y1372385D03*
X536082Y1384297D03*
Y1372385D03*
Y1396583D03*
X523842D03*
X536082Y1408495D03*
X523842D03*
X548322Y1348187D03*
Y1360099D03*
Y1384297D03*
Y1372385D03*
Y1396583D03*
Y1408495D03*
X560562Y1348187D03*
Y1360099D03*
Y1384297D03*
Y1372385D03*
Y1396583D03*
Y1408495D03*
X600295Y1084547D03*
Y1092027D03*
X604035Y1077066D03*
Y1084547D03*
Y1092027D03*
X600295Y1095767D03*
X604035D03*
X600295Y1110728D03*
Y1118208D03*
X604035Y1110728D03*
Y1118208D03*
X604036Y1166830D03*
X611516Y1073326D03*
X618996D03*
Y1088287D03*
Y1092027D03*
X611516Y1077066D03*
X615256Y1080807D03*
X607776D03*
X615256Y1084547D03*
X607776D03*
X615256Y1088287D03*
X611516D03*
X607776D03*
X611516Y1092027D03*
X618996Y1077066D03*
X611516Y1106988D03*
X607776D03*
X611516Y1095767D03*
X615256Y1099507D03*
X607776D03*
X615256Y1103247D03*
X607776D03*
X618996Y1095767D03*
X615256Y1110728D03*
Y1114468D03*
X611516D03*
X607776D03*
X615256Y1129429D03*
X617126Y1213582D03*
X620866D03*
X620083Y1728286D03*
Y1738286D03*
X619711Y1775438D03*
Y1785438D03*
X626476Y1088287D03*
X622736Y1080807D03*
Y1084547D03*
Y1088287D03*
Y1099507D03*
Y1103247D03*
Y1166830D03*
Y1170570D03*
Y1174310D03*
Y1178050D03*
X636288Y1372385D03*
Y1384297D03*
Y1396583D03*
X624048D03*
X636288Y1408495D03*
X624048D03*
X648528Y1348187D03*
Y1360099D03*
Y1372385D03*
Y1384297D03*
Y1396583D03*
Y1408495D03*
X660768Y1348187D03*
Y1360099D03*
Y1372385D03*
Y1384297D03*
Y1396583D03*
Y1408495D03*
X671358Y1114468D03*
X673008Y1348187D03*
X685248D03*
X673008Y1360099D03*
X685248D03*
Y1372385D03*
Y1384297D03*
X673008Y1372385D03*
Y1384297D03*
X685248Y1396583D03*
X673008D03*
X685248Y1408495D03*
X673008D03*
X695669Y1078936D03*
X699409Y1082677D03*
X695669Y1097637D03*
X699409Y1247243D03*
Y1243503D03*
X691929Y1247243D03*
X695669Y1250984D03*
Y1254724D03*
X697488Y1348187D03*
Y1360099D03*
Y1384297D03*
Y1372385D03*
Y1396583D03*
Y1408495D03*
X706890Y1082677D03*
X714370D03*
X706890Y1101377D03*
X703149Y1254724D03*
Y1250984D03*
X718110D03*
Y1239763D03*
X714370Y1247243D03*
X710630Y1254724D03*
Y1250984D03*
Y1239763D03*
X706890Y1247243D03*
Y1239763D03*
X718110Y1254724D03*
X709728Y1348187D03*
Y1360099D03*
Y1384297D03*
Y1372385D03*
Y1396583D03*
Y1408495D03*
X721850Y1082677D03*
X733071Y1078936D03*
Y1097637D03*
X731201Y1121948D03*
X734941Y1125688D03*
Y1133169D03*
X731201Y1204232D03*
X729331Y1243503D03*
X721850D03*
X729331Y1239763D03*
Y1247243D03*
X733071Y1250984D03*
Y1254724D03*
X725590D03*
Y1250984D03*
X721850Y1247243D03*
X734208Y1348187D03*
X721968D03*
X734208Y1360099D03*
X721968D03*
Y1384297D03*
Y1372385D03*
X734208D03*
Y1384297D03*
X721968Y1396489D03*
X734208D03*
X721968Y1408401D03*
X734208D03*
X744291Y1082677D03*
X748031Y1078936D03*
X736811Y1086417D03*
Y1082677D03*
X748031Y1097637D03*
X740551Y1093897D03*
X736811Y1243503D03*
Y1247243D03*
X744291Y1243503D03*
Y1239763D03*
X748031Y1254724D03*
Y1250984D03*
X744291Y1247243D03*
X740551Y1254724D03*
Y1250984D03*
X746448Y1348187D03*
Y1360099D03*
Y1372385D03*
Y1384297D03*
X759251Y1082677D03*
X751772Y1086417D03*
X751771Y1090157D03*
Y1082677D03*
X759252Y1086417D03*
X766732D03*
X766731Y1082677D03*
X762992Y1097637D03*
X755512D03*
X757382Y1155610D03*
X755512Y1250984D03*
Y1254724D03*
X759252Y1247243D03*
Y1243503D03*
X762992Y1250984D03*
Y1254724D03*
X766732Y1247243D03*
Y1243503D03*
X759252Y1239763D03*
X751772Y1247243D03*
Y1243503D03*
X758688Y1348187D03*
Y1360099D03*
Y1372385D03*
Y1384297D03*
X774213Y1086417D03*
X774212Y1082677D03*
X781693Y1086417D03*
X777953D03*
X770472Y1097637D03*
X777953Y1093897D03*
Y1105117D03*
X781693Y1093897D03*
Y1097637D03*
X777953D03*
X781693Y1105117D03*
Y1112598D03*
X777953Y1120078D03*
X781693D03*
X774212Y1108858D03*
X777953Y1112598D03*
X783563Y1140649D03*
X779823D03*
X781693Y1127558D03*
X777953D03*
Y1135039D03*
X781693D03*
X783563Y1155610D03*
Y1148129D03*
X779823Y1155610D03*
Y1148129D03*
X783563Y1170570D03*
Y1185531D03*
Y1178051D03*
X770472Y1250984D03*
Y1254724D03*
X777953Y1250984D03*
X774212Y1247243D03*
Y1243503D03*
Y1239763D03*
X777953Y1254724D03*
X770928Y1348187D03*
Y1360099D03*
X907279Y1738990D03*
Y1728990D03*
X907073Y1776014D03*
Y1786014D03*
X1057381Y1092027D03*
Y1084547D03*
Y1095767D03*
Y1118208D03*
Y1110728D03*
X1068602Y1073326D03*
X1072342Y1088287D03*
Y1084547D03*
Y1080807D03*
X1061121Y1092027D03*
X1068602D03*
X1064862Y1088287D03*
X1068602D03*
X1061121Y1084547D03*
X1064862D03*
Y1080807D03*
X1061121Y1077066D03*
X1068602D03*
X1072342Y1099507D03*
Y1103247D03*
X1061121Y1095767D03*
X1068602D03*
X1064862Y1106988D03*
X1068602D03*
X1064862Y1103247D03*
Y1099507D03*
X1072342Y1114468D03*
Y1110728D03*
X1061121Y1118208D03*
X1064862Y1114468D03*
X1068602D03*
X1061121Y1110728D03*
X1072342Y1129429D03*
X1061122Y1166830D03*
X1074212Y1213582D03*
X1076082Y1073326D03*
X1083562Y1088287D03*
X1079822D03*
Y1084547D03*
Y1080807D03*
X1076082Y1092027D03*
Y1088287D03*
Y1077066D03*
X1079822Y1103247D03*
Y1099507D03*
X1076082Y1095767D03*
X1079822Y1170570D03*
Y1166830D03*
Y1174310D03*
Y1178050D03*
X1077952Y1213582D03*
X1128444Y1114468D03*
X1152755Y1078936D03*
X1156495Y1082677D03*
X1152755Y1097637D03*
Y1254724D03*
Y1250984D03*
X1149015Y1247243D03*
X1156495Y1243503D03*
Y1247243D03*
X1163976Y1082677D03*
X1171456D03*
X1163976Y1101377D03*
Y1239763D03*
Y1247243D03*
X1167716Y1239763D03*
Y1250984D03*
Y1254724D03*
X1171456Y1247243D03*
X1160235Y1250984D03*
Y1254724D03*
X1178936Y1082677D03*
X1188287Y1121948D03*
Y1204232D03*
X1175196Y1254724D03*
Y1239763D03*
Y1250984D03*
X1178936Y1247243D03*
X1182676Y1250984D03*
Y1254724D03*
X1186417Y1247243D03*
Y1239763D03*
X1178936Y1243503D03*
X1186417D03*
X1190157Y1078936D03*
X1201377Y1082677D03*
X1205117Y1078936D03*
X1193897Y1082677D03*
Y1086417D03*
X1190157Y1097637D03*
X1197637Y1093897D03*
X1205117Y1097637D03*
X1192027Y1133169D03*
Y1125688D03*
X1190157Y1254724D03*
Y1250984D03*
X1197637D03*
Y1254724D03*
X1201377Y1247243D03*
X1205117Y1250984D03*
Y1254724D03*
X1201377Y1239763D03*
Y1243503D03*
X1193897Y1247243D03*
Y1243503D03*
X1216337Y1082677D03*
X1216338Y1086417D03*
X1208857Y1082677D03*
X1208858Y1086417D03*
X1208857Y1090157D03*
X1212598Y1097637D03*
X1220078D03*
X1214468Y1155610D03*
X1212598Y1250984D03*
Y1254724D03*
X1216338Y1247243D03*
Y1243503D03*
X1220078Y1250984D03*
Y1254724D03*
X1216338Y1239763D03*
X1208858Y1247243D03*
Y1243503D03*
X1223817Y1082677D03*
X1223818Y1086417D03*
X1231298Y1082677D03*
X1235039Y1086417D03*
X1231299D03*
X1227558Y1097637D03*
X1235039Y1093897D03*
Y1097637D03*
Y1105117D03*
X1231298Y1108858D03*
X1235039Y1112598D03*
Y1120078D03*
X1236909Y1140649D03*
X1235039Y1127558D03*
Y1135039D03*
X1236909Y1148129D03*
Y1155610D03*
X1223818Y1247243D03*
Y1243503D03*
X1227558Y1250984D03*
Y1254724D03*
X1235039Y1250984D03*
X1231298Y1247243D03*
Y1243503D03*
Y1239763D03*
X1235039Y1254724D03*
X1238779Y1086417D03*
Y1093897D03*
Y1097637D03*
Y1105117D03*
Y1112598D03*
Y1120078D03*
X1240649Y1140649D03*
X1238779Y1127558D03*
Y1135039D03*
X1240649Y1148129D03*
Y1155610D03*
Y1170570D03*
Y1178051D03*
Y1185531D03*
X1514468Y1084547D03*
Y1092027D03*
Y1095767D03*
Y1110728D03*
Y1118208D03*
X1525689Y1073326D03*
Y1077066D03*
X1518208D03*
X1529429Y1080807D03*
X1521949D03*
X1529429Y1084547D03*
X1521949D03*
X1518208D03*
X1529429Y1088287D03*
X1525689D03*
X1521949D03*
X1525689Y1092027D03*
X1518208D03*
X1521949Y1103247D03*
X1525689Y1106988D03*
X1521949D03*
X1525689Y1095767D03*
X1518208D03*
X1529429Y1099507D03*
X1521949D03*
X1529429Y1103247D03*
Y1110728D03*
X1518208D03*
X1529429Y1114468D03*
X1525689D03*
X1521949D03*
X1518208Y1118208D03*
X1529429Y1129429D03*
X1518209Y1166830D03*
X1533169Y1073326D03*
X1540649Y1088287D03*
X1533169Y1077066D03*
X1536909Y1080807D03*
Y1084547D03*
Y1088287D03*
X1533169D03*
Y1092027D03*
Y1095767D03*
X1536909Y1099507D03*
Y1103247D03*
Y1166830D03*
Y1170570D03*
Y1174310D03*
X1535039Y1176180D03*
Y1213582D03*
X1531299D03*
X1585531Y1114468D03*
X1609842Y1078936D03*
Y1097637D03*
Y1254724D03*
Y1250984D03*
X1606102Y1247243D03*
X1613582Y1082677D03*
X1621063D03*
Y1101377D03*
X1613582Y1243503D03*
Y1247243D03*
X1621063Y1239763D03*
Y1247243D03*
X1624803Y1239763D03*
Y1250984D03*
Y1254724D03*
X1617322Y1250984D03*
Y1254724D03*
X1636023Y1082677D03*
X1628543D03*
X1632283Y1254724D03*
X1628543Y1247243D03*
X1632283Y1239763D03*
Y1250984D03*
X1636023Y1247243D03*
X1639763Y1250984D03*
Y1254724D03*
X1643504Y1247243D03*
Y1239763D03*
X1636023Y1243503D03*
X1643504D03*
X1658464Y1082677D03*
X1650984D03*
Y1086417D03*
X1647244Y1078936D03*
Y1097637D03*
X1654724Y1093897D03*
X1645374Y1121948D03*
X1649114Y1133169D03*
Y1125688D03*
X1645374Y1204232D03*
X1647244Y1254724D03*
Y1250984D03*
X1654724D03*
Y1254724D03*
X1658464Y1247243D03*
Y1239763D03*
Y1243503D03*
X1650984Y1247243D03*
Y1243503D03*
X1662204Y1078936D03*
X1673424Y1082677D03*
X1673425Y1086417D03*
X1665944Y1082677D03*
X1665945Y1086417D03*
X1665944Y1090157D03*
X1662204Y1097637D03*
X1669685D03*
X1671555Y1155610D03*
X1665945Y1247243D03*
Y1243503D03*
X1662204Y1250984D03*
Y1254724D03*
X1669685Y1250984D03*
Y1254724D03*
X1673425Y1247243D03*
Y1243503D03*
Y1239763D03*
X1680904Y1082677D03*
X1680905Y1086417D03*
X1688385Y1082677D03*
X1692126Y1086417D03*
X1688386D03*
X1677165Y1097637D03*
X1684645D03*
X1692126Y1093897D03*
Y1097637D03*
Y1105117D03*
X1688385Y1108858D03*
X1692126Y1112598D03*
Y1120078D03*
Y1127558D03*
Y1135039D03*
X1684645Y1250984D03*
Y1254724D03*
X1692126Y1250984D03*
X1688385Y1247243D03*
Y1243503D03*
Y1239763D03*
X1692126Y1254724D03*
X1677165Y1250984D03*
Y1254724D03*
X1680905Y1247243D03*
Y1243503D03*
X1695866Y1086417D03*
Y1093897D03*
Y1097637D03*
Y1105117D03*
Y1112598D03*
Y1120078D03*
X1697736Y1140649D03*
X1693996D03*
X1695866Y1127558D03*
Y1135039D03*
X1697736Y1148129D03*
X1693996D03*
X1697736Y1155610D03*
X1693996D03*
X1697736Y1170570D03*
Y1178051D03*
Y1185531D03*
G54D34*
X145078Y1228543D03*
X148818D03*
X145078Y1250984D03*
X148818Y1243503D03*
Y1250984D03*
X145078Y1243503D03*
X161909Y1125688D03*
X158169Y1151869D03*
X154429D03*
Y1166830D03*
X160039Y1194881D03*
Y1202362D03*
Y1209842D03*
Y1217322D03*
Y1236023D03*
Y1232283D03*
X152559Y1236023D03*
Y1232283D03*
X156299Y1250984D03*
X160039Y1247243D03*
X152559D03*
X156299Y1239763D03*
X163779Y1250984D03*
X156299Y1254724D03*
X163779D03*
X178740Y1075196D03*
X171259D03*
X174999D03*
X182480D03*
X178740Y1078936D03*
X174999Y1086417D03*
Y1082677D03*
X171259Y1078936D03*
X182480Y1086417D03*
Y1082677D03*
X174999Y1078936D03*
X182480D03*
X178740Y1082677D03*
Y1086417D03*
X174999Y1093897D03*
X182480D03*
X171259Y1097637D03*
X182480D03*
X174999D03*
X178740Y1101376D03*
Y1105117D03*
X173129Y1129428D03*
X169389D03*
X180610Y1170570D03*
X174999Y1209842D03*
X167519Y1221062D03*
X182480Y1236023D03*
Y1232283D03*
X174999D03*
Y1236023D03*
X167519Y1232283D03*
Y1236023D03*
X182480Y1239763D03*
Y1247243D03*
X178740Y1250984D03*
Y1239763D03*
X174999Y1243503D03*
X178740Y1254724D03*
X171259D03*
X167519Y1247243D03*
X186220Y1075196D03*
X193700D03*
X189960D03*
X197440D03*
X189960Y1086417D03*
Y1082677D03*
X193700Y1078936D03*
X186220D03*
X197440Y1086417D03*
Y1082677D03*
X186220D03*
Y1086417D03*
X189960Y1078936D03*
X193700Y1086417D03*
Y1082677D03*
X197440Y1078936D03*
X193700Y1105117D03*
X197440Y1093897D03*
X189960Y1097637D03*
X186220Y1105117D03*
X197440Y1097637D03*
X193700Y1101376D03*
X186220D03*
X188090Y1178051D03*
Y1193011D03*
X197440Y1236023D03*
Y1232283D03*
X189960Y1236023D03*
Y1232283D03*
X197440Y1247243D03*
X193700Y1254724D03*
X186220D03*
X189960Y1239763D03*
X186220Y1250984D03*
X189960Y1247243D03*
X193700Y1250984D03*
X201181Y1075196D03*
X208661D03*
X204921D03*
X212401D03*
X208661Y1078936D03*
X212401Y1086417D03*
Y1082677D03*
X204921Y1086417D03*
Y1082677D03*
X201181Y1078936D03*
X212401D03*
X208661Y1082677D03*
X201181D03*
Y1086417D03*
X208661D03*
X204921Y1078936D03*
Y1097637D03*
X208661Y1101376D03*
X212401Y1097637D03*
X208661Y1105117D03*
X212401Y1093897D03*
X201181Y1101376D03*
X204921Y1093897D03*
X201181Y1105117D03*
X204921Y1232283D03*
X212401D03*
Y1236023D03*
X204921D03*
X208661Y1250984D03*
X201181Y1239763D03*
X212401D03*
Y1247243D03*
X201181Y1254724D03*
X204921Y1239763D03*
X201181Y1250984D03*
X204921Y1247243D03*
X208661Y1254724D03*
X213969Y1445013D03*
Y1456013D03*
X223622Y1075196D03*
X231102D03*
X216141D03*
X227362D03*
X219881D03*
X227362Y1086417D03*
Y1082677D03*
X219881Y1086417D03*
Y1082677D03*
X223622Y1078936D03*
X231102D03*
X216141D03*
X219881D03*
X216141Y1086417D03*
X231102Y1082677D03*
Y1086417D03*
X223622Y1082677D03*
X227362Y1078936D03*
X216141Y1082677D03*
X223622Y1086417D03*
X216141Y1101376D03*
X231102D03*
X227362Y1093897D03*
X219881Y1097637D03*
X223621Y1101376D03*
Y1105117D03*
X216141D03*
X219881Y1093897D03*
X227362Y1097637D03*
X231102Y1105117D03*
Y1228543D03*
X219881Y1232283D03*
Y1236023D03*
X227362Y1232283D03*
Y1236023D03*
X223622Y1254724D03*
X231102D03*
X227362Y1247243D03*
X219881Y1239763D03*
X223622Y1250984D03*
X219881Y1247243D03*
X231102Y1250984D03*
X227362Y1239763D03*
X216141Y1250984D03*
Y1254724D03*
X227249Y1445013D03*
Y1456013D03*
X234841Y1093897D03*
X246062Y1105117D03*
X242321Y1097637D03*
X234841D03*
X238582Y1101376D03*
X246062D03*
X238582Y1105117D03*
X242321Y1093897D03*
X246062Y1221062D03*
X238582Y1224803D03*
Y1228543D03*
X242322Y1236023D03*
Y1232283D03*
X246062Y1228543D03*
X234842Y1232283D03*
X246062Y1224803D03*
X234842Y1236023D03*
Y1239763D03*
Y1243503D03*
X242322Y1239763D03*
X257283Y1101377D03*
X253543Y1105117D03*
Y1101376D03*
X261023Y1105117D03*
Y1101376D03*
X249803Y1221062D03*
X253543D03*
X261023D03*
X257283D03*
X261023Y1224803D03*
X253543Y1228543D03*
X249803Y1232283D03*
X257283D03*
Y1236023D03*
X261023Y1228543D03*
X253543Y1224803D03*
X249803Y1236023D03*
Y1243503D03*
X257283D03*
X272244Y1101377D03*
X279724D03*
X264763D03*
X264762Y1097637D03*
X268503Y1105117D03*
X272243Y1097637D03*
X275984Y1105117D03*
X279723Y1093897D03*
X272243D03*
X279723Y1097637D03*
X268503Y1101376D03*
X275984D03*
X264762Y1093897D03*
X277854Y1121948D03*
Y1129429D03*
X264763Y1221062D03*
Y1232283D03*
X268503Y1224803D03*
X275984D03*
X272244Y1236023D03*
X279724Y1232283D03*
Y1236023D03*
X275984Y1228543D03*
X272244Y1232283D03*
X268503Y1228543D03*
X264763Y1236023D03*
X279724Y1239763D03*
X275984D03*
X264763D03*
X287204Y1086417D03*
X283464Y1097637D03*
X294684Y1101377D03*
X283464Y1101376D03*
X294684Y1093897D03*
X287203D03*
X294684Y1097637D03*
X283464Y1105117D03*
X290944Y1101376D03*
Y1105117D03*
X287203Y1097637D03*
X294684Y1123818D03*
Y1116338D03*
Y1131299D03*
X289074Y1144389D03*
X294685Y1198621D03*
Y1213582D03*
Y1206102D03*
X287204Y1232283D03*
X283464Y1224803D03*
Y1228543D03*
X287204Y1236023D03*
X294685D03*
X290944Y1224803D03*
X294685Y1232283D03*
X290944Y1228543D03*
X294685Y1239763D03*
X302164Y1090157D03*
X305904D03*
X309644D03*
X302165Y1101377D03*
X309645D03*
X298425Y1105117D03*
Y1101376D03*
X309644Y1097637D03*
X302164D03*
X305905Y1105117D03*
X309644Y1093897D03*
X305905Y1101376D03*
X302164Y1093897D03*
X309645Y1123818D03*
X309644Y1108858D03*
X309645Y1116338D03*
X302165Y1120078D03*
X305905Y1112598D03*
X298425Y1116338D03*
X305905Y1120078D03*
X302165Y1112598D03*
X298425Y1123818D03*
X309645Y1131299D03*
X307775Y1140649D03*
X298425Y1135039D03*
Y1127558D03*
X305905Y1127559D03*
Y1135039D03*
X302165D03*
Y1127559D03*
X298425Y1131299D03*
X300295Y1151869D03*
Y1144389D03*
X307775Y1148129D03*
Y1155610D03*
Y1159350D03*
X298425Y1198621D03*
X305905Y1202362D03*
X302165D03*
X298425Y1213582D03*
X305905Y1209842D03*
Y1217322D03*
X302165Y1209842D03*
X298425Y1206102D03*
X302165Y1217322D03*
Y1232283D03*
X309645D03*
X298425Y1224803D03*
Y1228543D03*
X309645Y1236023D03*
X305905Y1228543D03*
Y1224803D03*
X302165Y1236023D03*
X305905Y1239763D03*
X317125Y1090157D03*
X320866D03*
X324606D03*
Y1082676D03*
X320866D03*
X317126Y1105117D03*
X317125Y1101377D03*
X313385D03*
X317125Y1093897D03*
X320866Y1101377D03*
X324606D03*
X317125Y1097637D03*
X313385Y1120078D03*
X324606Y1123818D03*
Y1108858D03*
X320866D03*
X317125Y1112598D03*
X324606Y1116338D03*
X313385Y1112598D03*
X317125Y1120078D03*
X320866Y1116338D03*
Y1123818D03*
X318996Y1136909D03*
X317125Y1131299D03*
X313385Y1127558D03*
X317125Y1135039D03*
X313385D03*
X324606Y1131299D03*
X317125Y1127558D03*
X320866Y1131299D03*
X318996Y1144389D03*
Y1151869D03*
X322736Y1166830D03*
X318996Y1159350D03*
Y1166830D03*
X326476D03*
X318996Y1189271D03*
Y1181791D03*
Y1174310D03*
X317125Y1198621D03*
X320866D03*
X313385Y1202362D03*
X324606Y1198621D03*
X317125Y1202362D03*
Y1206102D03*
Y1213582D03*
Y1217322D03*
Y1209842D03*
X324606Y1213582D03*
X313385Y1209842D03*
X320866Y1213582D03*
X324606Y1206102D03*
X313385Y1217322D03*
X317125Y1236023D03*
X313385Y1224803D03*
X324606Y1228543D03*
X317125Y1232283D03*
X313385Y1228543D03*
X320866D03*
Y1243503D03*
X313385Y1239763D03*
X320866Y1247243D03*
X324606D03*
X602165Y1228543D03*
Y1243503D03*
Y1250984D03*
X618996Y1125688D03*
Y1133169D03*
X615256Y1151869D03*
X611516D03*
Y1166830D03*
X617126Y1202362D03*
Y1194881D03*
Y1209842D03*
Y1217322D03*
X605905Y1228543D03*
X609646Y1232283D03*
X617126Y1236023D03*
Y1232283D03*
X609646Y1236023D03*
X613386Y1239763D03*
X620866Y1254724D03*
Y1250984D03*
X617126Y1247243D03*
X609646D03*
X613386Y1254724D03*
Y1250984D03*
X605905Y1243503D03*
Y1254724D03*
Y1250984D03*
X626476Y1073326D03*
X635827Y1075196D03*
X628346D03*
X632086D03*
X626476Y1077066D03*
X628346Y1078936D03*
X635827D03*
X632086Y1082677D03*
Y1086417D03*
Y1078936D03*
X635827Y1086417D03*
Y1082677D03*
X632086Y1097637D03*
X626476Y1099507D03*
X628346Y1097637D03*
X635827Y1105117D03*
X632086Y1093897D03*
X635827Y1101376D03*
X630216Y1129428D03*
X626476D03*
X630216Y1136909D03*
X626476D03*
X632086Y1209842D03*
X624606Y1221062D03*
X632086Y1232283D03*
Y1236023D03*
X624606Y1232283D03*
Y1236023D03*
X632086Y1243503D03*
X635827Y1239763D03*
Y1254724D03*
Y1250984D03*
X628346Y1254724D03*
X624606Y1247243D03*
X643307Y1075196D03*
X650787D03*
X639567D03*
X647047D03*
X650787Y1078936D03*
X647047Y1082677D03*
Y1086417D03*
X643307Y1078936D03*
X639567Y1086417D03*
Y1082677D03*
X643307Y1086417D03*
Y1082677D03*
X647047Y1078936D03*
X639567D03*
X650787Y1082677D03*
Y1086417D03*
Y1105117D03*
X639567Y1097637D03*
X643307Y1105117D03*
X647047Y1097637D03*
X639567Y1093897D03*
X643307Y1101376D03*
X650787D03*
X637697Y1170570D03*
X645177Y1178051D03*
Y1193011D03*
X639567Y1236023D03*
X647047D03*
X639567Y1232283D03*
X647047D03*
X639567Y1239763D03*
Y1247243D03*
X647047Y1239763D03*
X650787Y1254724D03*
Y1250984D03*
X647047Y1247243D03*
X643307Y1254724D03*
Y1250984D03*
X658268Y1075196D03*
X665748D03*
X662008D03*
X654527D03*
X669488D03*
Y1086417D03*
X665748Y1078936D03*
X669488Y1082677D03*
X654527D03*
Y1086417D03*
X662008Y1082677D03*
Y1086417D03*
X658268Y1078936D03*
X662008D03*
X665748Y1082677D03*
X658268D03*
X654527Y1078936D03*
X665748Y1086417D03*
X658268D03*
X669488Y1078936D03*
X662008Y1097637D03*
X654527Y1093897D03*
X669488D03*
X665748Y1105117D03*
X654527Y1097637D03*
X662008Y1093897D03*
X669488Y1097637D03*
X665748Y1101376D03*
X658268Y1105117D03*
Y1101376D03*
X669488Y1232283D03*
X654527Y1236023D03*
X662008Y1232283D03*
Y1236023D03*
X669488D03*
X654527Y1232283D03*
Y1247243D03*
X662008Y1239763D03*
X658268D03*
X669488D03*
X665748Y1250984D03*
Y1254724D03*
X669488Y1247243D03*
X662008D03*
X658268Y1254724D03*
Y1250984D03*
X680709Y1075196D03*
X673228D03*
X676968D03*
X684449D03*
Y1082677D03*
Y1086417D03*
X673228Y1078936D03*
X680709D03*
X676968Y1082677D03*
Y1086417D03*
Y1078936D03*
X680709Y1086417D03*
X684449Y1078936D03*
X673228Y1086417D03*
Y1082677D03*
X680709D03*
X673228Y1105117D03*
X684449Y1093897D03*
X676968D03*
X684449Y1097637D03*
X676968D03*
X680708Y1105117D03*
X673228Y1101376D03*
X680708D03*
X676968Y1236023D03*
X684449Y1232283D03*
Y1236023D03*
X676968Y1232283D03*
Y1239763D03*
X680709Y1254724D03*
Y1250984D03*
X676968Y1247243D03*
X673228Y1254724D03*
Y1250984D03*
X684449Y1247243D03*
Y1239763D03*
X688189Y1075196D03*
Y1078936D03*
Y1086417D03*
Y1082677D03*
Y1105117D03*
X695669Y1101376D03*
X699408Y1097637D03*
X695669Y1105117D03*
X691928Y1093897D03*
Y1097637D03*
X699408Y1093897D03*
X688189Y1101376D03*
Y1228543D03*
X691929Y1236023D03*
X699409Y1232283D03*
Y1236023D03*
X691929Y1232283D03*
X695669Y1228543D03*
Y1224803D03*
X688189Y1254724D03*
Y1250984D03*
X699409Y1239763D03*
X691929D03*
Y1243503D03*
X714370Y1101377D03*
X703149Y1105117D03*
X718110D03*
Y1101376D03*
X710630Y1105117D03*
X703149Y1101376D03*
X710630D03*
X706890Y1236023D03*
X718110Y1228543D03*
X714370Y1236023D03*
X710630Y1228543D03*
X703149D03*
X714370Y1232283D03*
X703149Y1224803D03*
X718110D03*
X710630D03*
X706890Y1232283D03*
X714370Y1243503D03*
X706890D03*
X729331Y1101377D03*
X721850D03*
X725590Y1101376D03*
X733071Y1105117D03*
X725590D03*
X721849Y1097637D03*
Y1093897D03*
X729330Y1097637D03*
X733071Y1101376D03*
X729330Y1093897D03*
X734941Y1121948D03*
Y1129429D03*
X725590Y1228543D03*
X733071D03*
X721850Y1236023D03*
X733071Y1224803D03*
X721850Y1232283D03*
X725590Y1224803D03*
X729331Y1236023D03*
Y1232283D03*
X733071Y1239763D03*
X721850D03*
X744291Y1086417D03*
X740551Y1097637D03*
X736811Y1101377D03*
X736810Y1097637D03*
X748031Y1105117D03*
X744290Y1093897D03*
X740551Y1105117D03*
X744290Y1097637D03*
X736810Y1093897D03*
X740551Y1101376D03*
X748031D03*
X746161Y1144389D03*
X744291Y1236023D03*
X736811Y1232283D03*
X744291D03*
X736811Y1236023D03*
X740551Y1224803D03*
Y1228543D03*
X748031Y1224803D03*
Y1228543D03*
X736811Y1239763D03*
X766731Y1090157D03*
X759251D03*
X762991D03*
X751771Y1101377D03*
X759252D03*
X766732D03*
X751771Y1097637D03*
X762992Y1101376D03*
Y1105117D03*
X755512D03*
X759251Y1097637D03*
Y1093897D03*
X766731Y1097637D03*
X755512Y1101376D03*
X766731Y1093897D03*
X751771D03*
X766731Y1108858D03*
X766732Y1116338D03*
Y1123818D03*
X755512D03*
X759252Y1112598D03*
X751771Y1123818D03*
X762992Y1112598D03*
X755512Y1116338D03*
X751771D03*
X759252Y1120078D03*
X762992D03*
X764862Y1140649D03*
X766732Y1131299D03*
X755512Y1127558D03*
Y1135039D03*
X751771Y1131299D03*
X762992Y1135039D03*
X755512Y1131299D03*
X762992Y1127559D03*
X759252Y1135039D03*
Y1127559D03*
X764862Y1155610D03*
Y1148129D03*
X757382Y1144389D03*
Y1151869D03*
X764862Y1159350D03*
X762992Y1202362D03*
X755512Y1198621D03*
X759252Y1202362D03*
X751772Y1198621D03*
X762992Y1217322D03*
X751772Y1213582D03*
X762992Y1209842D03*
X755512Y1213582D03*
X751772Y1206102D03*
X759252Y1217322D03*
Y1209842D03*
X755512Y1206102D03*
Y1228543D03*
X751772Y1236023D03*
X762992Y1228543D03*
X751772Y1232283D03*
X766732D03*
Y1236023D03*
X759252Y1232283D03*
X762992Y1224803D03*
X759252Y1236023D03*
X755512Y1224803D03*
X762992Y1239763D03*
X751772D03*
X774212Y1090157D03*
X781693D03*
X777953D03*
X781693Y1082676D03*
X777953D03*
X774212Y1101377D03*
X774213Y1105117D03*
X770472Y1101377D03*
X781693D03*
X777953D03*
X774212Y1097637D03*
Y1093897D03*
Y1112598D03*
X770472D03*
X781693Y1123818D03*
X777953D03*
X781693Y1116338D03*
X777953Y1108858D03*
X770472Y1120078D03*
X781693Y1108858D03*
X777953Y1116338D03*
X774212Y1120078D03*
Y1131299D03*
X770472Y1127558D03*
Y1135039D03*
X781693Y1131299D03*
X774212Y1127558D03*
Y1135039D03*
X777953Y1131299D03*
X776083Y1151869D03*
Y1144389D03*
X783563Y1166830D03*
X776083D03*
Y1159350D03*
X779823Y1166830D03*
X776083Y1174310D03*
Y1181791D03*
Y1196751D03*
X774212Y1198621D03*
X781693D03*
X774212Y1202362D03*
X770472D03*
X777953Y1198621D03*
X774212Y1213582D03*
Y1206102D03*
X770472Y1209842D03*
X781693Y1213582D03*
X774212Y1209842D03*
X781693Y1206102D03*
X770472Y1217322D03*
X774212D03*
X777953Y1213582D03*
X770472Y1228543D03*
X781693D03*
X770472Y1224803D03*
X777953Y1228543D03*
X774212Y1232283D03*
Y1236023D03*
X777953Y1243503D03*
X770472Y1239763D03*
X777953Y1247243D03*
X781693D03*
X1059251Y1228543D03*
Y1243503D03*
Y1250984D03*
X1072342Y1151869D03*
X1068602D03*
Y1166830D03*
X1074212Y1194881D03*
Y1202362D03*
Y1217322D03*
Y1209842D03*
X1066732Y1236023D03*
Y1232283D03*
X1074212Y1236023D03*
Y1232283D03*
X1062991Y1228543D03*
X1070472Y1250984D03*
Y1254724D03*
X1066732Y1247243D03*
X1074212D03*
X1070472Y1239763D03*
X1062991Y1250984D03*
Y1254724D03*
Y1243503D03*
X1083562Y1073326D03*
X1089172Y1075196D03*
X1083562Y1077066D03*
X1089172Y1082677D03*
Y1086417D03*
Y1078936D03*
Y1097637D03*
Y1093897D03*
X1083562Y1099507D03*
Y1136909D03*
X1087302D03*
X1083562Y1129428D03*
X1087302D03*
X1076082Y1133169D03*
Y1125688D03*
X1089172Y1209842D03*
X1081692Y1221062D03*
X1089172Y1232283D03*
X1081692D03*
Y1236023D03*
X1089172D03*
X1077952Y1250984D03*
Y1254724D03*
X1081692Y1247243D03*
X1085432Y1254724D03*
X1089172Y1243503D03*
X1092913Y1075196D03*
X1107873D03*
X1100393D03*
X1096653D03*
X1104133D03*
X1092913Y1078936D03*
X1104133Y1086417D03*
Y1082677D03*
X1107873Y1078936D03*
X1100393D03*
X1096653Y1082677D03*
Y1086417D03*
X1100393Y1082677D03*
X1104133Y1078936D03*
X1107873Y1082677D03*
Y1086417D03*
X1092913Y1082677D03*
X1100393Y1086417D03*
X1092913D03*
X1096653Y1078936D03*
X1092913Y1105117D03*
X1104133Y1097637D03*
X1096653D03*
X1100393Y1105117D03*
Y1101376D03*
X1096653Y1093897D03*
X1092913Y1101376D03*
X1107873Y1105117D03*
Y1101376D03*
X1094783Y1170570D03*
X1102263Y1178051D03*
Y1193011D03*
X1104133Y1236023D03*
Y1232283D03*
X1096653Y1236023D03*
Y1232283D03*
X1092913Y1250984D03*
Y1254724D03*
Y1239763D03*
X1100393Y1250984D03*
Y1254724D03*
X1104133Y1247243D03*
X1107873Y1250984D03*
Y1254724D03*
X1104133Y1239763D03*
X1096653Y1247243D03*
Y1239763D03*
X1115354Y1075196D03*
X1122834D03*
X1111613D03*
X1119094D03*
X1115354Y1078936D03*
X1119094Y1082677D03*
Y1086417D03*
X1122834Y1078936D03*
X1111613Y1082677D03*
Y1086417D03*
X1122834D03*
X1119094Y1078936D03*
X1115354Y1082677D03*
X1111613Y1078936D03*
X1115354Y1086417D03*
X1122834Y1082677D03*
X1119094Y1097637D03*
X1115354Y1101376D03*
X1111613Y1093897D03*
Y1097637D03*
X1122834Y1105117D03*
X1119094Y1093897D03*
X1122834Y1101376D03*
X1115354Y1105117D03*
X1119094Y1232283D03*
X1111613D03*
X1119094Y1236023D03*
X1111613D03*
X1115354Y1250984D03*
Y1254724D03*
X1119094Y1247243D03*
X1122834Y1254724D03*
Y1250984D03*
X1115354Y1239763D03*
X1119094D03*
X1111613Y1247243D03*
X1130314Y1075196D03*
X1137795D03*
X1126574D03*
X1134054D03*
X1126574Y1086417D03*
Y1082677D03*
X1130314Y1078936D03*
X1134054Y1082677D03*
Y1086417D03*
X1137795Y1078936D03*
X1134054D03*
X1126574D03*
X1130314Y1086417D03*
Y1082677D03*
X1137795Y1086417D03*
Y1082677D03*
X1126574Y1093897D03*
X1130314Y1105117D03*
X1134054Y1093897D03*
X1130314Y1101376D03*
X1134054Y1097637D03*
X1137794Y1105117D03*
X1126574Y1097637D03*
X1137794Y1101376D03*
X1134054Y1236023D03*
Y1232283D03*
X1126574D03*
Y1236023D03*
Y1247243D03*
Y1239763D03*
X1130314Y1250984D03*
Y1254724D03*
X1134054Y1247243D03*
X1137795Y1250984D03*
Y1254724D03*
X1134054Y1239763D03*
X1145275Y1075196D03*
X1141535D03*
Y1082677D03*
Y1086417D03*
X1145275Y1078936D03*
Y1086417D03*
Y1082677D03*
X1141535Y1078936D03*
X1145275Y1105117D03*
X1141535Y1093897D03*
X1145275Y1101376D03*
X1141535Y1097637D03*
X1149014D03*
X1156494Y1093897D03*
X1152755Y1101376D03*
X1156494Y1097637D03*
X1149014Y1093897D03*
X1152755Y1105117D03*
X1149015Y1236023D03*
Y1232283D03*
X1152755Y1228543D03*
X1156495Y1232283D03*
Y1236023D03*
X1141535D03*
X1145275Y1228543D03*
X1152755Y1224803D03*
X1141535Y1232283D03*
Y1239763D03*
Y1247243D03*
X1149015Y1243503D03*
Y1239763D03*
X1156495D03*
X1145275Y1250984D03*
Y1254724D03*
X1171456Y1101377D03*
X1160235Y1105117D03*
Y1101376D03*
X1167716Y1105117D03*
Y1101376D03*
X1160235Y1224803D03*
X1163976Y1232283D03*
X1167716Y1224803D03*
X1160235Y1228543D03*
X1171456Y1232283D03*
X1163976Y1236023D03*
X1171456D03*
X1167716Y1228543D03*
X1163976Y1243503D03*
X1171456D03*
X1178936Y1101377D03*
X1186417D03*
X1178935Y1097637D03*
X1186416Y1093897D03*
X1182676Y1105117D03*
X1175196D03*
X1178935Y1093897D03*
X1182676Y1101376D03*
X1175196D03*
X1186416Y1097637D03*
X1182676Y1228543D03*
X1186417Y1236023D03*
X1178936D03*
X1186417Y1232283D03*
X1175196Y1228543D03*
X1178936Y1232283D03*
X1182676Y1224803D03*
X1175196D03*
X1178936Y1239763D03*
X1201377Y1086417D03*
X1197637Y1097637D03*
X1193897Y1101377D03*
X1201376Y1093897D03*
X1193896Y1097637D03*
X1197637Y1105117D03*
X1205117D03*
X1197637Y1101376D03*
X1205117D03*
X1190157D03*
X1193896Y1093897D03*
X1201376Y1097637D03*
X1190157Y1105117D03*
X1192027Y1121948D03*
Y1129429D03*
X1203247Y1144389D03*
X1197637Y1224803D03*
X1193897Y1236023D03*
X1190157Y1228543D03*
X1201377Y1236023D03*
X1190157Y1224803D03*
X1193897Y1232283D03*
X1197637Y1228543D03*
X1201377Y1232283D03*
X1205117Y1228543D03*
Y1224803D03*
X1190157Y1239763D03*
X1193897D03*
X1216337Y1090157D03*
X1220077D03*
X1216338Y1101377D03*
X1208857D03*
X1220078Y1105117D03*
X1216337Y1093897D03*
X1212598Y1101376D03*
Y1105117D03*
X1208857Y1093897D03*
X1216337Y1097637D03*
X1220078Y1101376D03*
X1208857Y1097637D03*
X1212598Y1123818D03*
X1208857Y1116338D03*
X1212598D03*
X1216338Y1120078D03*
Y1112598D03*
X1208857Y1123818D03*
X1220078Y1112598D03*
Y1120078D03*
X1221948Y1140649D03*
X1212598Y1127558D03*
Y1135039D03*
X1216338Y1127559D03*
Y1135039D03*
X1212598Y1131299D03*
X1208857D03*
X1220078Y1135039D03*
Y1127559D03*
X1221948Y1155610D03*
X1214468Y1151869D03*
Y1144389D03*
X1221948Y1148129D03*
Y1159350D03*
X1212598Y1198621D03*
X1208858D03*
X1216338Y1202362D03*
X1220078D03*
Y1217322D03*
Y1209842D03*
X1212598Y1206102D03*
X1216338Y1217322D03*
X1212598Y1213582D03*
X1208858Y1206102D03*
Y1213582D03*
X1216338Y1209842D03*
X1220078Y1224803D03*
X1212598Y1228543D03*
X1208858Y1232283D03*
X1216338Y1236023D03*
Y1232283D03*
X1212598Y1224803D03*
X1220078Y1228543D03*
X1208858Y1236023D03*
X1220078Y1239763D03*
X1208858D03*
X1223817Y1090157D03*
X1231298D03*
X1235039D03*
Y1082676D03*
X1223818Y1101377D03*
X1231298D03*
X1231299Y1105117D03*
X1227558Y1101377D03*
X1231298Y1093897D03*
X1235039Y1101377D03*
X1223817Y1093897D03*
Y1097637D03*
X1231298D03*
X1223817Y1108858D03*
X1223818Y1116338D03*
Y1123818D03*
X1227558Y1112598D03*
X1235039Y1123818D03*
X1231298Y1120078D03*
Y1112598D03*
X1235039Y1108858D03*
Y1116338D03*
X1227558Y1120078D03*
X1233169Y1136909D03*
X1223818Y1131299D03*
X1231298D03*
Y1135039D03*
X1227558Y1127558D03*
X1235039Y1131299D03*
X1231298Y1127558D03*
X1227558Y1135039D03*
X1233169Y1144389D03*
Y1151869D03*
X1236909Y1166830D03*
X1233169Y1159350D03*
Y1166830D03*
Y1189271D03*
Y1181791D03*
Y1174310D03*
Y1196751D03*
X1231298Y1198621D03*
Y1202362D03*
X1235039Y1198621D03*
X1227558Y1202362D03*
X1231298Y1206102D03*
Y1213582D03*
X1235039D03*
X1231298Y1209842D03*
X1227558D03*
X1231298Y1217322D03*
X1227558D03*
X1231298Y1232283D03*
X1227558Y1228543D03*
Y1224803D03*
X1223818Y1236023D03*
X1231298D03*
X1235039Y1228543D03*
X1223818Y1232283D03*
X1235039Y1243503D03*
X1227558Y1239763D03*
X1235039Y1247243D03*
X1238779Y1090157D03*
Y1082676D03*
Y1101377D03*
Y1108858D03*
Y1116338D03*
Y1123818D03*
X1243149Y1136909D03*
X1238779Y1131299D03*
X1240649Y1166830D03*
X1238779Y1198621D03*
Y1206102D03*
Y1213582D03*
Y1228543D03*
Y1247243D03*
X1511968Y1170570D03*
Y1178050D03*
X1529429Y1151869D03*
X1525689D03*
Y1166830D03*
X1516338Y1228543D03*
X1523819Y1232283D03*
X1520078Y1228543D03*
X1523819Y1236023D03*
X1516338Y1243503D03*
Y1250984D03*
X1527559D03*
Y1254724D03*
X1523819Y1247243D03*
X1527559Y1239763D03*
X1520078Y1250984D03*
Y1254724D03*
Y1243503D03*
X1540649Y1073326D03*
X1546259Y1075196D03*
X1540649Y1077066D03*
X1546259Y1082677D03*
Y1086417D03*
Y1078936D03*
X1540649Y1099507D03*
X1546259Y1097637D03*
Y1093897D03*
X1533169Y1125688D03*
X1544389Y1129428D03*
X1540649D03*
X1544389Y1136909D03*
X1533169Y1133169D03*
X1540649Y1136909D03*
X1531299Y1194881D03*
Y1202362D03*
Y1217322D03*
Y1209842D03*
X1546259D03*
X1538779Y1221062D03*
X1546259Y1232283D03*
X1538779Y1236023D03*
X1531299Y1232283D03*
X1546259Y1236023D03*
X1531299D03*
X1538779Y1232283D03*
X1531299Y1247243D03*
X1535039Y1250984D03*
Y1254724D03*
X1538779Y1247243D03*
X1542519Y1254724D03*
X1546259Y1243503D03*
X1557480Y1075196D03*
X1550000D03*
X1553740D03*
X1561220D03*
Y1086417D03*
Y1082677D03*
X1557480Y1078936D03*
X1553740Y1082677D03*
Y1086417D03*
X1550000Y1078936D03*
X1557480Y1082677D03*
X1553740Y1078936D03*
X1561220D03*
X1550000Y1086417D03*
Y1082677D03*
X1557480Y1086417D03*
Y1101376D03*
Y1105117D03*
X1561220Y1097637D03*
X1550000Y1101376D03*
Y1105117D03*
X1553740Y1093897D03*
Y1097637D03*
X1551870Y1170570D03*
X1559350Y1178051D03*
Y1193011D03*
X1553740Y1232283D03*
Y1236023D03*
X1561220D03*
Y1232283D03*
X1550000Y1250984D03*
Y1254724D03*
Y1239763D03*
X1557480Y1250984D03*
Y1254724D03*
X1561220Y1247243D03*
Y1239763D03*
X1553740Y1247243D03*
Y1239763D03*
X1572441Y1075196D03*
X1564960D03*
X1576181D03*
X1568700D03*
X1564960Y1078936D03*
X1572441D03*
X1576181Y1082677D03*
Y1086417D03*
X1568700Y1082677D03*
Y1086417D03*
Y1078936D03*
X1572441Y1086417D03*
X1564960Y1082677D03*
Y1086417D03*
X1572441Y1082677D03*
X1576181Y1078936D03*
X1564960Y1105117D03*
X1576181Y1097637D03*
X1568700D03*
X1576181Y1093897D03*
X1568700D03*
X1572441Y1101376D03*
Y1105117D03*
X1564960Y1101376D03*
X1568700Y1236023D03*
X1576181D03*
Y1232283D03*
X1568700D03*
X1564960Y1250984D03*
Y1254724D03*
X1572441Y1250984D03*
Y1254724D03*
X1576181Y1247243D03*
X1572441Y1239763D03*
X1576181D03*
X1568700Y1247243D03*
X1579921Y1075196D03*
X1587401D03*
X1594882D03*
X1583661D03*
X1591141D03*
X1583661Y1086417D03*
Y1082677D03*
X1579921Y1078936D03*
X1587401D03*
X1591141Y1082677D03*
Y1086417D03*
X1594882Y1078936D03*
Y1082677D03*
X1579921D03*
X1583661Y1078936D03*
X1594882Y1086417D03*
X1587401Y1082677D03*
X1579921Y1086417D03*
X1587401D03*
X1591141Y1078936D03*
X1594881Y1105117D03*
X1591141Y1097637D03*
X1583661Y1093897D03*
X1594881Y1101376D03*
X1583661Y1097637D03*
X1587401Y1105117D03*
X1579921Y1101376D03*
X1591141Y1093897D03*
X1587401Y1101376D03*
X1579921Y1105117D03*
X1591141Y1232283D03*
X1583661Y1236023D03*
Y1232283D03*
X1591141Y1236023D03*
X1583661Y1247243D03*
X1579921Y1254724D03*
Y1250984D03*
X1583661Y1239763D03*
X1587401Y1250984D03*
Y1254724D03*
X1591141Y1247243D03*
X1594882Y1250984D03*
Y1254724D03*
X1591141Y1239763D03*
X1602362Y1075196D03*
X1598622D03*
Y1082677D03*
Y1086417D03*
X1602362Y1078936D03*
Y1082677D03*
Y1086417D03*
X1598622Y1078936D03*
X1606101Y1093897D03*
X1602362Y1101376D03*
X1598622Y1097637D03*
Y1093897D03*
X1602362Y1105117D03*
X1609842Y1101376D03*
Y1105117D03*
X1606101Y1097637D03*
X1598622Y1236023D03*
X1606102D03*
X1609842Y1228543D03*
X1606102Y1232283D03*
X1609842Y1224803D03*
X1602362Y1228543D03*
X1598622Y1232283D03*
Y1239763D03*
Y1247243D03*
X1606102Y1243503D03*
Y1239763D03*
X1602362Y1250984D03*
Y1254724D03*
X1617322Y1105117D03*
Y1101376D03*
X1613581Y1093897D03*
Y1097637D03*
X1624803Y1101376D03*
Y1105117D03*
X1617322Y1228543D03*
X1624803Y1224803D03*
X1617322D03*
X1621063Y1236023D03*
X1613582D03*
X1621063Y1232283D03*
X1624803Y1228543D03*
X1613582Y1232283D03*
Y1239763D03*
X1621063Y1243503D03*
X1639763Y1101376D03*
X1636022Y1093897D03*
X1636023Y1101377D03*
X1643504D03*
X1628543D03*
X1639763Y1105117D03*
X1632283D03*
Y1101376D03*
X1636022Y1097637D03*
X1643503D03*
Y1093897D03*
X1632283Y1228543D03*
X1628543Y1236023D03*
Y1232283D03*
X1639763Y1224803D03*
X1636023Y1236023D03*
X1643504Y1232283D03*
X1632283Y1224803D03*
X1643504Y1236023D03*
X1636023Y1232283D03*
X1639763Y1228543D03*
X1628543Y1243503D03*
X1636023Y1239763D03*
X1658464Y1086417D03*
X1658463Y1097637D03*
X1647244Y1101376D03*
X1654724Y1097637D03*
X1650984Y1101377D03*
X1658463Y1093897D03*
X1654724Y1105117D03*
X1650983Y1093897D03*
X1647244Y1105117D03*
X1654724Y1101376D03*
X1650983Y1097637D03*
X1649114Y1121948D03*
Y1129429D03*
X1660334Y1144389D03*
X1654724Y1228543D03*
X1647244D03*
X1658464Y1232283D03*
X1654724Y1224803D03*
X1658464Y1236023D03*
X1650984D03*
X1647244Y1224803D03*
X1650984Y1232283D03*
X1647244Y1239763D03*
X1650984D03*
X1673424Y1090157D03*
X1665944Y1093897D03*
X1662204Y1105117D03*
X1669685D03*
X1673424Y1097637D03*
X1669685Y1101376D03*
X1673425Y1101377D03*
X1665944D03*
X1673424Y1093897D03*
X1665944Y1097637D03*
X1662204Y1101376D03*
X1673425Y1112598D03*
X1665944Y1123818D03*
X1673425Y1120078D03*
X1669685Y1123818D03*
X1665944Y1116338D03*
X1669685D03*
X1665944Y1131299D03*
X1671555Y1136909D03*
X1669685Y1127558D03*
Y1135039D03*
Y1131299D03*
X1673425Y1127559D03*
Y1135039D03*
X1671555Y1151869D03*
Y1144389D03*
X1673425Y1202362D03*
X1665945Y1198621D03*
X1669685D03*
X1665945Y1206102D03*
X1669685Y1213582D03*
X1673425Y1209842D03*
X1669685Y1206102D03*
X1665945Y1213582D03*
X1673425Y1217322D03*
Y1236023D03*
X1662204Y1228543D03*
X1669685D03*
X1673425Y1232283D03*
X1665945D03*
Y1236023D03*
X1662204Y1224803D03*
X1669685D03*
X1665945Y1239763D03*
X1677164Y1090157D03*
X1680904D03*
X1688385D03*
X1692126D03*
Y1082676D03*
Y1101377D03*
X1684645D03*
X1677165Y1105117D03*
X1680905Y1101377D03*
X1688385D03*
X1688386Y1105117D03*
X1680904Y1097637D03*
X1677165Y1101376D03*
X1688385Y1097637D03*
X1680904Y1093897D03*
X1688385D03*
X1677165Y1120078D03*
Y1112598D03*
X1680904Y1108858D03*
X1680905Y1116338D03*
Y1123818D03*
X1692126Y1116338D03*
Y1108858D03*
X1684645Y1120078D03*
X1688385D03*
X1684645Y1112598D03*
X1692126Y1123818D03*
X1688385Y1112598D03*
X1690256Y1136909D03*
X1679035Y1140649D03*
X1680905Y1131299D03*
X1688385D03*
X1677165Y1135039D03*
Y1127559D03*
X1684645Y1135039D03*
Y1127558D03*
X1692126Y1131299D03*
X1688385Y1127558D03*
Y1135039D03*
X1690256Y1144389D03*
X1679035Y1148129D03*
Y1155610D03*
X1690256Y1151869D03*
Y1159350D03*
X1679035D03*
X1690256Y1166830D03*
Y1174310D03*
Y1189271D03*
Y1181791D03*
X1688385Y1198621D03*
X1684645Y1202362D03*
X1692126Y1198621D03*
X1688385Y1202362D03*
X1677165D03*
X1688385Y1213582D03*
Y1206102D03*
X1692126Y1213582D03*
X1684645Y1217322D03*
Y1209842D03*
X1677165D03*
X1688385D03*
X1677165Y1217322D03*
X1688385D03*
X1677165Y1228543D03*
X1680905Y1236023D03*
Y1232283D03*
X1692126Y1228543D03*
X1684645Y1224803D03*
Y1228543D03*
X1677165Y1224803D03*
X1688385Y1232283D03*
Y1236023D03*
X1692126Y1243503D03*
X1684645Y1239763D03*
X1677165D03*
X1692126Y1247243D03*
X1695866Y1090157D03*
Y1082676D03*
Y1101377D03*
Y1123818D03*
Y1116338D03*
Y1108858D03*
X1700236Y1136909D03*
X1695866Y1131299D03*
X1693996Y1166830D03*
X1697736D03*
X1695866Y1198621D03*
Y1213582D03*
Y1206102D03*
Y1228543D03*
Y1247243D03*
G54D43*
X718503Y-38525D03*
X718500Y-33320D03*
Y-30420D03*
X718488Y-36010D03*
X721756Y-38539D03*
X724781Y-37219D03*
X721741Y-36024D03*
X838503Y-77705D03*
X841756Y-77719D03*
X838500Y-72500D03*
X838488Y-75190D03*
X841741Y-75204D03*
X844781Y-76399D03*
X838500Y-69600D03*
X1005256Y-48539D03*
X1002003D03*
X1005241Y-46024D03*
X1001988D03*
X1008281Y-47219D03*
X1002000Y-40834D03*
X1005256Y-38239D03*
X1002003Y-38225D03*
X1002000Y-43334D03*
X1005241Y-35724D03*
X1002000Y-32720D03*
X1001988Y-35710D03*
X1002000Y-30120D03*
X1008281Y-36919D03*
X1075256Y-77419D03*
X1072003Y-77405D03*
X1071988Y-85290D03*
X1075241D03*
X1072000Y-82600D03*
X1072003Y-87805D03*
X1075256D03*
X1072000Y-80100D03*
Y-72000D03*
Y-69400D03*
X1075241Y-74904D03*
X1071988Y-74890D03*
X1078281Y-86399D03*
Y-76099D03*
X1291756Y-48669D03*
X1288503D03*
X1291741Y-46154D03*
X1288488D03*
X1294781Y-47349D03*
X1288500Y-40964D03*
X1291756Y-38369D03*
X1288503Y-38355D03*
X1288500Y-43464D03*
X1291741Y-35854D03*
X1288500Y-32950D03*
X1288488Y-35840D03*
X1288500Y-30350D03*
X1294781Y-37049D03*
X1328500Y-80100D03*
X1331756Y-77419D03*
X1328503Y-77405D03*
X1331756Y-87805D03*
X1328503D03*
X1328500Y-82600D03*
X1331741Y-85290D03*
X1328488D03*
X1334781Y-86499D03*
X1331741Y-74904D03*
X1328500Y-72000D03*
X1328488Y-74890D03*
X1328500Y-69400D03*
X1334781Y-76099D03*
X1576256Y-48799D03*
X1573003D03*
X1576241Y-46284D03*
X1572988D03*
X1579281Y-47479D03*
X1573000Y-41094D03*
X1576256Y-38499D03*
X1573003Y-38485D03*
X1573000Y-43594D03*
X1576241Y-35984D03*
X1573000Y-33080D03*
X1572988Y-35970D03*
X1573000Y-30480D03*
X1579281Y-37179D03*
X1583000Y-80014D03*
X1586256Y-77419D03*
X1583003Y-77405D03*
X1586256Y-87719D03*
X1583003D03*
X1583000Y-82514D03*
X1586241Y-85204D03*
X1582988D03*
X1589281Y-86399D03*
X1586241Y-74904D03*
X1583000Y-72000D03*
X1582988Y-74890D03*
X1583000Y-69400D03*
X1589281Y-76099D03*
G54D25*
X56348Y1727941D03*
Y1737941D03*
X56248Y1750941D03*
X56348Y1773941D03*
X56248Y1760941D03*
X56348Y1783941D03*
X56248Y1806941D03*
Y1796941D03*
X308448Y1737941D03*
Y1727941D03*
Y1750941D03*
Y1760941D03*
Y1773941D03*
Y1783941D03*
X308348Y1796941D03*
Y1806941D03*
X343286Y1738583D03*
Y1728583D03*
X343112Y1751624D03*
X343212Y1774624D03*
X343112Y1761624D03*
X343212Y1784624D03*
Y1797624D03*
Y1807624D03*
X595386Y1728583D03*
Y1738583D03*
X595312Y1751624D03*
Y1774624D03*
Y1761624D03*
Y1784624D03*
Y1807624D03*
Y1797624D03*
X630083Y1738286D03*
Y1728286D03*
X629861Y1751765D03*
X629711Y1775438D03*
X629861Y1761765D03*
X629711Y1785438D03*
X629475Y1798845D03*
Y1808845D03*
X882183Y1728286D03*
Y1738286D03*
X881911Y1751765D03*
X881761Y1775438D03*
X881911Y1761765D03*
X881761Y1785438D03*
X881525Y1798845D03*
Y1808845D03*
X917279Y1738990D03*
Y1728990D03*
X917163Y1752566D03*
Y1762566D03*
X917073Y1786014D03*
Y1776014D03*
X917166Y1800435D03*
Y1810435D03*
X1169329Y1728990D03*
Y1738990D03*
X1169263Y1752566D03*
Y1762566D03*
X1169123Y1776014D03*
Y1786014D03*
X1169216Y1800435D03*
Y1810435D03*
G54D39*
X318448Y1727941D03*
Y1737941D03*
Y1773941D03*
Y1783941D03*
X605312Y1751624D03*
Y1761624D03*
Y1807624D03*
Y1797624D03*
X891911Y1751765D03*
Y1761765D03*
X891525Y1808845D03*
Y1798845D03*
X1179263Y1752566D03*
Y1762566D03*
X1179216Y1800435D03*
Y1810435D03*
G54D56*
X1250055Y1710189D03*
Y1720189D03*
Y1739208D03*
Y1749208D03*
X1250048Y1768377D03*
Y1778377D03*
X1248555Y1797909D03*
Y1807909D03*
X1734069Y1710189D03*
Y1720189D03*
Y1739208D03*
Y1749208D03*
X1734062Y1768377D03*
Y1778377D03*
X1734069Y1797909D03*
Y1807909D03*
G54D51*
X1011187Y-43526D03*
Y-40126D03*
X1081187Y-79306D03*
Y-82706D03*
X1225405Y-79278D03*
Y-82678D03*
X1230761Y-43628D03*
Y-40228D03*
X1297687Y-40256D03*
Y-43656D03*
X1337687Y-79306D03*
Y-82706D03*
X1481905Y-79278D03*
Y-82678D03*
X1517261Y-40358D03*
Y-43758D03*
X1592187Y-79306D03*
Y-82706D03*
X1582187Y-43786D03*
Y-40386D03*
X1736405Y-79278D03*
Y-82678D03*
X1801761Y-43888D03*
Y-40488D03*
G54D11*
X13780Y1226024D03*
X79331Y1186654D03*
X390354Y1141024D03*
X536418Y1086654D03*
X854291Y1225118D03*
X993504Y1170748D03*
X1304528Y1141024D03*
X1450591Y1086654D03*
X1761614Y1215000D03*
X1827165Y1235630D03*
G54D41*
X661674Y23622D03*
G54D18*
X23622Y1604724D03*
X62205Y765197D03*
X74016Y333464D03*
X102224Y70866D03*
X409488Y1604724D03*
X433130Y70866D03*
X463387Y286221D03*
X463386Y765197D03*
X785039Y1547638D03*
X890217Y23622D03*
X920473Y765196D03*
X1055905Y1547637D03*
X1118760Y23622D03*
X1347303Y70866D03*
X1377559Y286220D03*
Y765197D03*
X1431457Y1604724D03*
X1575846Y23622D03*
X1766929Y333464D03*
X1778740Y765197D03*
X1795010Y23622D03*
X1817323Y1604724D03*
G54D19*
X28819Y81575D03*
X73307Y61614D03*
X131181Y81575D03*
X175669Y61614D03*
X233543Y81575D03*
X278032Y61614D03*
X335906Y81575D03*
X380394Y61614D03*
X485886Y81595D03*
X530394Y61614D03*
X588248Y81594D03*
X632756Y61614D03*
X690611Y81595D03*
X735118Y61614D03*
X792973Y81595D03*
X837480Y61614D03*
X942973Y81595D03*
X987480Y61614D03*
X1045335Y81595D03*
X1089843Y61614D03*
X1147697Y81595D03*
X1192205Y61614D03*
X1250060Y81595D03*
X1294567Y61614D03*
X1400060Y81595D03*
X1444567Y61614D03*
X1502441Y81575D03*
X1546929Y61614D03*
X1604784Y81595D03*
X1649291Y61614D03*
X1707146Y81595D03*
X1751654Y61614D03*
G54D35*
X173829Y455492D03*
Y583957D03*
X202844Y455492D03*
Y583957D03*
X630915Y455492D03*
Y583957D03*
X659930Y455492D03*
Y583957D03*
X1088002Y455492D03*
Y583957D03*
X1117017Y455492D03*
Y583957D03*
X1545089Y455492D03*
Y583957D03*
X1574104Y455492D03*
Y583957D03*
G54D59*
X1795453Y812874D03*
Y834922D03*
G54D45*
X849441Y1367717D03*
G54D47*
X895384Y228740D03*
Y276772D03*
X923336Y226772D03*
Y278740D03*
G54D53*
X1030635Y764546D03*
G54D60*
X1803917Y823898D03*
G54D57*
X1747253Y1715189D03*
Y1744208D03*
X1747246Y1773377D03*
G54D58*
X1747253Y1802909D03*
G54D61*
X1817323Y1567323D03*
G54D13*
X19685Y-83298D03*
Y1801195D03*
X1821260Y-83298D03*
Y1801195D03*
G54D29*
X116731Y1066535D03*
Y1263386D03*
X352952Y1066535D03*
Y1263386D03*
X573818Y1066535D03*
Y1263386D03*
X810038Y1066535D03*
Y1263386D03*
X1030905Y1066535D03*
Y1263386D03*
X1267125Y1066535D03*
Y1263386D03*
X1487991Y1066535D03*
Y1263386D03*
X1724212Y1066535D03*
Y1263386D03*
G54D17*
X26789Y1373669D03*
X184851Y334492D03*
X235433Y1580079D03*
Y1626339D03*
X581890Y1580079D03*
Y1626339D03*
X1259055Y1580079D03*
Y1626339D03*
X1605512Y1580079D03*
Y1626339D03*
X1796847Y1517889D03*
X1809883Y120792D03*
G54D44*
X770472Y1490945D03*
X820079Y388583D03*
X1020866D03*
X1070472Y1490945D03*
G54D31*
X109882Y1453504D03*
Y1468859D03*
Y1484213D03*
Y1499567D03*
Y1514922D03*
Y1555867D03*
Y1571221D03*
Y1586575D03*
Y1601930D03*
Y1617284D03*
X127205Y1453504D03*
X118543Y1457835D03*
X127205Y1468859D03*
X118543Y1473189D03*
X127205Y1484213D03*
X118543Y1488544D03*
X127205Y1499567D03*
Y1514922D03*
X118543Y1503898D03*
Y1519252D03*
X127205Y1555867D03*
X118543Y1560197D03*
X127205Y1571221D03*
X118543Y1575552D03*
X127205Y1586575D03*
X118543Y1590906D03*
X127205Y1601930D03*
X118543Y1606260D03*
X127205Y1617284D03*
X118543Y1621615D03*
X144528Y1453504D03*
X135866Y1457835D03*
X144528Y1468859D03*
X135866Y1473189D03*
X144528Y1484213D03*
X135866Y1488544D03*
X144528Y1499567D03*
Y1514922D03*
X135866Y1503898D03*
Y1519252D03*
X144528Y1555867D03*
X135866Y1560197D03*
X144528Y1571221D03*
X135866Y1575552D03*
X144528Y1586575D03*
X135866Y1590906D03*
X144528Y1601930D03*
X135866Y1606260D03*
X144528Y1617284D03*
X135866Y1621615D03*
X161850Y1453504D03*
X153189Y1457835D03*
X161850Y1468859D03*
X153189Y1473189D03*
X161850Y1484213D03*
X153189Y1488544D03*
X161850Y1499567D03*
Y1514922D03*
X153189Y1503898D03*
Y1519252D03*
X161850Y1555867D03*
X153189Y1560197D03*
X161850Y1571221D03*
X153189Y1575552D03*
X161850Y1586575D03*
X153189Y1590906D03*
X161850Y1601930D03*
X153189Y1606260D03*
X161850Y1617284D03*
X153189Y1621615D03*
X179173Y1453504D03*
X170512Y1457835D03*
X179173Y1468859D03*
X170512Y1473189D03*
X179173Y1484213D03*
X170512Y1488544D03*
X179173Y1499567D03*
Y1514922D03*
X170512Y1503898D03*
Y1519252D03*
X179173Y1555867D03*
X170512Y1560197D03*
X179173Y1571221D03*
X170512Y1575552D03*
X179173Y1586575D03*
X170512Y1590906D03*
X179173Y1601930D03*
X170512Y1606260D03*
X179173Y1617284D03*
X170512Y1621615D03*
X187835Y1457835D03*
Y1473189D03*
Y1488544D03*
Y1503898D03*
Y1519252D03*
Y1560197D03*
Y1575552D03*
Y1590906D03*
Y1606260D03*
Y1621615D03*
X283110Y1453504D03*
X291771Y1457835D03*
X283110Y1468859D03*
X291771Y1473189D03*
X283110Y1484213D03*
X291771Y1488544D03*
X283110Y1499567D03*
X291771Y1503898D03*
X283110Y1514922D03*
X291771Y1519252D03*
X283110Y1555867D03*
X291771Y1560197D03*
X283110Y1571221D03*
X291771Y1575552D03*
X283110Y1586575D03*
X291771Y1590906D03*
X283110Y1601930D03*
X291771Y1606260D03*
X283110Y1617284D03*
X291771Y1621615D03*
X300433Y1453504D03*
X309094Y1457835D03*
X300433Y1468859D03*
X309094Y1473189D03*
X300433Y1484213D03*
X309094Y1488544D03*
X300433Y1499567D03*
X309094Y1503898D03*
X300433Y1514922D03*
X309094Y1519252D03*
X300433Y1555867D03*
X309094Y1560197D03*
X300433Y1571221D03*
X309094Y1575552D03*
X300433Y1586575D03*
X309094Y1590906D03*
X300433Y1601930D03*
X309094Y1606260D03*
X300433Y1617284D03*
X309094Y1621615D03*
X317756Y1453504D03*
X326417Y1457835D03*
X317756Y1468859D03*
X326417Y1473189D03*
X317756Y1484213D03*
X326417Y1488544D03*
X317756Y1499567D03*
X326417Y1503898D03*
X317756Y1514922D03*
X326417Y1519252D03*
X317756Y1555867D03*
X326417Y1560197D03*
X317756Y1571221D03*
X326417Y1575552D03*
X317756Y1586575D03*
X326417Y1590906D03*
X317756Y1601930D03*
X326417Y1606260D03*
X317756Y1617284D03*
X326417Y1621615D03*
X335078Y1453504D03*
X343740Y1457835D03*
X335078Y1468859D03*
X343740Y1473189D03*
X335078Y1484213D03*
X343740Y1488544D03*
X335078Y1499567D03*
X343740Y1503898D03*
X335078Y1514922D03*
X343740Y1519252D03*
X335078Y1555867D03*
X343740Y1560197D03*
X335078Y1571221D03*
X343740Y1575552D03*
X335078Y1586575D03*
X343740Y1590906D03*
X335078Y1601930D03*
X343740Y1606260D03*
X335078Y1617284D03*
X343740Y1621615D03*
X352401Y1453504D03*
X361063Y1457835D03*
X352401Y1468859D03*
X361063Y1473189D03*
X352401Y1484213D03*
X361063Y1488544D03*
X352401Y1499567D03*
X361063Y1503898D03*
X352401Y1514922D03*
X361063Y1519252D03*
X352401Y1555867D03*
X361063Y1560197D03*
X352401Y1571221D03*
X361063Y1575552D03*
X352401Y1586575D03*
X361063Y1590906D03*
X352401Y1601930D03*
X361063Y1606260D03*
X352401Y1617284D03*
X361063Y1621615D03*
X456339Y1453504D03*
Y1468859D03*
Y1484213D03*
Y1499567D03*
Y1514922D03*
Y1555867D03*
Y1571221D03*
Y1586575D03*
Y1601930D03*
Y1617284D03*
X473662Y1453504D03*
X465000Y1457835D03*
X473662Y1468859D03*
X465000Y1473189D03*
X473662Y1484213D03*
X465000Y1488544D03*
X473662Y1499567D03*
Y1514922D03*
X465000Y1503898D03*
Y1519252D03*
X473662Y1555867D03*
X465000Y1560197D03*
X473662Y1571221D03*
X465000Y1575552D03*
X473662Y1586575D03*
X465000Y1590906D03*
X473662Y1601930D03*
X465000Y1606260D03*
X473662Y1617284D03*
X465000Y1621615D03*
X490985Y1453504D03*
X482323Y1457835D03*
X490985Y1468859D03*
X482323Y1473189D03*
X490985Y1484213D03*
X482323Y1488544D03*
X490985Y1499567D03*
Y1514922D03*
X482323Y1503898D03*
Y1519252D03*
X490985Y1555867D03*
X482323Y1560197D03*
X490985Y1571221D03*
X482323Y1575552D03*
X490985Y1586575D03*
X482323Y1590906D03*
X490985Y1601930D03*
X482323Y1606260D03*
X490985Y1617284D03*
X482323Y1621615D03*
X508307Y1453504D03*
X499646Y1457835D03*
X508307Y1468859D03*
X499646Y1473189D03*
X508307Y1484213D03*
X499646Y1488544D03*
X508307Y1499567D03*
Y1514922D03*
X499646Y1503898D03*
Y1519252D03*
X508307Y1555867D03*
X499646Y1560197D03*
X508307Y1571221D03*
X499646Y1575552D03*
X508307Y1586575D03*
X499646Y1590906D03*
X508307Y1601930D03*
X499646Y1606260D03*
X508307Y1617284D03*
X499646Y1621615D03*
X516969Y1457835D03*
Y1473189D03*
Y1488544D03*
Y1503898D03*
Y1519252D03*
Y1560197D03*
Y1575552D03*
Y1590906D03*
Y1606260D03*
Y1621615D03*
X525630Y1453504D03*
X534292Y1457835D03*
X525630Y1468859D03*
X534292Y1473189D03*
X525630Y1484213D03*
X534292Y1488544D03*
X525630Y1499567D03*
X534292Y1503898D03*
X525630Y1514922D03*
X534292Y1519252D03*
X525630Y1555867D03*
X534292Y1560197D03*
X525630Y1571221D03*
X534292Y1575552D03*
X525630Y1586575D03*
X534292Y1590906D03*
X525630Y1601930D03*
X534292Y1606260D03*
X525630Y1617284D03*
X534292Y1621615D03*
X629567Y1453504D03*
X638228Y1457835D03*
X629567Y1468859D03*
X638228Y1473189D03*
X629567Y1484213D03*
X638228Y1488544D03*
X629567Y1499567D03*
X638228Y1503898D03*
X629567Y1514922D03*
X638228Y1519252D03*
X629567Y1555867D03*
X638228Y1560197D03*
X629567Y1571221D03*
X638228Y1575552D03*
X629567Y1586575D03*
X638228Y1590906D03*
X629567Y1601930D03*
X638228Y1606260D03*
X629567Y1617284D03*
X638228Y1621615D03*
X646890Y1453504D03*
Y1468859D03*
Y1484213D03*
Y1499567D03*
Y1514922D03*
Y1555867D03*
Y1571221D03*
Y1586575D03*
Y1601930D03*
Y1617284D03*
X664213Y1453504D03*
X655551Y1457835D03*
X664213Y1468859D03*
X655551Y1473189D03*
X664213Y1484213D03*
X655551Y1488544D03*
X664213Y1499567D03*
Y1514922D03*
X655551Y1503898D03*
Y1519252D03*
X664213Y1555867D03*
X655551Y1560197D03*
X664213Y1571221D03*
X655551Y1575552D03*
X664213Y1586575D03*
X655551Y1590906D03*
X664213Y1601930D03*
X655551Y1606260D03*
X664213Y1617284D03*
X655551Y1621615D03*
X681535Y1453504D03*
X672874Y1457835D03*
X681535Y1468859D03*
X672874Y1473189D03*
X681535Y1484213D03*
X672874Y1488544D03*
X681535Y1499567D03*
Y1514922D03*
X672874Y1503898D03*
Y1519252D03*
X681535Y1555867D03*
X672874Y1560197D03*
X681535Y1571221D03*
X672874Y1575552D03*
X681535Y1586575D03*
X672874Y1590906D03*
X681535Y1601930D03*
X672874Y1606260D03*
X681535Y1617284D03*
X672874Y1621615D03*
X698858Y1453504D03*
X690197Y1457835D03*
X698858Y1468859D03*
X690197Y1473189D03*
X698858Y1484213D03*
X690197Y1488544D03*
X698858Y1499567D03*
Y1514922D03*
X690197Y1503898D03*
Y1519252D03*
X698858Y1555867D03*
X690197Y1560197D03*
X698858Y1571221D03*
X690197Y1575552D03*
X698858Y1586575D03*
X690197Y1590906D03*
X698858Y1601930D03*
X690197Y1606260D03*
X698858Y1617284D03*
X690197Y1621615D03*
X707520Y1457835D03*
Y1473189D03*
Y1488544D03*
Y1503898D03*
Y1519252D03*
Y1560197D03*
Y1575552D03*
Y1590906D03*
Y1606260D03*
Y1621615D03*
X1131850Y1453504D03*
X1140511Y1457835D03*
X1131850Y1468859D03*
X1140511Y1473189D03*
X1131850Y1484213D03*
X1140511Y1488544D03*
X1131850Y1499567D03*
X1140511Y1503898D03*
X1131850Y1514922D03*
X1140511Y1519252D03*
X1131850Y1555867D03*
X1140511Y1560197D03*
X1131850Y1571221D03*
X1140511Y1575552D03*
X1131850Y1586575D03*
X1140511Y1590906D03*
X1131850Y1601930D03*
X1140511Y1606260D03*
X1131850Y1617284D03*
X1140511Y1621615D03*
X1149173Y1453504D03*
X1157834Y1457835D03*
X1149173Y1468859D03*
X1157834Y1473189D03*
X1149173Y1484213D03*
X1157834Y1488544D03*
X1149173Y1499567D03*
X1157834Y1503898D03*
X1149173Y1514922D03*
X1157834Y1519252D03*
X1149173Y1555867D03*
X1157834Y1560197D03*
X1149173Y1571221D03*
X1157834Y1575552D03*
X1149173Y1586575D03*
X1157834Y1590906D03*
X1149173Y1601930D03*
X1157834Y1606260D03*
X1149173Y1617284D03*
X1157834Y1621615D03*
X1166496Y1453504D03*
Y1468859D03*
Y1484213D03*
Y1499567D03*
Y1514922D03*
Y1555867D03*
Y1571221D03*
Y1586575D03*
Y1601930D03*
Y1617284D03*
X1183818Y1453504D03*
X1175157Y1457835D03*
X1183818Y1468859D03*
X1175157Y1473189D03*
X1183818Y1484213D03*
X1175157Y1488544D03*
X1183818Y1499567D03*
Y1514922D03*
X1175157Y1503898D03*
Y1519252D03*
X1183818Y1555867D03*
X1175157Y1560197D03*
X1183818Y1571221D03*
X1175157Y1575552D03*
X1183818Y1586575D03*
X1175157Y1590906D03*
X1183818Y1601930D03*
X1175157Y1606260D03*
X1183818Y1617284D03*
X1175157Y1621615D03*
X1201141Y1453504D03*
X1192480Y1457835D03*
X1201141Y1468859D03*
X1192480Y1473189D03*
X1201141Y1484213D03*
X1192480Y1488544D03*
X1201141Y1499567D03*
Y1514922D03*
X1192480Y1503898D03*
Y1519252D03*
X1201141Y1555867D03*
X1192480Y1560197D03*
X1201141Y1571221D03*
X1192480Y1575552D03*
X1201141Y1586575D03*
X1192480Y1590906D03*
X1201141Y1601930D03*
X1192480Y1606260D03*
X1201141Y1617284D03*
X1192480Y1621615D03*
X1209803Y1457835D03*
Y1473189D03*
Y1488544D03*
Y1503898D03*
Y1519252D03*
Y1560197D03*
Y1575552D03*
Y1590906D03*
Y1606260D03*
Y1621615D03*
X1305079Y1453504D03*
X1313740Y1457835D03*
X1305079Y1468859D03*
X1313740Y1473189D03*
X1305079Y1484213D03*
X1313740Y1488544D03*
X1305079Y1499567D03*
X1313740Y1503898D03*
X1305079Y1514922D03*
X1313740Y1519252D03*
X1305079Y1555867D03*
X1313740Y1560197D03*
X1305079Y1571221D03*
X1313740Y1575552D03*
X1305079Y1586575D03*
X1313740Y1590906D03*
X1305079Y1601930D03*
X1313740Y1606260D03*
X1305079Y1617284D03*
X1313740Y1621615D03*
X1322402Y1453504D03*
X1331063Y1457835D03*
X1322402Y1468859D03*
X1331063Y1473189D03*
X1322402Y1484213D03*
X1331063Y1488544D03*
X1322402Y1499567D03*
X1331063Y1503898D03*
X1322402Y1514922D03*
X1331063Y1519252D03*
X1322402Y1555867D03*
X1331063Y1560197D03*
X1322402Y1571221D03*
X1331063Y1575552D03*
X1322402Y1586575D03*
X1331063Y1590906D03*
X1322402Y1601930D03*
X1331063Y1606260D03*
X1322402Y1617284D03*
X1331063Y1621615D03*
X1339725Y1453504D03*
X1348386Y1457835D03*
X1339725Y1468859D03*
X1348386Y1473189D03*
X1339725Y1484213D03*
X1348386Y1488544D03*
X1339725Y1499567D03*
X1348386Y1503898D03*
X1339725Y1514922D03*
X1348386Y1519252D03*
X1339725Y1555867D03*
X1348386Y1560197D03*
X1339725Y1571221D03*
X1348386Y1575552D03*
X1339725Y1586575D03*
X1348386Y1590906D03*
X1339725Y1601930D03*
X1348386Y1606260D03*
X1339725Y1617284D03*
X1348386Y1621615D03*
X1357047Y1453504D03*
X1365709Y1457835D03*
X1357047Y1468859D03*
X1365709Y1473189D03*
X1357047Y1484213D03*
X1365709Y1488544D03*
X1357047Y1499567D03*
X1365709Y1503898D03*
X1357047Y1514922D03*
X1365709Y1519252D03*
X1357047Y1555867D03*
X1365709Y1560197D03*
X1357047Y1571221D03*
X1365709Y1575552D03*
X1357047Y1586575D03*
X1365709Y1590906D03*
X1357047Y1601930D03*
X1365709Y1606260D03*
X1357047Y1617284D03*
X1365709Y1621615D03*
X1374370Y1453504D03*
X1383032Y1457835D03*
X1374370Y1468859D03*
X1383032Y1473189D03*
X1374370Y1484213D03*
X1383032Y1488544D03*
X1374370Y1499567D03*
X1383032Y1503898D03*
X1374370Y1514922D03*
X1383032Y1519252D03*
X1374370Y1555867D03*
X1383032Y1560197D03*
X1374370Y1571221D03*
X1383032Y1575552D03*
X1374370Y1586575D03*
X1383032Y1590906D03*
X1374370Y1601930D03*
X1383032Y1606260D03*
X1374370Y1617284D03*
X1383032Y1621615D03*
X1478307Y1453504D03*
Y1468859D03*
Y1484213D03*
Y1499567D03*
Y1514922D03*
Y1555867D03*
Y1571221D03*
Y1586575D03*
Y1601930D03*
Y1617284D03*
X1495630Y1453504D03*
X1486968Y1457835D03*
X1495630Y1468859D03*
X1486968Y1473189D03*
X1495630Y1484213D03*
X1486968Y1488544D03*
X1495630Y1499567D03*
Y1514922D03*
X1486968Y1503898D03*
Y1519252D03*
X1495630Y1555867D03*
X1486968Y1560197D03*
X1495630Y1571221D03*
X1486968Y1575552D03*
X1495630Y1586575D03*
X1486968Y1590906D03*
X1495630Y1601930D03*
X1486968Y1606260D03*
X1495630Y1617284D03*
X1486968Y1621615D03*
X1512953Y1453504D03*
X1504291Y1457835D03*
X1512953Y1468859D03*
X1504291Y1473189D03*
X1512953Y1484213D03*
X1504291Y1488544D03*
X1512953Y1499567D03*
Y1514922D03*
X1504291Y1503898D03*
Y1519252D03*
X1512953Y1555867D03*
X1504291Y1560197D03*
X1512953Y1571221D03*
X1504291Y1575552D03*
X1512953Y1586575D03*
X1504291Y1590906D03*
X1512953Y1601930D03*
X1504291Y1606260D03*
X1512953Y1617284D03*
X1504291Y1621615D03*
X1530275Y1453504D03*
X1521614Y1457835D03*
X1530275Y1468859D03*
X1521614Y1473189D03*
X1530275Y1484213D03*
X1521614Y1488544D03*
X1530275Y1499567D03*
Y1514922D03*
X1521614Y1503898D03*
Y1519252D03*
X1530275Y1555867D03*
X1521614Y1560197D03*
X1530275Y1571221D03*
X1521614Y1575552D03*
X1530275Y1586575D03*
X1521614Y1590906D03*
X1530275Y1601930D03*
X1521614Y1606260D03*
X1530275Y1617284D03*
X1521614Y1621615D03*
X1547598Y1453504D03*
X1538937Y1457835D03*
X1547598Y1468859D03*
X1538937Y1473189D03*
X1547598Y1484213D03*
X1538937Y1488544D03*
X1547598Y1499567D03*
Y1514922D03*
X1538937Y1503898D03*
Y1519252D03*
X1547598Y1555867D03*
X1538937Y1560197D03*
X1547598Y1571221D03*
X1538937Y1575552D03*
X1547598Y1586575D03*
X1538937Y1590906D03*
X1547598Y1601930D03*
X1538937Y1606260D03*
X1547598Y1617284D03*
X1538937Y1621615D03*
X1556260Y1457835D03*
Y1473189D03*
Y1488544D03*
Y1503898D03*
Y1519252D03*
Y1560197D03*
Y1575552D03*
Y1590906D03*
Y1606260D03*
Y1621615D03*
X1651535Y1453504D03*
X1660196Y1457835D03*
X1651535Y1468859D03*
X1660196Y1473189D03*
X1651535Y1484213D03*
X1660196Y1488544D03*
X1651535Y1499567D03*
X1660196Y1503898D03*
X1651535Y1514922D03*
X1660196Y1519252D03*
X1651535Y1555867D03*
X1660196Y1560197D03*
X1651535Y1571221D03*
X1660196Y1575552D03*
X1651535Y1586575D03*
X1660196Y1590906D03*
X1651535Y1601930D03*
X1660196Y1606260D03*
X1651535Y1617284D03*
X1660196Y1621615D03*
X1668858Y1453504D03*
X1677519Y1457835D03*
X1668858Y1468859D03*
X1677519Y1473189D03*
X1668858Y1484213D03*
X1677519Y1488544D03*
X1668858Y1499567D03*
X1677519Y1503898D03*
X1668858Y1514922D03*
X1677519Y1519252D03*
X1668858Y1555867D03*
X1677519Y1560197D03*
X1668858Y1571221D03*
X1677519Y1575552D03*
X1668858Y1586575D03*
X1677519Y1590906D03*
X1668858Y1601930D03*
X1677519Y1606260D03*
X1668858Y1617284D03*
X1677519Y1621615D03*
X1686181Y1453504D03*
Y1468859D03*
Y1484213D03*
Y1499567D03*
Y1514922D03*
Y1555867D03*
Y1571221D03*
Y1586575D03*
Y1601930D03*
Y1617284D03*
X1703503Y1453504D03*
X1694842Y1457835D03*
X1703503Y1468859D03*
X1694842Y1473189D03*
X1703503Y1484213D03*
X1694842Y1488544D03*
X1703503Y1499567D03*
Y1514922D03*
X1694842Y1503898D03*
Y1519252D03*
X1703503Y1555867D03*
X1694842Y1560197D03*
X1703503Y1571221D03*
X1694842Y1575552D03*
X1703503Y1586575D03*
X1694842Y1590906D03*
X1703503Y1601930D03*
X1694842Y1606260D03*
X1703503Y1617284D03*
X1694842Y1621615D03*
X1720826Y1453504D03*
X1712165Y1457835D03*
X1720826Y1468859D03*
X1712165Y1473189D03*
X1720826Y1484213D03*
X1712165Y1488544D03*
X1720826Y1499567D03*
Y1514922D03*
X1712165Y1503898D03*
Y1519252D03*
X1720826Y1555867D03*
X1712165Y1560197D03*
X1720826Y1571221D03*
X1712165Y1575552D03*
X1720826Y1586575D03*
X1712165Y1590906D03*
X1720826Y1601930D03*
X1712165Y1606260D03*
X1720826Y1617284D03*
X1712165Y1621615D03*
X1729488Y1457835D03*
Y1473189D03*
Y1488544D03*
Y1503898D03*
Y1519252D03*
Y1560197D03*
Y1575552D03*
Y1590906D03*
Y1606260D03*
Y1621615D03*
G54D37*
X235433Y1606142D03*
X581890D03*
X1259055D03*
X1605512D03*
G54D16*
X15139Y198883D03*
Y201683D03*
X18564Y238589D03*
X6690Y1496782D03*
X34520Y213539D03*
X36201Y238714D03*
X21530Y236121D03*
X27966Y238689D03*
X27625Y663094D03*
X25818Y682139D03*
X28818D03*
X32079Y1517641D03*
X65189Y228961D03*
Y231461D03*
Y223661D03*
Y226461D03*
X54733Y231226D03*
Y228726D03*
Y223726D03*
Y226226D03*
X67622Y572842D03*
X64408Y572975D03*
X73110Y101701D03*
X78501Y110445D03*
Y115401D03*
Y129574D03*
Y124618D03*
X73158Y229286D03*
X76851Y222212D03*
Y224712D03*
X73158Y231786D03*
X75777Y585507D03*
X71184D03*
X71730Y579475D03*
X71228Y590145D03*
X75822Y590190D03*
X75684Y605443D03*
X83684D03*
X78129Y656900D03*
X72314Y680207D03*
Y683407D03*
X82714Y674707D03*
X71928Y873683D03*
X88903Y117557D03*
Y122513D03*
Y131731D03*
Y136687D03*
X94390Y293645D03*
Y290845D03*
Y288345D03*
X91890Y293645D03*
Y290845D03*
Y288345D03*
X93456Y649838D03*
X89432Y668293D03*
X92134D03*
X85614Y674707D03*
X87714Y684607D03*
X117501Y198883D03*
Y201683D03*
X111275Y1008262D03*
Y1011762D03*
X130328Y238689D03*
X123892Y236121D03*
X120926Y238589D03*
X136882Y213539D03*
X138563Y238714D03*
X143186Y402291D03*
Y397335D03*
X140786Y416465D03*
Y411509D03*
Y425682D03*
Y430638D03*
Y439855D03*
Y444811D03*
Y468609D03*
Y473565D03*
Y487738D03*
Y482782D03*
Y512743D03*
Y517699D03*
Y531872D03*
Y526916D03*
X157095Y228726D03*
Y231226D03*
X167551Y223661D03*
X157095Y226226D03*
Y223726D03*
X151188Y390223D03*
Y395179D03*
Y404396D03*
Y409352D03*
Y423525D03*
Y418569D03*
Y432743D03*
Y437699D03*
Y489895D03*
Y480677D03*
Y475721D03*
Y494851D03*
Y519855D03*
Y538984D03*
Y534028D03*
Y524811D03*
X175472Y101701D03*
X175520Y229286D03*
X179213Y224712D03*
Y222212D03*
X167551Y231461D03*
Y228961D03*
Y226461D03*
X175520Y231786D03*
X194189Y103621D03*
X196752Y293645D03*
Y290845D03*
Y288345D03*
X194252Y293645D03*
Y290845D03*
Y288345D03*
X203740Y567914D03*
Y565414D03*
Y570414D03*
Y575414D03*
Y572914D03*
X219863Y198883D03*
Y201683D03*
X226254Y236121D03*
X223288Y238589D03*
X239244Y213539D03*
X232690Y238689D03*
X240925Y238714D03*
X259457Y228726D03*
Y231226D03*
Y226226D03*
Y223726D03*
X251802Y824128D03*
X277834Y101701D03*
X269913Y228961D03*
Y226461D03*
Y223661D03*
X277882Y229286D03*
X269913Y231461D03*
X277882Y231786D03*
X286129Y36971D03*
X296551Y103621D03*
X281575Y224712D03*
Y222212D03*
X296614Y293645D03*
Y290845D03*
Y288345D03*
X309106Y37543D03*
X299114Y290845D03*
Y288345D03*
Y293645D03*
X302966Y324139D03*
X310013Y316731D03*
X301158Y380307D03*
X301308Y395346D03*
X301393Y400039D03*
X322225Y198883D03*
Y201683D03*
X325650Y238589D03*
X328616Y236121D03*
X321549Y445315D03*
Y448115D03*
X323489Y471484D03*
Y466528D03*
Y480701D03*
Y485657D03*
Y515617D03*
Y510661D03*
Y529791D03*
Y524835D03*
Y565657D03*
Y560701D03*
Y574874D03*
Y579830D03*
Y589047D03*
Y594003D03*
Y603221D03*
Y608177D03*
X330905Y11806D03*
Y23806D03*
Y31806D03*
X341606Y213539D03*
X335052Y238689D03*
X343287Y238714D03*
X345050Y458334D03*
X333891Y473640D03*
Y487813D03*
Y478596D03*
Y492769D03*
Y522730D03*
Y517774D03*
Y531947D03*
Y536903D03*
Y572769D03*
Y567813D03*
Y586943D03*
Y581987D03*
Y596160D03*
Y601116D03*
Y610333D03*
Y615289D03*
X347450Y447486D03*
X353670Y488618D03*
Y491118D03*
Y493618D03*
Y496118D03*
X372275Y226461D03*
X361819Y231226D03*
Y228726D03*
Y223726D03*
Y226226D03*
X372275Y228961D03*
Y231461D03*
Y223661D03*
X364954Y450091D03*
X367564Y452740D03*
X365332Y490070D03*
Y487570D03*
X361887Y493758D03*
Y496258D03*
X377020Y782535D03*
X368491Y815092D03*
X368273Y928100D03*
X380196Y101701D03*
X380244Y229286D03*
X383937Y222212D03*
Y224712D03*
X380244Y231786D03*
X393837Y466409D03*
X393823Y487382D03*
X398913Y103621D03*
X398976Y293645D03*
X401476D03*
Y288345D03*
Y290845D03*
X398976Y288345D03*
Y290845D03*
X406843Y399161D03*
Y401661D03*
Y396661D03*
X405603Y668060D03*
X408103D03*
X403103D03*
X400603D03*
Y678060D03*
X405603D03*
X408103D03*
X403103D03*
X406967Y878764D03*
X406415Y874840D03*
X399285Y1081599D03*
X398915Y1097278D03*
X396415D03*
X401711Y1419771D03*
X406667D03*
X400911Y1537902D03*
X407048D03*
X400911Y1544424D03*
X407048Y1549936D03*
X400911D03*
X420050Y33425D03*
X418876Y401661D03*
Y396661D03*
Y399161D03*
X411754Y474513D03*
X424731Y508152D03*
Y513452D03*
Y515952D03*
X414275Y508217D03*
Y510717D03*
Y515717D03*
Y513217D03*
X424731Y510952D03*
X410603Y668060D03*
Y678060D03*
X425759Y869921D03*
Y872721D03*
Y875521D03*
Y867121D03*
Y878321D03*
X411214Y892109D03*
X413012Y1537902D03*
Y1544098D03*
X426196Y1534087D03*
X413012Y1549936D03*
X421616Y1549885D03*
X442704Y506427D03*
X427693Y506520D03*
X438353Y508685D03*
X427693Y509020D03*
X432700Y516277D03*
X429210Y784833D03*
X428759Y869921D03*
Y867121D03*
Y872721D03*
Y875521D03*
Y878321D03*
X432332Y892049D03*
Y897649D03*
Y894849D03*
Y900449D03*
X453544Y461961D03*
X451144Y472809D03*
X447836Y711199D03*
X451889Y1301067D03*
X456832Y1299121D03*
X451889Y1306023D03*
X472226Y198883D03*
Y201683D03*
X473658Y467215D03*
X471048Y464566D03*
X469495Y1011303D03*
Y1023303D03*
Y1017303D03*
X491607Y213539D03*
X478617Y236121D03*
X475651Y238589D03*
X485053Y238689D03*
X481495Y1011303D03*
X475495D03*
X481495Y1023303D03*
Y1017303D03*
X475495Y1023303D03*
X484800Y1302000D03*
X493288Y238714D03*
X522276Y223661D03*
Y226461D03*
Y228961D03*
Y231461D03*
X511820Y231226D03*
Y228726D03*
Y223726D03*
Y226226D03*
X521494Y572975D03*
X524475Y952290D03*
X509471Y981608D03*
X517374Y1287222D03*
X514363Y1287370D03*
X520548Y1287181D03*
X530197Y101701D03*
X530245Y229286D03*
X533938Y222212D03*
Y224712D03*
X530245Y231786D03*
X524708Y572842D03*
X532863Y585507D03*
X528270D03*
X528816Y579475D03*
X532908Y590190D03*
X528314Y590145D03*
X532770Y605443D03*
X528868Y873683D03*
X548914Y103621D03*
X551477Y288345D03*
Y290845D03*
X548977Y288345D03*
Y290845D03*
Y293645D03*
X551477D03*
X540770Y605443D03*
X574588Y201683D03*
X568362Y1008262D03*
Y1011762D03*
X574588Y198883D03*
X587415Y238689D03*
X580979Y236121D03*
X578013Y238589D03*
X577249Y965445D03*
X593969Y213539D03*
X595650Y238714D03*
X600272Y397335D03*
Y402291D03*
X597872Y425682D03*
Y416465D03*
Y411509D03*
Y439855D03*
Y430638D03*
Y444811D03*
Y468609D03*
Y473565D03*
Y487738D03*
Y482782D03*
Y517699D03*
Y531872D03*
Y526916D03*
X606142Y965665D03*
X614182Y223726D03*
Y226226D03*
Y231226D03*
Y228726D03*
X608274Y390223D03*
Y395179D03*
Y404396D03*
Y409352D03*
Y418569D03*
Y423525D03*
Y432743D03*
Y437699D03*
Y489895D03*
Y480677D03*
Y475721D03*
Y494851D03*
Y519855D03*
Y538984D03*
Y534028D03*
Y524811D03*
X632559Y101701D03*
X624638Y231461D03*
X636300Y222212D03*
Y224712D03*
X632607Y229286D03*
X624638Y223661D03*
Y226461D03*
Y228961D03*
X632607Y231786D03*
X651276Y103621D03*
X651339Y290845D03*
Y293645D03*
X653839D03*
Y288345D03*
Y290845D03*
X651339Y288345D03*
X660826Y570414D03*
Y567914D03*
Y565414D03*
Y575414D03*
Y572914D03*
X676950Y201683D03*
X680375Y238589D03*
X683341Y236121D03*
X696331Y213539D03*
X698012Y238714D03*
X689777Y238689D03*
X716544Y228726D03*
Y231226D03*
Y226226D03*
Y223726D03*
X704446Y760611D03*
X713425Y786029D03*
X734921Y101701D03*
X727000Y228961D03*
Y226461D03*
Y223661D03*
X734969Y229286D03*
X727000Y231461D03*
X734969Y231786D03*
X721218Y742131D03*
X720271Y782481D03*
X738662Y224712D03*
Y222212D03*
X744069Y746617D03*
X735576Y861780D03*
X753638Y103621D03*
X760407Y324494D03*
X767099Y316731D03*
X767310Y1599164D03*
X756358Y1616917D03*
X779312Y198883D03*
Y201683D03*
X782737Y238589D03*
X780575Y471484D03*
Y466528D03*
Y480701D03*
Y485657D03*
Y510661D03*
Y515617D03*
Y524835D03*
Y529791D03*
Y560701D03*
Y565657D03*
Y579830D03*
Y574874D03*
Y589047D03*
Y594003D03*
Y603221D03*
Y608177D03*
X798693Y213539D03*
X792139Y238689D03*
X785703Y236121D03*
X790977Y473640D03*
Y487813D03*
Y478596D03*
Y492769D03*
Y517774D03*
Y522730D03*
Y531947D03*
Y536903D03*
Y567813D03*
Y572769D03*
Y581987D03*
Y586943D03*
Y601116D03*
Y596160D03*
Y615289D03*
Y610333D03*
X800374Y238714D03*
X804536Y441486D03*
X802136Y452334D03*
X810756Y491118D03*
Y488618D03*
Y483618D03*
Y486118D03*
X815492Y732917D03*
X829362Y231461D03*
Y228961D03*
Y226461D03*
Y223661D03*
X818906Y228726D03*
Y231226D03*
Y226226D03*
Y223726D03*
X829381Y348036D03*
X824650Y446740D03*
X822040Y444091D03*
X826262Y462326D03*
Y459326D03*
X818973Y491258D03*
Y488758D03*
X822418Y485070D03*
Y482570D03*
X823790Y713375D03*
X823843Y732109D03*
X819890Y736924D03*
X828423Y964731D03*
X837283Y101701D03*
X837331Y229286D03*
X841024Y224712D03*
Y222212D03*
X837331Y231786D03*
X839573Y325327D03*
X856000Y103621D03*
X858563Y293645D03*
Y290845D03*
X856063Y293645D03*
Y290845D03*
X858563Y288345D03*
X856063D03*
X854622Y359004D03*
X873885Y340892D03*
X873733Y357844D03*
X871382Y373971D03*
X875907Y486256D03*
X870137Y669461D03*
X875916Y808965D03*
X886026Y346584D03*
X896592Y362369D03*
Y366369D03*
Y370369D03*
X882907Y480350D03*
X892023Y570176D03*
X890959Y579788D03*
X890956Y588325D03*
X894015Y588253D03*
X895933Y618143D03*
X910076Y304843D03*
X905120D03*
X913206Y336489D03*
X910040Y353532D03*
X902169Y413002D03*
Y418002D03*
Y415502D03*
X913853Y561487D03*
X904393Y570176D03*
X908517D03*
X898815D03*
X898232Y588320D03*
X902635Y588305D03*
X906999Y588274D03*
X905313Y709259D03*
X905050Y720268D03*
X913716Y800815D03*
X899916D03*
X911053Y800510D03*
X901428Y1136426D03*
X904897Y1145169D03*
X902397D03*
X929978Y186854D03*
Y184054D03*
X917906Y321670D03*
X922629Y336609D03*
X922198Y342051D03*
X917858Y331453D03*
X927309Y357267D03*
X921389D03*
X915395D03*
Y363212D03*
X927309Y363239D03*
Y369210D03*
X921468D03*
X915395D03*
X927072Y386992D03*
X919072D03*
X923072D03*
X914202Y418002D03*
Y413002D03*
Y415502D03*
X916590Y800636D03*
X921790Y810965D03*
X926044Y1545370D03*
Y1542370D03*
X938125Y230891D03*
X942805Y223860D03*
X936369Y221292D03*
X940158Y245707D03*
X946064Y252998D03*
X941845Y278968D03*
X939606Y310521D03*
X939653Y317474D03*
X940924Y328959D03*
X936608Y326058D03*
X945120Y326441D03*
X930398Y342050D03*
X936453Y345336D03*
X945599Y345383D03*
X940972Y338238D03*
X943663Y355674D03*
X944900Y363700D03*
X938499Y362202D03*
X940600Y370600D03*
X939314Y707847D03*
X931244Y720471D03*
X936026Y730600D03*
X941916Y808965D03*
X949359Y198710D03*
X951040Y223885D03*
X956348Y356371D03*
X952170Y356131D03*
X958823Y362802D03*
X954888Y369513D03*
X948400Y370045D03*
X956035Y1545333D03*
X959035D03*
X953035D03*
X950035D03*
X959035Y1542333D03*
X956035D03*
X953035D03*
X950035D03*
X968906Y223726D03*
Y228726D03*
Y231226D03*
X979362Y223661D03*
X968906Y226226D03*
X973338Y345018D03*
X978581Y572975D03*
X971144Y908972D03*
X965405Y1136426D03*
X987283Y101701D03*
X987331Y229286D03*
X991024Y224712D03*
Y222212D03*
X979362Y231461D03*
Y228961D03*
Y226461D03*
X987331Y231786D03*
X992045Y366559D03*
X984045D03*
X988045D03*
X981795Y572842D03*
X985903Y579475D03*
X985357Y585507D03*
X989950D03*
X985401Y590145D03*
X989995Y590190D03*
X989857Y605443D03*
X983712Y722064D03*
X1006000Y103621D03*
X1008563Y293645D03*
X1006063D03*
Y290845D03*
Y288345D03*
X1008563Y290845D03*
Y288345D03*
X997857Y605443D03*
X1010606Y1547824D03*
X1010659Y1568771D03*
Y1565771D03*
X1010653Y1571669D03*
X1021451Y322879D03*
X1026032Y322906D03*
X1018238Y678647D03*
X1018155Y684132D03*
X1025116Y698332D03*
X1024932Y717856D03*
X1016320Y828481D03*
X1026340Y917761D03*
X1025448Y1008262D03*
Y1011762D03*
X1013606Y1547824D03*
X1016606D03*
X1019606D03*
X1013659Y1568771D03*
X1016659D03*
X1019659D03*
X1013659Y1565771D03*
X1016659D03*
X1019659D03*
X1013653Y1571669D03*
X1016653D03*
X1019653D03*
X1031674Y198883D03*
Y201683D03*
X1038065Y236121D03*
X1035099Y238589D03*
X1030184Y288709D03*
X1038068Y298789D03*
X1033112D03*
X1030753Y732213D03*
X1051055Y213539D03*
X1044501Y238689D03*
X1052736Y238714D03*
X1048695Y280161D03*
X1057359Y402291D03*
Y397335D03*
X1054959Y411509D03*
Y425682D03*
Y416465D03*
Y430638D03*
Y439855D03*
Y444811D03*
Y468609D03*
Y473565D03*
Y487738D03*
Y482782D03*
Y517699D03*
Y512743D03*
Y531872D03*
Y526916D03*
X1071268Y226226D03*
Y223726D03*
Y228726D03*
Y231226D03*
X1065361Y390223D03*
Y395179D03*
Y404396D03*
Y409352D03*
Y423525D03*
Y418569D03*
Y432743D03*
Y437699D03*
Y489895D03*
Y480677D03*
Y475721D03*
Y494851D03*
Y519855D03*
Y524811D03*
Y538984D03*
Y534028D03*
X1089645Y101701D03*
X1081724Y226461D03*
Y223661D03*
X1089693Y229286D03*
X1081724Y231461D03*
Y228961D03*
X1089693Y231786D03*
X1079863Y345660D03*
X1090747Y1617415D03*
X1108362Y103621D03*
X1093386Y224712D03*
Y222212D03*
X1108425Y293645D03*
Y290845D03*
Y288345D03*
X1096264Y1562285D03*
X1093713Y1585583D03*
X1110925Y293645D03*
Y290845D03*
Y288345D03*
X1117913Y565414D03*
Y567914D03*
Y570414D03*
Y572914D03*
Y575414D03*
X1122718Y598857D03*
X1121191Y612555D03*
X1120512Y617332D03*
X1121022Y607750D03*
X1134036Y198883D03*
Y201683D03*
X1137461Y238589D03*
X1140427Y236121D03*
X1138166Y534759D03*
X1153417Y213539D03*
X1146863Y238689D03*
X1155098Y238714D03*
X1149437Y728541D03*
X1152316Y746625D03*
X1173630Y226226D03*
Y223726D03*
Y228726D03*
Y231226D03*
X1161274Y550462D03*
X1170603Y715281D03*
X1163751Y719498D03*
X1168577Y733812D03*
X1169266Y800799D03*
X1184086Y231461D03*
Y228961D03*
Y226461D03*
Y223661D03*
X1176577Y885974D03*
X1188431Y936568D03*
X1192007Y101701D03*
X1192055Y229286D03*
X1195748Y224712D03*
Y222212D03*
X1192055Y231786D03*
X1192990Y914873D03*
X1195118Y936296D03*
X1210724Y103621D03*
X1213287Y293645D03*
Y290845D03*
Y288345D03*
X1210787Y293645D03*
Y290845D03*
Y288345D03*
X1217139Y324139D03*
X1222909Y-83456D03*
Y-78500D03*
Y-68500D03*
Y-73456D03*
X1228265Y-44406D03*
Y-39450D03*
Y-29450D03*
Y-34406D03*
X1236398Y198883D03*
Y201683D03*
X1224186Y316731D03*
X1237662Y466528D03*
Y471484D03*
Y480701D03*
Y485657D03*
Y515617D03*
Y510661D03*
Y524835D03*
Y529791D03*
Y565657D03*
Y560701D03*
Y589047D03*
Y574874D03*
Y579830D03*
Y603221D03*
Y594003D03*
Y608177D03*
X1239823Y238589D03*
X1242789Y236121D03*
X1248064Y473640D03*
Y487813D03*
Y478596D03*
Y492769D03*
Y517774D03*
Y522730D03*
Y531947D03*
Y536903D03*
X1255779Y213539D03*
X1257460Y238714D03*
X1264481Y300223D03*
X1261623Y447486D03*
X1259223Y458334D03*
X1267843Y488618D03*
Y491118D03*
Y493618D03*
X1275992Y223726D03*
Y226226D03*
Y231226D03*
Y228726D03*
X1286448Y223661D03*
Y226461D03*
Y228961D03*
Y231461D03*
X1279127Y450091D03*
X1281737Y452740D03*
X1279505Y487570D03*
Y490070D03*
X1276060Y496258D03*
Y493758D03*
X1294369Y101701D03*
X1294417Y229286D03*
X1298110Y222212D03*
Y224712D03*
X1294417Y231786D03*
X1313086Y103621D03*
X1313149Y288345D03*
Y290845D03*
Y293645D03*
X1315649Y288345D03*
Y290845D03*
Y293645D03*
X1308010Y466409D03*
X1307996Y487382D03*
X1313459Y1081599D03*
X1310589Y1097278D03*
X1313089D03*
X1334223Y33425D03*
X1333049Y399268D03*
Y401768D03*
Y396768D03*
X1321016Y399161D03*
Y401661D03*
Y396661D03*
X1325927Y474513D03*
X1386399Y201683D03*
X1383669Y1011303D03*
Y1017303D03*
Y1023303D03*
X1386399Y198883D03*
X1399226Y238689D03*
X1392790Y236121D03*
X1389824Y238589D03*
X1395669Y1011303D03*
X1389669D03*
X1395669Y1017303D03*
Y1023303D03*
X1389669D03*
X1405780Y213539D03*
X1407461Y238714D03*
X1425993Y231226D03*
Y228726D03*
Y226226D03*
Y223726D03*
X1444370Y101701D03*
X1436449Y228961D03*
X1444418Y229286D03*
X1436449Y226461D03*
Y223661D03*
X1448111Y222212D03*
Y224712D03*
X1436449Y231461D03*
X1444418Y231786D03*
X1438882Y572842D03*
X1447037Y585507D03*
X1442444D03*
X1442990Y579475D03*
X1435668Y572975D03*
X1442488Y590145D03*
X1447082Y590190D03*
X1446944Y605443D03*
X1443041Y873683D03*
X1463087Y103621D03*
X1465650Y293645D03*
Y288345D03*
Y290845D03*
X1463150Y288345D03*
Y290845D03*
Y293645D03*
X1454944Y605443D03*
X1479409Y-83456D03*
Y-78500D03*
Y-68500D03*
Y-73456D03*
X1476822Y40780D03*
X1498621Y15043D03*
Y35043D03*
Y27043D03*
X1488761Y198883D03*
Y201683D03*
X1492186Y238589D03*
X1495152Y236121D03*
X1483813Y368516D03*
X1482535Y1008262D03*
Y1002453D03*
Y1011762D03*
X1514765Y-44536D03*
Y-39580D03*
Y-29580D03*
Y-34536D03*
X1508142Y213539D03*
X1509823Y238714D03*
X1501588Y238689D03*
X1514446Y402291D03*
Y397335D03*
X1512046Y411509D03*
Y425682D03*
Y416465D03*
Y439855D03*
Y430638D03*
Y444811D03*
Y468609D03*
Y473565D03*
Y487738D03*
Y482782D03*
Y517699D03*
Y512743D03*
Y531872D03*
Y526916D03*
X1528355Y228726D03*
Y223726D03*
Y226226D03*
Y231226D03*
X1515779Y351594D03*
X1522448Y390223D03*
Y395179D03*
Y404396D03*
Y409352D03*
Y423525D03*
Y418569D03*
Y437699D03*
Y432743D03*
Y489895D03*
Y480677D03*
Y475721D03*
Y494851D03*
Y519855D03*
Y538984D03*
Y534028D03*
Y524811D03*
X1546732Y101701D03*
X1538811Y226461D03*
Y228961D03*
Y231461D03*
X1546780Y229286D03*
X1538811Y223661D03*
X1546780Y231786D03*
X1550473Y222212D03*
Y224712D03*
X1565449Y103621D03*
X1565512Y288345D03*
X1568012Y293645D03*
Y290845D03*
Y288345D03*
X1565512Y293645D03*
Y290845D03*
X1575000Y565414D03*
Y567914D03*
Y570414D03*
Y572914D03*
Y575414D03*
X1579753Y599100D03*
X1578679Y613047D03*
X1578114Y607563D03*
X1591123Y198883D03*
Y201683D03*
X1594548Y238589D03*
X1610504Y213539D03*
X1597514Y236121D03*
X1612185Y238714D03*
X1603950Y238689D03*
X1641173Y231461D03*
X1630717Y223726D03*
Y226226D03*
Y231226D03*
Y228726D03*
X1641173Y223661D03*
Y226461D03*
Y228961D03*
X1649094Y101701D03*
X1649142Y229286D03*
X1652835Y222212D03*
Y224712D03*
X1649142Y231786D03*
X1667811Y103621D03*
X1670374Y290845D03*
Y288345D03*
X1667874Y290845D03*
Y288345D03*
X1670374Y293645D03*
X1667874D03*
X1674226Y324139D03*
X1693485Y198883D03*
Y201683D03*
X1681273Y316731D03*
X1699876Y236121D03*
X1696910Y238589D03*
X1706312Y238689D03*
X1694749Y466528D03*
Y471484D03*
X1705151Y473640D03*
Y487813D03*
Y478596D03*
X1694749Y480701D03*
Y485657D03*
X1705151Y492769D03*
Y517774D03*
Y522730D03*
X1694749Y510661D03*
Y515617D03*
X1705151Y536903D03*
Y531947D03*
X1694749Y524835D03*
Y529791D03*
X1705151Y572769D03*
Y567813D03*
X1694749Y565657D03*
Y560701D03*
Y579830D03*
X1705151Y586943D03*
Y581987D03*
X1694749Y589047D03*
Y574874D03*
Y603221D03*
X1705151Y601116D03*
Y596160D03*
X1694749Y594003D03*
X1705151Y615289D03*
X1694749Y608177D03*
X1705151Y610333D03*
X1712866Y213539D03*
X1714547Y238714D03*
X1718710Y447486D03*
X1716310Y458334D03*
X1724930Y491118D03*
Y488618D03*
Y493618D03*
Y496118D03*
X1733909Y-83456D03*
Y-78500D03*
Y-68500D03*
Y-73456D03*
X1733079Y223726D03*
Y226226D03*
Y231226D03*
Y228726D03*
X1743535Y223661D03*
X1738824Y452740D03*
X1736214Y450091D03*
X1736592Y487570D03*
Y490070D03*
X1733147Y493758D03*
Y496258D03*
X1751456Y101701D03*
X1743535Y226461D03*
X1755197Y224712D03*
X1743535Y228961D03*
Y231461D03*
X1751504Y229286D03*
X1755197Y222212D03*
X1751504Y231786D03*
X1770173Y103621D03*
X1772736Y293645D03*
X1770236D03*
Y290845D03*
Y288345D03*
X1772736Y290845D03*
Y288345D03*
X1765097Y466409D03*
X1765083Y487382D03*
X1772768Y818696D03*
X1790136Y399161D03*
Y401661D03*
Y396661D03*
X1778103Y399161D03*
Y401661D03*
Y396661D03*
X1783014Y474513D03*
X1778801Y836469D03*
X1786256Y927626D03*
X1784306Y924601D03*
X1786256Y930626D03*
X1799265Y-44666D03*
Y-39710D03*
Y-29710D03*
Y-34666D03*
X1791302Y829031D03*
X1816385Y1136912D03*
X1813885D03*
Y1144912D03*
X1816385D03*
G54D20*
X51043Y60709D03*
Y150197D03*
X153405Y60709D03*
Y150197D03*
X255767Y60709D03*
Y150197D03*
X279360Y368760D03*
Y421555D03*
Y501752D03*
Y550020D03*
Y636752D03*
X358129Y60709D03*
Y150197D03*
X508130Y60709D03*
Y150197D03*
X610492Y60709D03*
Y150197D03*
X712854Y60709D03*
Y150197D03*
X736446Y368760D03*
Y421555D03*
Y501752D03*
Y550020D03*
Y636752D03*
X815216Y60709D03*
Y150197D03*
X965216Y60709D03*
Y150197D03*
X1067578Y60709D03*
Y150197D03*
X1169940Y60709D03*
Y150197D03*
X1193533Y368760D03*
Y421555D03*
Y501752D03*
Y550020D03*
Y636752D03*
X1272302Y60709D03*
Y150197D03*
X1422303Y60709D03*
Y150197D03*
X1524665Y60709D03*
Y150197D03*
X1627027Y60709D03*
Y150197D03*
X1650620Y368760D03*
Y421555D03*
Y501752D03*
Y550020D03*
Y636752D03*
X1729389Y60709D03*
Y150197D03*
G54D46*
X843012Y1592787D03*
Y1602787D03*
Y1612787D03*
Y1622787D03*
X853012Y1592787D03*
Y1602787D03*
Y1612787D03*
Y1622787D03*
X878012Y1592787D03*
Y1602787D03*
Y1612787D03*
Y1622787D03*
X888012Y1592787D03*
Y1602787D03*
Y1612787D03*
Y1622787D03*
X913012Y1592787D03*
Y1602787D03*
Y1612787D03*
Y1622787D03*
X923012Y1592787D03*
Y1602787D03*
Y1612787D03*
Y1622787D03*
X948012Y1592787D03*
Y1602787D03*
Y1612787D03*
Y1622787D03*
X958012Y1592787D03*
Y1602787D03*
Y1612787D03*
Y1622787D03*
X983012Y1592787D03*
X993012D03*
X983012Y1602787D03*
Y1612787D03*
X993012Y1602787D03*
Y1612787D03*
X983012Y1622787D03*
X993012D03*
X1018012Y1592787D03*
X1028012D03*
X1018012Y1602787D03*
Y1612787D03*
X1028012Y1602787D03*
Y1612787D03*
X1018012Y1622787D03*
X1028012D03*
G54D12*
X3035Y1578036D03*
X3017Y1639466D03*
X14751Y62381D03*
X12601Y92110D03*
X9364Y107501D03*
X16728Y107910D03*
X12652Y116894D03*
X13615Y153263D03*
X10966Y155873D03*
Y152873D03*
X12709Y175777D03*
X9745Y245784D03*
X19075Y278429D03*
X7036Y268371D03*
X14252Y1121333D03*
X11552D03*
X16752D03*
X8952D03*
X14152Y1111633D03*
X11452D03*
X8852D03*
X16652D03*
X14252Y1130333D03*
X16752D03*
X14306Y1138705D03*
X16806D03*
X20079Y1429347D03*
X12327Y1519202D03*
X11995Y1535134D03*
X6567Y1554215D03*
X14375Y1553121D03*
X18409Y1554202D03*
X12000Y1644980D03*
X33288Y109410D03*
Y116497D03*
X30788D03*
X25988D03*
X22439Y106495D03*
X30788Y123584D03*
X33288Y123583D03*
X25988Y123584D03*
X33288Y130670D03*
X30788D03*
X25988D03*
X30788Y137757D03*
X25988D03*
X29201Y151651D03*
X26201D03*
X20709Y175777D03*
X28740Y247292D03*
X21449Y253198D03*
X28740Y267292D03*
X21386Y273198D03*
X23479Y295619D03*
X32452Y581222D03*
X29652D03*
X35252D03*
Y591215D03*
X29652D03*
X32452D03*
X34254Y611091D03*
X29451Y633560D03*
X30369Y663048D03*
X27854Y671553D03*
X30414Y671508D03*
X26596Y874520D03*
X26844Y920354D03*
X24132Y958151D03*
X25371Y980696D03*
X34314Y1215403D03*
X22284Y1464612D03*
X32079Y1525641D03*
X35237Y1532096D03*
X35850Y1556096D03*
X32000Y1644980D03*
X46450Y82984D03*
Y77784D03*
Y75184D03*
Y80384D03*
X48364Y92473D03*
X46450Y85584D03*
X37988Y109410D03*
Y102323D03*
Y116496D03*
Y130670D03*
Y123583D03*
X52437Y137756D03*
X37988D03*
X45984Y163264D03*
X37284Y285272D03*
X42690Y451466D03*
X48596Y458466D03*
X39643Y555194D03*
X36843D03*
X39643Y563194D03*
X36843D03*
X39643Y571194D03*
X36843D03*
X49265Y886660D03*
X52922Y900295D03*
X47916Y947622D03*
X50366Y1086981D03*
Y1082388D03*
X38200Y1089721D03*
X44365Y1086404D03*
X38216Y1093757D03*
X49500Y1199066D03*
X51197Y1218206D03*
X39452Y1250932D03*
X48195Y1511279D03*
X48079Y1525641D03*
Y1529641D03*
Y1521641D03*
X52048Y1556062D03*
X52000Y1644980D03*
X56098Y109410D03*
Y116496D03*
X55964Y103037D03*
X56098Y123583D03*
Y130670D03*
X68896Y226141D03*
X58279Y293796D03*
X66293Y285690D03*
X68793D03*
X66293Y288190D03*
X68793D03*
X60779Y293796D03*
X65759Y437508D03*
X61759D03*
X57759D03*
X54936Y449352D03*
X59522Y448874D03*
X68619Y447269D03*
X68497Y450201D03*
X64550Y504699D03*
X62050D03*
X59550D03*
X68236Y519458D03*
X61752Y516979D03*
X64252D03*
X59252D03*
X55318Y629362D03*
X53129Y627948D03*
X55307Y688473D03*
X66342Y880067D03*
X67316Y865869D03*
X64175Y897500D03*
X67461Y912983D03*
X63303Y912835D03*
X57178Y981386D03*
X69263Y1053152D03*
X55049Y1082343D03*
X55004Y1086937D03*
X58981Y1105100D03*
X56381D03*
X61581D03*
X64281D03*
X61681Y1114800D03*
X56481D03*
X59081D03*
X64381D03*
X57218Y1123867D03*
X55397Y1133688D03*
X57897D03*
X58250Y1220896D03*
X65940Y1209382D03*
X58250Y1227796D03*
Y1230296D03*
Y1237196D03*
Y1234696D03*
Y1223396D03*
X57185Y1480808D03*
X57144Y1491047D03*
X56114Y1556061D03*
X68743Y1583498D03*
X73381Y94017D03*
X69381D03*
X71422Y151540D03*
X75072Y191941D03*
X81572Y184619D03*
X74939Y188727D03*
X83552Y206760D03*
X71696Y226141D03*
X76766Y256535D03*
X84766D03*
X71593Y285690D03*
Y288190D03*
X75819Y290755D03*
X79819D03*
X83819D03*
X71826Y480705D03*
X75736Y519458D03*
X73236D03*
X70736D03*
X81740Y636250D03*
X69670Y633205D03*
Y636005D03*
X81740Y633450D03*
X69670Y638805D03*
X81740Y639050D03*
X74414Y681907D03*
X76991Y946134D03*
X84679Y1018368D03*
X70059Y1071656D03*
X69373Y1063389D03*
X70059Y1079656D03*
X80290Y1345691D03*
Y1350683D03*
X75334Y1345691D03*
Y1350683D03*
X80290Y1357603D03*
Y1362595D03*
X75334Y1357603D03*
Y1362595D03*
X80290Y1381801D03*
Y1369889D03*
Y1374881D03*
X75334Y1381801D03*
Y1374881D03*
Y1369889D03*
X80290Y1386793D03*
X75334D03*
X87000Y1597855D03*
X76005Y1580680D03*
X82433Y1580590D03*
X72000Y1644980D03*
X88080Y103603D03*
X87002Y146461D03*
X85904Y152367D03*
X87604Y180572D03*
X92287Y180527D03*
X96010Y192421D03*
X92242Y185121D03*
X87604Y185165D03*
X85796Y279208D03*
X89900Y281307D03*
X90257Y445506D03*
X88875Y840940D03*
X91581Y877859D03*
Y874859D03*
X87853Y899220D03*
X91128Y1006487D03*
X99836Y997860D03*
X95836D03*
X100594Y1035088D03*
X97247Y1030568D03*
X103124Y1165091D03*
X87574Y1345691D03*
Y1350683D03*
X99814D03*
Y1345691D03*
X92530D03*
Y1350683D03*
X87574Y1362595D03*
Y1357603D03*
X99814Y1362595D03*
Y1357603D03*
X92530Y1362595D03*
Y1357603D03*
X87574Y1374881D03*
Y1369795D03*
Y1381801D03*
X99814D03*
Y1374881D03*
Y1369889D03*
X92530Y1374881D03*
Y1369795D03*
Y1381801D03*
X87574Y1399079D03*
Y1393993D03*
Y1386793D03*
X99814Y1399079D03*
Y1394087D03*
Y1386793D03*
X92530Y1393993D03*
Y1399079D03*
Y1386793D03*
X87574Y1410991D03*
Y1405999D03*
X99814Y1410991D03*
Y1405999D03*
X92530Y1410991D03*
Y1405999D03*
X92000Y1644980D03*
X107364Y113394D03*
Y110394D03*
X110013Y110784D03*
X110152Y130898D03*
X117607Y133298D03*
X111754Y134579D03*
X107540Y172665D03*
Y180665D03*
X107572Y200864D03*
Y212864D03*
Y216864D03*
Y221864D03*
X109329Y252371D03*
X112474Y716315D03*
X114397Y727974D03*
X113601Y881266D03*
X107641Y865224D03*
X103836Y997860D03*
X111836D03*
X114770Y1009354D03*
X107836Y997860D03*
X115836D03*
X108933Y1102091D03*
X112433D03*
X103124D03*
X112433Y1114691D03*
X103124D03*
X108933D03*
Y1127291D03*
X112433D03*
X103124D03*
X112433Y1139891D03*
X103124Y1152491D03*
X108933D03*
X112433D03*
X108933Y1165091D03*
X112433D03*
X103184Y1177691D03*
X108933D03*
X112433D03*
X109415Y1202103D03*
X112795Y1223749D03*
X104770Y1350683D03*
Y1345691D03*
X112054D03*
Y1350683D03*
X117010Y1345691D03*
Y1350683D03*
X104770Y1362595D03*
Y1357603D03*
X112054Y1362595D03*
Y1357603D03*
X117010Y1362595D03*
Y1357603D03*
Y1369889D03*
Y1374881D03*
Y1381801D03*
X104770D03*
Y1374881D03*
Y1369889D03*
X112054D03*
Y1374881D03*
Y1381801D03*
X104770Y1399079D03*
Y1394087D03*
Y1386793D03*
X112054Y1399079D03*
Y1394087D03*
Y1386793D03*
X117010Y1394087D03*
Y1399079D03*
Y1386793D03*
X104770Y1410991D03*
Y1405999D03*
X112054Y1410991D03*
Y1405999D03*
X117010Y1410991D03*
Y1405999D03*
X107669Y1456451D03*
Y1465913D03*
X116330Y1465513D03*
X107669Y1461182D03*
X116330Y1460782D03*
X107669Y1481267D03*
X116330Y1480867D03*
X107669Y1476536D03*
X116330Y1476136D03*
Y1470244D03*
X107669Y1471805D03*
X116330Y1491490D03*
Y1485598D03*
X107669Y1487159D03*
Y1496621D03*
X116330Y1496221D03*
X107669Y1491890D03*
X116330Y1506845D03*
Y1500952D03*
X107669Y1502514D03*
X116330Y1511576D03*
X107669Y1511976D03*
Y1507245D03*
X116330Y1516307D03*
X107669Y1563544D03*
X116330Y1563144D03*
X107669Y1558813D03*
Y1568275D03*
X116330Y1567875D03*
X107669Y1578898D03*
X116330Y1578498D03*
Y1572606D03*
X107669Y1574167D03*
Y1583629D03*
X116330Y1583229D03*
X107669Y1594253D03*
X116330Y1593853D03*
Y1587960D03*
X107669Y1589522D03*
Y1609607D03*
X116330Y1609207D03*
X107669Y1598984D03*
X116330Y1598584D03*
Y1603315D03*
X107669Y1604876D03*
X116330Y1613938D03*
Y1618669D03*
X107669Y1614338D03*
X112000Y1644980D03*
X128350Y116497D03*
X133150D03*
X124606Y106495D03*
X125599Y109172D03*
X122599D03*
X133150Y123584D03*
X128350D03*
X133150Y130670D03*
X128350D03*
Y137757D03*
X133150D03*
X126246Y141228D03*
X124340Y146012D03*
X129134Y150847D03*
X131102Y247292D03*
X123811Y253198D03*
X125125Y362403D03*
X118122Y747565D03*
X122887Y884000D03*
X127067Y891495D03*
X124079Y1009354D03*
X119836Y997860D03*
X131836D03*
X127836D03*
X123836D03*
X120579Y1009354D03*
Y1021954D03*
X124079D03*
X133870Y1105091D03*
Y1117691D03*
Y1130291D03*
Y1142891D03*
Y1155491D03*
Y1168091D03*
X121211Y1215195D03*
X126937Y1209607D03*
X124294Y1350683D03*
Y1345691D03*
X129250Y1350683D03*
Y1345691D03*
X124294Y1362595D03*
Y1357603D03*
X129250D03*
Y1362595D03*
X124294Y1374881D03*
Y1369889D03*
Y1381801D03*
X129250Y1374881D03*
Y1369889D03*
Y1381801D03*
X124294Y1394087D03*
Y1399079D03*
Y1386793D03*
X129250Y1394087D03*
Y1399079D03*
Y1386793D03*
X124294Y1405999D03*
Y1410991D03*
X129250Y1405999D03*
Y1410991D03*
X124992Y1465913D03*
Y1456451D03*
Y1461182D03*
X133653Y1465513D03*
Y1460782D03*
X124992Y1471805D03*
Y1476536D03*
Y1481267D03*
X133653Y1476136D03*
Y1470244D03*
Y1480867D03*
Y1496221D03*
X124992Y1487159D03*
Y1491890D03*
Y1496621D03*
X133653Y1491490D03*
Y1485598D03*
Y1506845D03*
Y1500952D03*
Y1511576D03*
X124992Y1511976D03*
Y1507245D03*
Y1502514D03*
X133653Y1516307D03*
X124992Y1558813D03*
Y1563544D03*
X133653Y1563144D03*
Y1567875D03*
X124992Y1574167D03*
Y1578898D03*
X133653Y1578498D03*
Y1572606D03*
X124992Y1568275D03*
Y1589522D03*
Y1594253D03*
X133653Y1593853D03*
Y1587960D03*
X124992Y1583629D03*
X133653Y1583229D03*
X124992Y1609607D03*
Y1604876D03*
Y1598984D03*
X133653Y1609207D03*
Y1598584D03*
Y1603315D03*
X124992Y1614338D03*
X133653Y1613938D03*
Y1618669D03*
X132000Y1644980D03*
X148812Y80384D03*
Y82984D03*
Y75184D03*
Y77784D03*
Y85584D03*
X135650Y109410D03*
X140350Y116496D03*
Y109410D03*
Y102323D03*
X135650Y116497D03*
Y123583D03*
Y130670D03*
X140350D03*
Y123583D03*
Y137756D03*
X136604Y450750D03*
X140703Y536382D03*
X145670Y597580D03*
X147893Y599588D03*
X147155Y589556D03*
X147094Y592354D03*
X145609Y594668D03*
X147896Y596095D03*
X147925Y615600D03*
X147893Y607588D03*
X139836Y997860D03*
X147836D03*
X143836D03*
X135836D03*
X145516Y1024954D03*
Y1012354D03*
X148534Y1046476D03*
X134457Y1180654D03*
X141490Y1345691D03*
Y1350683D03*
X136534D03*
Y1345691D03*
X148774Y1350683D03*
Y1345691D03*
X141490Y1357603D03*
Y1362595D03*
X136534D03*
Y1357603D03*
X148774D03*
Y1362595D03*
X141490Y1369889D03*
Y1374881D03*
Y1381801D03*
X136534Y1369889D03*
Y1381801D03*
Y1374881D03*
X148774Y1369889D03*
Y1381801D03*
Y1374881D03*
X141490Y1386793D03*
Y1394087D03*
Y1399079D03*
X136534D03*
Y1394087D03*
Y1386793D03*
X148774Y1394087D03*
Y1399079D03*
Y1386793D03*
X141490Y1405999D03*
Y1410991D03*
X136534D03*
Y1405999D03*
X148774D03*
Y1410991D03*
X142315Y1456451D03*
Y1461182D03*
Y1465913D03*
Y1471805D03*
Y1476536D03*
Y1481267D03*
Y1487159D03*
Y1491890D03*
Y1496621D03*
Y1507245D03*
Y1502514D03*
Y1511976D03*
Y1558813D03*
Y1563544D03*
Y1574167D03*
Y1578898D03*
Y1568275D03*
Y1589522D03*
Y1594253D03*
Y1583629D03*
Y1609607D03*
Y1604876D03*
Y1598984D03*
Y1614338D03*
X151366Y92849D03*
X158460Y116496D03*
X158326Y103037D03*
X158460Y109410D03*
Y130670D03*
Y123583D03*
X155051Y137756D03*
X163141Y293796D03*
X160641D03*
X166528Y312392D03*
X157375Y555234D03*
X157090Y562003D03*
X152386Y634946D03*
X151836Y997860D03*
X159836D03*
X164028Y1041468D03*
X155513Y1065148D03*
X161014Y1345691D03*
Y1350683D03*
X153730Y1345691D03*
Y1350683D03*
X165970Y1345691D03*
Y1350683D03*
X161014Y1362595D03*
Y1357603D03*
X153730Y1362595D03*
Y1357603D03*
X165970Y1362595D03*
Y1357603D03*
X161014Y1381801D03*
Y1369889D03*
Y1374881D03*
X153730Y1369889D03*
Y1381801D03*
Y1374881D03*
X165970D03*
Y1381801D03*
Y1369889D03*
X161014Y1394087D03*
Y1386793D03*
X153730Y1394087D03*
Y1386793D03*
X165970Y1394087D03*
Y1386793D03*
X161014Y1399079D03*
X153730D03*
X165970D03*
X161014Y1410991D03*
Y1405999D03*
X153730D03*
Y1410991D03*
X165970D03*
Y1405999D03*
X159637Y1461182D03*
X150976Y1465513D03*
Y1460782D03*
X159637Y1465913D03*
Y1456451D03*
X150976Y1476136D03*
Y1470244D03*
Y1480867D03*
X159637Y1471805D03*
Y1476536D03*
Y1481267D03*
Y1496621D03*
X150976Y1491490D03*
Y1485598D03*
Y1496221D03*
X159637Y1487159D03*
Y1491890D03*
X150976Y1500952D03*
Y1511576D03*
X159637Y1507245D03*
Y1502514D03*
Y1511976D03*
X150976Y1506845D03*
Y1516307D03*
X159637Y1558813D03*
Y1563544D03*
X150976Y1563144D03*
X159637Y1578898D03*
X150976Y1567875D03*
Y1578498D03*
Y1572606D03*
X159637Y1568275D03*
Y1574167D03*
X150976Y1583229D03*
Y1593853D03*
Y1587960D03*
X159637Y1583629D03*
Y1589522D03*
Y1594253D03*
X150976Y1609207D03*
Y1598584D03*
Y1603315D03*
X159637Y1609607D03*
Y1604876D03*
Y1598984D03*
X150976Y1613938D03*
Y1618669D03*
X159637Y1614338D03*
X152000Y1644980D03*
X179743Y94017D03*
X175743D03*
X171743D03*
X175871Y110445D03*
X180863Y115401D03*
Y110445D03*
X175871Y115401D03*
X180863Y129574D03*
Y124618D03*
X175871Y129574D03*
Y124618D03*
X173784Y151540D03*
X177434Y191941D03*
X177301Y188727D03*
X171258Y226141D03*
X174058D03*
X179128Y256535D03*
X173955Y285690D03*
Y288190D03*
X171155Y285690D03*
X168655Y288190D03*
X171155D03*
X168655Y285690D03*
X182181Y290755D03*
X178181D03*
X177369Y389154D03*
Y396240D03*
Y403327D03*
Y410413D03*
Y417500D03*
Y424587D03*
Y431673D03*
Y438760D03*
Y445847D03*
Y467539D03*
Y474626D03*
Y488799D03*
Y481713D03*
Y495886D03*
Y511673D03*
Y518760D03*
Y525847D03*
Y532933D03*
Y540020D03*
Y547106D03*
X176650Y602197D03*
X177114Y595108D03*
X173254Y1345691D03*
Y1350683D03*
X178210Y1345691D03*
Y1350683D03*
X173254Y1362595D03*
Y1357603D03*
X178210D03*
Y1362595D03*
X173254Y1374881D03*
Y1369889D03*
Y1381801D03*
X178210Y1374881D03*
Y1369889D03*
Y1381801D03*
X173254Y1394087D03*
Y1386793D03*
X178210Y1394087D03*
Y1386793D03*
X173254Y1399079D03*
X178210D03*
X173254Y1405999D03*
Y1410991D03*
X178210Y1405999D03*
Y1410991D03*
X168299Y1465513D03*
Y1460782D03*
X176960Y1465914D03*
Y1456452D03*
Y1461183D03*
X168299Y1476136D03*
Y1470244D03*
Y1480867D03*
X176960Y1476537D03*
Y1471806D03*
Y1481268D03*
X168299Y1491490D03*
Y1485598D03*
Y1496221D03*
X176960Y1491891D03*
Y1487160D03*
Y1496622D03*
Y1507246D03*
Y1502515D03*
X168299Y1506845D03*
Y1500952D03*
Y1511576D03*
X176960Y1511977D03*
X168299Y1516307D03*
Y1563144D03*
X176960Y1563544D03*
Y1558813D03*
Y1568275D03*
X168299Y1578498D03*
Y1572606D03*
Y1567875D03*
Y1583229D03*
X176960Y1583629D03*
X168299Y1593853D03*
Y1587960D03*
X176960Y1594253D03*
Y1589522D03*
X168299Y1609207D03*
Y1598584D03*
Y1603315D03*
X176960Y1609607D03*
Y1598984D03*
Y1604876D03*
X168299Y1613938D03*
Y1618669D03*
X176960Y1614338D03*
X172000Y1644980D03*
X188820Y80140D03*
Y84140D03*
Y76140D03*
X183752Y94017D03*
X186273Y117557D03*
X191265D03*
X186273Y131731D03*
Y122513D03*
X191265D03*
Y131731D03*
X189364Y146461D03*
X186273Y136687D03*
X191265D03*
X188266Y152367D03*
X194649Y180527D03*
X189966Y180572D03*
X198372Y192421D03*
X189966Y185165D03*
X194604Y185121D03*
X183934Y184619D03*
X185914Y206760D03*
X187128Y256535D03*
X188158Y279208D03*
X192262Y281307D03*
X186181Y290755D03*
X191988Y389154D03*
X190518Y396240D03*
X194603Y422864D03*
X195295Y414823D03*
X194673Y429832D03*
X194278Y436447D03*
X196313Y447953D03*
X195480Y467539D03*
X194222Y472772D03*
X194956Y487711D03*
X195069Y479104D03*
X195480Y495886D03*
X190829Y516841D03*
X194080Y510565D03*
X185654Y552872D03*
X185776Y550123D03*
X185099Y562443D03*
X186867Y560675D03*
X187408Y572334D03*
X185640Y574102D03*
X193723Y656942D03*
X185494Y1345597D03*
Y1350683D03*
X190450Y1345597D03*
Y1350683D03*
X197734Y1345691D03*
Y1350683D03*
X185494Y1362595D03*
Y1357603D03*
X197734Y1362595D03*
Y1357603D03*
X190450Y1362595D03*
Y1357603D03*
X185494Y1374881D03*
Y1381801D03*
Y1369889D03*
X197734D03*
Y1381801D03*
Y1374881D03*
X190450Y1369889D03*
Y1374881D03*
Y1381801D03*
X185494Y1393993D03*
Y1386793D03*
X190450Y1393993D03*
Y1386793D03*
X197734Y1394087D03*
Y1386793D03*
X185494Y1399079D03*
X190450D03*
X197734D03*
X185494Y1410991D03*
Y1405999D03*
X190450Y1410991D03*
Y1405999D03*
X197734D03*
Y1410991D03*
X185622Y1465513D03*
Y1460782D03*
Y1480868D03*
Y1476137D03*
Y1470244D03*
Y1485599D03*
X192000Y1644980D03*
X211262Y60922D03*
X206398Y55513D03*
X208463Y96472D03*
X202195Y117261D03*
X209726Y113394D03*
Y110394D03*
X212375Y110784D03*
X211969Y133298D03*
X214116Y134579D03*
X209902Y172665D03*
Y180665D03*
X209934Y200864D03*
Y212864D03*
Y216864D03*
Y221864D03*
X211691Y252371D03*
X215380Y389153D03*
X210580D03*
X215380Y396240D03*
X208080Y403327D03*
X215380Y403326D03*
X210580D03*
X208080Y410413D03*
X210580D03*
X215380D03*
X208080Y396240D03*
X210580D03*
X208080Y417500D03*
X215380Y417499D03*
X210580D03*
X208080Y424586D03*
X210580D03*
X215380D03*
X208080Y431673D03*
Y438760D03*
X210580D03*
X215380D03*
Y431673D03*
X210580D03*
X208080Y445847D03*
X215380Y467539D03*
X210580D03*
X208080Y474626D03*
X210580D03*
X215380D03*
Y488799D03*
X208080D03*
X210580D03*
Y481712D03*
X208080D03*
X215380D03*
X208080Y495886D03*
X215380Y518760D03*
X210580D03*
X208080D03*
X210580Y511673D03*
X215380D03*
X210580Y532933D03*
X208080D03*
Y540020D03*
Y525846D03*
X210580D03*
X215380D03*
Y532933D03*
X212460Y560500D03*
X209429Y625300D03*
X202690Y1345597D03*
Y1350683D03*
Y1362595D03*
Y1357603D03*
Y1369889D03*
Y1381801D03*
Y1374881D03*
Y1394087D03*
Y1386793D03*
Y1399079D03*
Y1405999D03*
Y1410991D03*
X211473Y1446675D03*
X213296Y1438215D03*
X211473Y1451631D03*
Y1462631D03*
Y1457675D03*
X224961Y109172D03*
X226968Y106495D03*
X230712Y116497D03*
X227961Y109172D03*
X230712Y123584D03*
Y130670D03*
X219969Y133298D03*
X228608Y141228D03*
X230712Y137757D03*
X226702Y146012D03*
X231496Y150847D03*
X226173Y253198D03*
X228760Y316122D03*
X223925Y543925D03*
X224500Y555000D03*
X222646Y607542D03*
X217945Y1423924D03*
X217799Y1433684D03*
X216465Y1446675D03*
X222253Y1438483D03*
X216465Y1451631D03*
Y1462631D03*
Y1457675D03*
X229260Y1469587D03*
X218171Y1474460D03*
X224176Y1492816D03*
X223235Y1506770D03*
X222908Y1502028D03*
X226957Y1510442D03*
X216342Y1515642D03*
X217519Y1537172D03*
X242712Y116496D03*
Y109410D03*
Y102323D03*
X238012Y116497D03*
X235512D03*
X238012Y109410D03*
Y123583D03*
Y130670D03*
X235512D03*
X242712D03*
Y123583D03*
X235512Y123584D03*
Y137757D03*
X242712Y137756D03*
X233464Y247292D03*
X236349Y339428D03*
X247333Y599506D03*
X241967Y616063D03*
X243078Y636486D03*
X240249Y628328D03*
X241084Y638243D03*
X246583Y665140D03*
X241850Y678462D03*
X247600Y848500D03*
X240845Y1345691D03*
Y1350683D03*
X245801Y1345691D03*
Y1350683D03*
X240845Y1357603D03*
Y1362595D03*
X245801Y1357603D03*
Y1362595D03*
X240845Y1381801D03*
Y1374881D03*
Y1369889D03*
X245801Y1381801D03*
Y1374881D03*
Y1369889D03*
X240845Y1386793D03*
X245801D03*
X232675Y1466801D03*
X240466Y1503857D03*
X243268Y1501903D03*
X237700Y1531600D03*
X251174Y77784D03*
Y80384D03*
Y82984D03*
Y75184D03*
Y85584D03*
X253728Y92849D03*
X260688Y103037D03*
X260822Y116496D03*
Y109410D03*
Y130670D03*
Y123583D03*
X257413Y137756D03*
X263003Y293796D03*
X257226Y312081D03*
X265011Y403307D03*
X255000Y427017D03*
X254692Y431029D03*
X253758Y435029D03*
X254678Y449873D03*
X261605Y465492D03*
Y472579D03*
X259105D03*
X254305D03*
X261605Y486752D03*
X254305D03*
X259105Y479666D03*
X261605D03*
X254305D03*
X259105Y486752D03*
X254305Y493839D03*
X259105D03*
X261605Y516713D03*
X259105D03*
Y523800D03*
X261605D03*
X254305D03*
Y516713D03*
X261605Y509626D03*
Y530886D03*
X259105D03*
Y537973D03*
X254305Y530886D03*
Y537973D03*
Y566752D03*
X261605Y559665D03*
Y566752D03*
X259105D03*
X261605Y588012D03*
X259105Y588013D03*
X254305Y573839D03*
X261605D03*
X259105D03*
X261605Y580926D03*
X259105D03*
X254305D03*
Y588013D03*
X259105Y602186D03*
X254305D03*
Y595099D03*
X259105D03*
X261605D03*
Y602185D03*
X254305Y609272D03*
X259105D03*
X261605D03*
X259105Y616359D03*
X254305D03*
X248984Y638125D03*
X258867Y680499D03*
X258041Y1350683D03*
Y1345691D03*
X253085Y1350683D03*
Y1345691D03*
X258041Y1362595D03*
X253085D03*
X258041Y1357603D03*
X253085D03*
X258041Y1381801D03*
Y1369795D03*
Y1374881D03*
X253085Y1381801D03*
Y1369795D03*
Y1374881D03*
Y1393993D03*
Y1399079D03*
X258041Y1386793D03*
Y1399079D03*
Y1393993D03*
X253085Y1386793D03*
X258041Y1405999D03*
Y1410991D03*
X253085Y1405999D03*
Y1410991D03*
X248042Y1532900D03*
X274105Y94017D03*
X278105D03*
X278233Y115401D03*
Y110445D03*
Y129574D03*
Y124618D03*
X276146Y151540D03*
X279796Y191941D03*
X279663Y188727D03*
X276420Y226141D03*
X273620D03*
X276317Y288190D03*
X273517Y285690D03*
X271017Y288190D03*
X273517D03*
X271017Y285690D03*
X265503Y293796D03*
X276317Y285690D03*
X274425Y390500D03*
X265011Y410394D03*
X266405Y451319D03*
Y458406D03*
Y465492D03*
X266229Y462264D03*
X266405Y472579D03*
Y479665D03*
Y486752D03*
Y493839D03*
Y523799D03*
Y516713D03*
Y509626D03*
Y530886D03*
Y537973D03*
Y566752D03*
Y559665D03*
Y580926D03*
Y588012D03*
Y573839D03*
Y602185D03*
Y595099D03*
Y609272D03*
Y616358D03*
X269700Y884600D03*
X269900Y914200D03*
X270100Y946500D03*
X277565Y1350683D03*
Y1345691D03*
X265325D03*
Y1350683D03*
X270281Y1345691D03*
Y1350683D03*
X277565Y1362595D03*
X265325D03*
X270281D03*
X277565Y1357603D03*
X265325D03*
X270281D03*
X277565Y1381801D03*
Y1374881D03*
Y1369889D03*
X265325D03*
Y1374881D03*
Y1381801D03*
X270281Y1369889D03*
Y1374881D03*
Y1381801D03*
X277565Y1386793D03*
Y1394087D03*
Y1399079D03*
X265325Y1394087D03*
Y1399079D03*
Y1386793D03*
X270281Y1399079D03*
Y1394087D03*
Y1386793D03*
X265325Y1405999D03*
Y1410991D03*
X270281Y1405999D03*
Y1410991D03*
X277565Y1405999D03*
Y1410991D03*
X272000Y1644980D03*
X291182Y84140D03*
Y80140D03*
Y76140D03*
X282105Y94017D03*
X286114D03*
X288635Y117557D03*
X283225Y115401D03*
Y110445D03*
X293627Y117557D03*
X288635Y131731D03*
Y122513D03*
X283225Y129574D03*
Y124618D03*
X293627Y122513D03*
Y131731D03*
X291726Y146461D03*
X293627Y136687D03*
X288635D03*
X290628Y152367D03*
X292328Y180572D03*
Y185165D03*
X286296Y184619D03*
X288276Y206760D03*
X281490Y256535D03*
X289490D03*
X290520Y279208D03*
X294624Y281307D03*
X284543Y290755D03*
X280543D03*
X288543D03*
X284075Y381500D03*
X284482Y460250D03*
X284516Y465492D03*
X282247Y470136D03*
X284516Y472579D03*
Y479665D03*
Y486752D03*
Y493839D03*
Y516713D03*
Y509626D03*
X283377Y532756D03*
X283456Y525483D03*
X280976Y537973D03*
X284516Y559665D03*
Y566752D03*
X284366Y579978D03*
X284516Y573839D03*
X284580Y608117D03*
X282521Y1345691D03*
X289805Y1350683D03*
Y1345691D03*
X294761Y1350683D03*
Y1345691D03*
X282521Y1350683D03*
X289805Y1362595D03*
X294761D03*
X282521D03*
X289805Y1357603D03*
X294761D03*
X282521D03*
X289805Y1374881D03*
Y1369889D03*
Y1381801D03*
X294761Y1374881D03*
Y1369889D03*
Y1381801D03*
X282521D03*
Y1374881D03*
Y1369889D03*
X289805Y1394087D03*
Y1399079D03*
Y1386793D03*
X294761Y1394087D03*
Y1399079D03*
Y1386793D03*
X282521D03*
Y1399079D03*
Y1394087D03*
X289805Y1405999D03*
Y1410991D03*
X294761Y1405999D03*
Y1410991D03*
X282521Y1405999D03*
Y1410991D03*
X280897Y1465913D03*
X289558Y1465513D03*
X280897Y1461182D03*
X289558Y1460782D03*
X280897Y1456451D03*
X289558Y1480867D03*
X280897Y1476536D03*
X289558Y1476136D03*
Y1470244D03*
X280897Y1471805D03*
Y1481267D03*
Y1491890D03*
X289558Y1491490D03*
Y1485598D03*
X280897Y1487159D03*
Y1496621D03*
X289558Y1496221D03*
X280897Y1507245D03*
X289558Y1506845D03*
Y1500952D03*
X280897Y1502514D03*
X289558Y1511576D03*
X280897Y1511976D03*
X289558Y1516307D03*
X280897Y1563544D03*
X289558Y1563144D03*
X280897Y1558813D03*
Y1574167D03*
Y1568275D03*
X289558Y1567875D03*
X280897Y1578898D03*
X289558Y1578498D03*
Y1572606D03*
Y1593853D03*
Y1587960D03*
X280897Y1589522D03*
Y1583629D03*
X289558Y1583229D03*
X280897Y1594253D03*
Y1609607D03*
X289558Y1609207D03*
X280897Y1598984D03*
X289558Y1598584D03*
Y1603315D03*
X280897Y1604876D03*
Y1614338D03*
X289558Y1613938D03*
Y1618669D03*
X292000Y1644980D03*
X308760Y55513D03*
X310882Y96613D03*
X305953Y91951D03*
X312088Y113394D03*
X304557Y117261D03*
X297011Y180527D03*
X312264Y172665D03*
Y180665D03*
X299759Y190285D03*
X296966Y185121D03*
X312296Y212864D03*
Y200864D03*
Y221864D03*
Y216864D03*
X306812Y342319D03*
X309258Y389912D03*
Y393924D03*
Y385912D03*
Y409924D03*
Y405924D03*
Y401924D03*
X306673Y418838D03*
X298507Y445908D03*
X302457Y445787D03*
X302045Y1345691D03*
Y1350683D03*
X307001D03*
Y1345691D03*
X302045Y1362595D03*
X307001D03*
X302045Y1357603D03*
X307001D03*
X302045Y1374881D03*
Y1381801D03*
Y1369889D03*
X307001Y1374881D03*
Y1369889D03*
Y1381801D03*
X302045Y1386793D03*
Y1394087D03*
Y1399079D03*
X307001Y1386793D03*
Y1399079D03*
Y1394087D03*
X302045Y1405999D03*
Y1410991D03*
X307001Y1405999D03*
Y1410991D03*
X298220Y1465913D03*
Y1456451D03*
Y1461182D03*
X306881Y1465513D03*
Y1460782D03*
Y1470244D03*
Y1480867D03*
X298220Y1471805D03*
Y1476536D03*
Y1481267D03*
X306881Y1476136D03*
X298220Y1487159D03*
Y1491890D03*
Y1496621D03*
X306881Y1491490D03*
Y1485598D03*
Y1496221D03*
X298220Y1507245D03*
Y1502514D03*
X306881Y1506845D03*
Y1500952D03*
Y1511576D03*
X298220Y1511976D03*
X306881Y1516307D03*
X298220Y1558813D03*
Y1563544D03*
X306881Y1563144D03*
X298220Y1568275D03*
X306881Y1567875D03*
X298220Y1574167D03*
Y1578898D03*
X306881Y1578498D03*
Y1572606D03*
X298220Y1583629D03*
X306881Y1583229D03*
X298220Y1589522D03*
Y1594253D03*
X306881Y1593853D03*
Y1587960D03*
Y1598584D03*
Y1603315D03*
X298220Y1609607D03*
Y1604876D03*
Y1598984D03*
X306881Y1609207D03*
X298220Y1614338D03*
X306881Y1613938D03*
Y1618669D03*
X312000Y1644980D03*
X313624Y60922D03*
X327323Y109172D03*
X314737Y110784D03*
X314854Y130898D03*
X322331Y133298D03*
X329064Y146012D03*
X316478Y134579D03*
X328535Y253198D03*
X314053Y252371D03*
X323882Y303839D03*
X315904Y336324D03*
X320483Y353506D03*
X319241Y1350683D03*
Y1345691D03*
X314285D03*
Y1350683D03*
X326525Y1345691D03*
Y1350683D03*
X319241Y1362595D03*
X314285D03*
X326525D03*
X319241Y1357603D03*
X314285D03*
X326525D03*
X319241Y1374881D03*
Y1381801D03*
Y1369889D03*
X314285Y1374881D03*
Y1381801D03*
Y1369889D03*
X326525Y1381801D03*
Y1369889D03*
Y1374881D03*
X319241Y1386793D03*
Y1399079D03*
Y1394087D03*
X314285Y1386793D03*
Y1399079D03*
Y1394087D03*
X326525Y1399079D03*
Y1394087D03*
Y1386793D03*
X319241Y1410991D03*
Y1405999D03*
X314285Y1410991D03*
Y1405999D03*
X326525Y1410991D03*
Y1405999D03*
X315543Y1465913D03*
Y1456451D03*
Y1461182D03*
X324204Y1465513D03*
Y1460782D03*
Y1480867D03*
X315543Y1471805D03*
Y1476536D03*
Y1481267D03*
X324204Y1476136D03*
Y1470244D03*
X315543Y1487159D03*
Y1491890D03*
Y1496621D03*
X324204Y1491490D03*
Y1485598D03*
Y1496221D03*
Y1500952D03*
Y1511576D03*
X315543Y1507245D03*
Y1502514D03*
Y1511976D03*
X324204Y1506845D03*
Y1516307D03*
X315543Y1558813D03*
Y1563544D03*
X324204Y1563144D03*
X315543Y1574167D03*
Y1578898D03*
X324204Y1567875D03*
Y1578498D03*
Y1572606D03*
X315543Y1568275D03*
Y1583629D03*
Y1589522D03*
Y1594253D03*
X324204Y1583229D03*
Y1593853D03*
Y1587960D03*
X315543Y1609607D03*
Y1604876D03*
Y1598984D03*
X324204Y1609207D03*
Y1598584D03*
Y1603315D03*
X315543Y1614338D03*
X324204Y1613938D03*
Y1618669D03*
X329330Y106495D03*
X345074Y116496D03*
X337874Y116497D03*
X340374D03*
X345074Y109410D03*
Y102323D03*
X340374Y109410D03*
X333074Y116497D03*
X330323Y109172D03*
X337874Y130670D03*
X345074D03*
Y123583D03*
X340374D03*
X337874Y123584D03*
X333074D03*
Y130670D03*
X340374D03*
X333074Y137757D03*
X337874D03*
X330970Y141228D03*
X345074Y137756D03*
X333858Y150847D03*
X335826Y247292D03*
X338358Y554861D03*
X337564Y1018294D03*
X337629Y1186071D03*
X336901Y1196407D03*
X338765Y1350683D03*
Y1345691D03*
X331481D03*
Y1350683D03*
X343721Y1345691D03*
Y1350683D03*
X331481Y1362595D03*
X343721D03*
X338765D03*
X331481Y1357603D03*
X343721D03*
X338765D03*
X331481Y1374881D03*
Y1381801D03*
Y1369889D03*
X343721Y1381801D03*
Y1369889D03*
Y1374881D03*
X338765Y1381801D03*
Y1369889D03*
Y1374881D03*
X331481Y1399079D03*
Y1394087D03*
Y1386793D03*
X343721D03*
Y1394087D03*
Y1399079D03*
X338765Y1386793D03*
Y1394087D03*
Y1399079D03*
X331481Y1410991D03*
Y1405999D03*
X343721Y1410991D03*
Y1405999D03*
X338765Y1410991D03*
Y1405999D03*
X341527Y1460782D03*
X332865Y1465913D03*
Y1456451D03*
Y1461182D03*
X341527Y1465513D03*
Y1476136D03*
Y1470244D03*
Y1480867D03*
X332865Y1471805D03*
Y1476536D03*
Y1481267D03*
X341527Y1491490D03*
Y1485598D03*
Y1496221D03*
X332865Y1487159D03*
Y1491890D03*
Y1496621D03*
Y1511976D03*
X341527Y1506845D03*
Y1500952D03*
Y1511576D03*
X332865Y1507245D03*
Y1502514D03*
X341527Y1516307D03*
X332865Y1558813D03*
Y1563544D03*
X341527Y1563144D03*
X332865Y1578898D03*
X341527Y1567875D03*
Y1578498D03*
Y1572606D03*
X332865Y1568275D03*
Y1574167D03*
Y1583629D03*
Y1589522D03*
Y1594253D03*
X341527Y1583229D03*
Y1593853D03*
Y1587960D03*
X332865Y1598984D03*
X341527Y1609207D03*
Y1598584D03*
Y1603315D03*
X332865Y1609607D03*
Y1604876D03*
X341527Y1613938D03*
Y1618669D03*
X332865Y1614338D03*
X332000Y1644980D03*
X353536Y82984D03*
Y80384D03*
Y77784D03*
Y75184D03*
X356090Y92849D03*
X353536Y85584D03*
X359525Y137756D03*
X356423Y301288D03*
X348375Y322284D03*
X348968Y333138D03*
X359278Y491870D03*
X356778D03*
X358096Y867459D03*
X358086Y884616D03*
X357962Y898800D03*
X358024Y912085D03*
X358085Y923327D03*
X355929Y1132042D03*
X351563Y1132410D03*
X349700Y1148000D03*
X357947Y1159455D03*
X352536Y1160168D03*
X357297Y1192709D03*
X360659Y1209789D03*
X355961Y1350683D03*
X351005Y1345597D03*
Y1350683D03*
X355961Y1345597D03*
X351005Y1362595D03*
X355961D03*
X351005Y1357603D03*
X355961D03*
X351005Y1374881D03*
Y1381801D03*
Y1369889D03*
X355961Y1381801D03*
Y1374881D03*
Y1369889D03*
X351005Y1399079D03*
Y1393993D03*
Y1386793D03*
X355961D03*
Y1399079D03*
Y1393993D03*
X351005Y1410991D03*
Y1405999D03*
X355961D03*
Y1410991D03*
X350188Y1491891D03*
Y1487160D03*
Y1496622D03*
Y1507246D03*
Y1502515D03*
Y1511977D03*
X358850Y1511576D03*
Y1506845D03*
Y1516307D03*
X350188Y1563544D03*
Y1558813D03*
Y1568275D03*
Y1578898D03*
Y1574167D03*
Y1583629D03*
Y1594253D03*
Y1589522D03*
Y1604876D03*
Y1609607D03*
Y1598984D03*
Y1614338D03*
X352000Y1644980D03*
X376467Y94017D03*
X363050Y103037D03*
X363184Y116496D03*
Y109410D03*
Y130670D03*
Y123583D03*
X375982Y226141D03*
X378782D03*
X365365Y293796D03*
X367865D03*
X373379Y288190D03*
X375879Y285690D03*
X373379D03*
X375879Y288190D03*
X368057Y354184D03*
X364933Y374232D03*
X373264Y370010D03*
X366443Y472189D03*
X373504Y517954D03*
X375040Y932959D03*
X371424Y937185D03*
X367944Y946082D03*
X368657Y1146937D03*
X366133Y1162817D03*
X368661Y1182649D03*
X368917Y1195419D03*
X365029Y1214158D03*
X362735Y1211864D03*
X369839Y1218940D03*
X363245Y1345691D03*
Y1350683D03*
X368201Y1345691D03*
Y1350683D03*
X363245Y1362595D03*
X368201D03*
X363245Y1357603D03*
X368201D03*
X363245Y1369889D03*
Y1381801D03*
Y1374881D03*
X368201D03*
Y1381801D03*
Y1369889D03*
X363245Y1399079D03*
Y1394087D03*
Y1386793D03*
X368201D03*
Y1394087D03*
Y1399079D03*
X363245Y1405999D03*
Y1410991D03*
X368201D03*
Y1405999D03*
X372000Y1644980D03*
X393544Y76140D03*
Y84140D03*
Y80140D03*
X384467Y94017D03*
X388476D03*
X380467D03*
X390997Y117557D03*
X385587Y115401D03*
X380595D03*
X385587Y110445D03*
X380595D03*
X390997Y131731D03*
Y122513D03*
X385587Y129574D03*
X380595D03*
X385587Y124618D03*
X380595D03*
X390997Y136687D03*
X382158Y191941D03*
X388658Y184619D03*
X382025Y188727D03*
X390638Y206760D03*
X391852Y256535D03*
X383852D03*
X392882Y279208D03*
X378679Y285690D03*
Y288190D03*
X386905Y290755D03*
X382905D03*
X390905D03*
X392387Y337599D03*
Y342555D03*
X392444Y401949D03*
X393893Y413611D03*
X393833Y423944D03*
X393652Y482382D03*
X393746Y478382D03*
X388593Y664232D03*
X386350Y693559D03*
X391478Y690675D03*
X391614Y938651D03*
X381377Y1003008D03*
X381045Y1009444D03*
X391284Y1307238D03*
X394000Y1508100D03*
X382017Y1555700D03*
Y1547700D03*
Y1551700D03*
X392000Y1644980D03*
X408493Y117577D03*
X395989Y117557D03*
Y131731D03*
Y122513D03*
Y136687D03*
X399373Y180527D03*
X394690Y180572D03*
X403096Y192421D03*
X394690Y185165D03*
X399328Y185121D03*
X396986Y281307D03*
X409484Y314921D03*
X398951Y333711D03*
X397374Y344439D03*
X407493Y354142D03*
X394237Y370899D03*
X394944Y398949D03*
X399518Y402642D03*
X402018D03*
X396633Y423944D03*
X396693Y413611D03*
X399193D03*
X401693D03*
X401633Y423944D03*
X399133D03*
X409284Y741316D03*
X401121Y936686D03*
X409121Y939186D03*
X401121D03*
X409121Y936686D03*
X409231Y1123101D03*
X406105Y1139435D03*
X410131Y1129301D03*
X407631D03*
X409231Y1125801D03*
X406105Y1131935D03*
Y1134435D03*
Y1136935D03*
Y1141935D03*
Y1146935D03*
Y1144435D03*
X403263Y1152684D03*
X406319Y1204405D03*
Y1206905D03*
Y1211905D03*
Y1209405D03*
X397695Y1287071D03*
X399716Y1295198D03*
X408523Y1332967D03*
X404657D03*
X408937Y1351568D03*
X403981D03*
X401990Y1446807D03*
X399731Y1442755D03*
X397245Y1511640D03*
X404053Y1513673D03*
X397220Y1521207D03*
X409461Y1569560D03*
X405461D03*
X426147Y151540D03*
X414626Y180665D03*
Y172665D03*
X414658Y212864D03*
Y200864D03*
Y216864D03*
Y221864D03*
X422873Y309966D03*
X419955Y306966D03*
X414999D03*
X411984Y314921D03*
X421231Y338523D03*
Y331255D03*
Y345776D03*
X413432Y346797D03*
X416318Y367903D03*
X424479Y367859D03*
X418754Y468607D03*
X418226Y653288D03*
Y646480D03*
Y648980D03*
Y655788D03*
X425121Y936686D03*
Y939186D03*
X417121Y936686D03*
Y939186D03*
X417677Y1052215D03*
X425175Y1098767D03*
X417171Y1098887D03*
X419987Y1098518D03*
X419731Y1123101D03*
X417231D03*
X422631Y1125801D03*
X425131Y1129301D03*
X422631D03*
X420131D03*
X417631D03*
X415131D03*
X412631D03*
X420131Y1125801D03*
X417631D03*
X425131D03*
X422495Y1152713D03*
Y1155213D03*
X412095Y1152713D03*
Y1155213D03*
X422934Y1200821D03*
Y1198321D03*
X420619Y1204617D03*
Y1207117D03*
Y1209617D03*
Y1212117D03*
X411174Y1282776D03*
X418537Y1300197D03*
X423741Y1300115D03*
X413354Y1300197D03*
X425582Y1291743D03*
X423762Y1305298D03*
X413374D03*
X418558Y1310523D03*
X413395Y1310481D03*
X423721Y1310523D03*
X425283Y1373958D03*
X411147Y1474993D03*
X419818Y1474945D03*
X415241Y1492990D03*
X415095Y1502750D03*
X411353Y1519440D03*
X419467Y1519706D03*
X420279Y1525978D03*
X410626Y1525991D03*
X413461Y1569560D03*
X412000Y1644980D03*
X441727Y146461D03*
X440629Y152367D03*
X435703Y306966D03*
X430747D03*
X427829Y309966D03*
X428459Y331255D03*
X435793D03*
X428500Y345776D03*
X435793Y345738D03*
X430439Y358115D03*
X435702Y367813D03*
X430746D03*
X427782Y464026D03*
X438396Y511493D03*
X435834Y509580D03*
X431804Y536682D03*
Y539182D03*
X441832Y626193D03*
X433206Y1055498D03*
X430706D03*
Y1057998D03*
X433206D03*
Y1060498D03*
Y1062998D03*
X430706D03*
Y1060498D03*
X441359Y1123101D03*
X438233Y1139435D03*
X441359Y1125801D03*
X439759Y1129301D03*
X442259D03*
X429331Y1136935D03*
Y1134435D03*
Y1139435D03*
Y1131935D03*
X435733D03*
Y1134435D03*
Y1136935D03*
Y1139435D03*
X438233Y1131935D03*
Y1134435D03*
Y1136935D03*
X429331Y1141935D03*
X435733D03*
Y1146935D03*
Y1144435D03*
X438233Y1141935D03*
Y1146935D03*
Y1144435D03*
X437231Y1154902D03*
Y1152402D03*
X429331Y1146935D03*
Y1144435D03*
X433249Y1204405D03*
Y1209405D03*
Y1211905D03*
Y1206905D03*
X437991Y1286544D03*
X440896Y1311366D03*
X432485Y1325784D03*
X439624Y1345691D03*
Y1350683D03*
Y1357603D03*
Y1362595D03*
Y1381801D03*
Y1369889D03*
Y1374881D03*
X436002Y1382252D03*
X439624Y1386793D03*
X437675Y1550158D03*
X429784Y1548222D03*
X432000Y1644980D03*
X458454Y328963D03*
Y324007D03*
Y339755D03*
Y344711D03*
X453463Y370694D03*
X448092Y375770D03*
X443094Y491251D03*
X455104Y536582D03*
Y539082D03*
X447279Y633881D03*
X454815Y974622D03*
X448999Y994483D03*
X456210Y1004680D03*
X452319Y1000828D03*
X449731Y1000855D03*
X453710Y1018825D03*
X443091Y1022766D03*
Y1030266D03*
X450063Y1043140D03*
X449767Y1047047D03*
X457303Y1098767D03*
X452115Y1098518D03*
X446863Y1098428D03*
X449359Y1123101D03*
X451859D03*
X457259Y1129301D03*
X449759Y1125801D03*
X452259D03*
X444759Y1129301D03*
X447259D03*
X449759D03*
X452259D03*
X454759Y1125801D03*
X457259D03*
X454759Y1129301D03*
X443223Y1155213D03*
Y1152713D03*
X452623D03*
Y1155213D03*
X447549Y1204617D03*
X449864Y1198321D03*
Y1200821D03*
X447549Y1209617D03*
Y1207117D03*
Y1212117D03*
X454120Y1269498D03*
X456213Y1286776D03*
X451304Y1293045D03*
X456820Y1345691D03*
X451864D03*
Y1350683D03*
X456820D03*
X444580Y1345691D03*
Y1350683D03*
X456820Y1362595D03*
Y1357603D03*
X451864Y1362595D03*
Y1357603D03*
X444580D03*
Y1362595D03*
X456820Y1374881D03*
X451864D03*
X444580Y1369889D03*
X456820Y1369795D03*
X451864D03*
X444580Y1374881D03*
Y1381801D03*
X456820D03*
X451864D03*
X456820Y1399079D03*
X451864Y1393993D03*
Y1399079D03*
X456820Y1393993D03*
Y1386793D03*
X451864D03*
X444580D03*
X456820Y1405999D03*
X451864D03*
Y1410991D03*
X456820D03*
X454125Y1461182D03*
Y1465913D03*
Y1471805D03*
Y1481267D03*
Y1476536D03*
Y1491890D03*
Y1487159D03*
Y1496621D03*
Y1511976D03*
Y1507245D03*
Y1502514D03*
Y1558813D03*
Y1578898D03*
Y1568275D03*
Y1563544D03*
Y1574167D03*
Y1583629D03*
Y1589522D03*
Y1594253D03*
Y1609607D03*
Y1598984D03*
Y1604876D03*
Y1614338D03*
X452000Y1644980D03*
X464738Y110784D03*
X462089Y113394D03*
X472332Y133298D03*
X464332D03*
X466479Y134579D03*
X464054Y252371D03*
X461454Y336837D03*
Y331881D03*
Y347629D03*
Y352585D03*
X466375Y366365D03*
X470389Y389553D03*
X468558Y491669D03*
Y503669D03*
Y507669D03*
Y512669D03*
X462242Y809792D03*
X475032Y843252D03*
X474678Y857919D03*
X463134Y859203D03*
X460455Y867050D03*
X475046Y885952D03*
X467494Y924532D03*
X462427Y1030218D03*
X460277Y1090268D03*
Y1093068D03*
X474818Y1123101D03*
X469192Y1131935D03*
X474818Y1125801D03*
X473218Y1129301D03*
X461459Y1136935D03*
Y1134435D03*
Y1139435D03*
Y1131935D03*
X471692Y1139435D03*
Y1136935D03*
Y1134435D03*
Y1131935D03*
X469192Y1139435D03*
Y1136935D03*
Y1134435D03*
X471692Y1146935D03*
Y1141935D03*
X469192Y1144435D03*
Y1146935D03*
Y1141935D03*
X471692Y1144435D03*
X461459D03*
X462687Y1152684D03*
X468850D03*
X461459Y1141935D03*
Y1146935D03*
X463216Y1254164D03*
Y1250760D03*
Y1244055D03*
X461613Y1286776D03*
X469060Y1345691D03*
Y1350683D03*
X464104Y1345691D03*
Y1350683D03*
X469060Y1357603D03*
Y1362595D03*
X464104D03*
Y1357603D03*
Y1381801D03*
X469060D03*
X464104Y1369889D03*
X469060D03*
X464104Y1374881D03*
X469060D03*
Y1386793D03*
X464104D03*
X469060Y1399079D03*
X464104Y1394087D03*
X469060D03*
X464104Y1399079D03*
Y1405999D03*
X469060D03*
X464104Y1410991D03*
X469060D03*
X471448Y1461182D03*
X462786Y1460782D03*
X471448Y1465913D03*
X462786Y1465513D03*
X471448Y1481267D03*
X462786Y1480867D03*
X471448Y1471805D03*
Y1476536D03*
X462786Y1476136D03*
Y1470244D03*
X471448Y1496621D03*
X462786Y1496221D03*
X471448Y1491890D03*
X462786Y1491490D03*
Y1485598D03*
X471448Y1487159D03*
Y1511976D03*
Y1502514D03*
Y1507245D03*
X462786Y1511576D03*
Y1506845D03*
Y1500952D03*
Y1516307D03*
Y1563144D03*
X471448Y1558813D03*
X462786Y1578498D03*
X471448Y1574167D03*
Y1568275D03*
Y1563544D03*
X462786Y1567875D03*
Y1572606D03*
X471448Y1578898D03*
Y1594253D03*
X462786Y1593853D03*
X471448Y1589522D03*
Y1583629D03*
X462786Y1583229D03*
Y1587960D03*
X471448Y1598984D03*
X462786Y1609207D03*
Y1598584D03*
Y1603315D03*
X471448Y1609607D03*
Y1604876D03*
Y1614338D03*
X462786Y1613938D03*
Y1618669D03*
X472000Y1644980D03*
X480324Y109172D03*
X477324D03*
X479331Y106495D03*
X483075Y116497D03*
X487875D03*
X490375Y109410D03*
Y116497D03*
X483075Y130670D03*
X487875Y123584D03*
Y130670D03*
X490375Y123583D03*
Y130670D03*
X483075Y123584D03*
X479065Y146012D03*
X480971Y141228D03*
X483075Y137757D03*
X487875D03*
X483859Y150847D03*
X485827Y247292D03*
X478536Y253198D03*
X483242Y366481D03*
X483584Y375840D03*
X483736Y371266D03*
X483541Y380306D03*
X481724Y391589D03*
Y387089D03*
X488438Y425464D03*
X482532Y418464D03*
X482484Y444517D03*
X486738Y581222D03*
X489538D03*
Y591215D03*
X486738D03*
X491340Y611091D03*
X485005Y659771D03*
X491324Y667293D03*
X485303Y681841D03*
X486246Y804497D03*
X485824Y819787D03*
X481593Y826387D03*
X491453Y834546D03*
X491527Y843206D03*
X488469Y857013D03*
X481943Y924633D03*
X488388Y938903D03*
X483636Y952152D03*
X490143Y989521D03*
X476148Y1057998D03*
Y1055498D03*
X478648D03*
Y1057998D03*
X476148Y1060498D03*
Y1062998D03*
X478648D03*
Y1060498D03*
X490762Y1098767D03*
X485574Y1098518D03*
X480322Y1098428D03*
X485318Y1123101D03*
X482818D03*
X490718Y1129301D03*
X483218Y1125801D03*
X485718D03*
X475718Y1129301D03*
X478218D03*
X480718D03*
X483218D03*
X485718D03*
X488218Y1125801D03*
X490718D03*
X488218Y1129301D03*
X477682Y1152713D03*
Y1155213D03*
X488082D03*
Y1152713D03*
X479521Y1204405D03*
Y1206905D03*
Y1211905D03*
Y1209405D03*
X488584Y1345691D03*
Y1350683D03*
X481300Y1345691D03*
X476344D03*
X481300Y1350683D03*
X476344D03*
X488584Y1357603D03*
Y1362595D03*
X481300D03*
Y1357603D03*
X476344Y1362595D03*
Y1357603D03*
X488584Y1381801D03*
X481300D03*
X488584Y1374881D03*
Y1369889D03*
X481300D03*
Y1374881D03*
X476344Y1381801D03*
Y1369889D03*
Y1374881D03*
X488584Y1386793D03*
X481300D03*
Y1399079D03*
X476344Y1394087D03*
Y1399079D03*
X488584Y1394087D03*
X481300D03*
X488584Y1399079D03*
X476344Y1386793D03*
Y1410991D03*
X481300Y1405999D03*
X476344D03*
X488584D03*
Y1410991D03*
X481300D03*
X480109Y1460782D03*
Y1465513D03*
X488771Y1465913D03*
Y1461182D03*
X480109Y1476136D03*
Y1470244D03*
X488771Y1471805D03*
Y1476536D03*
Y1481267D03*
X480109Y1480867D03*
Y1496221D03*
X488771Y1487159D03*
Y1491890D03*
X480109Y1491490D03*
Y1485598D03*
X488771Y1496621D03*
Y1511976D03*
X480109Y1511576D03*
Y1506845D03*
Y1500952D03*
X488771Y1502514D03*
Y1507245D03*
X480109Y1516307D03*
X488771Y1558813D03*
X480109Y1563144D03*
X488771Y1578898D03*
X480109Y1578498D03*
X488771Y1574167D03*
Y1568275D03*
Y1563544D03*
X480109Y1567875D03*
Y1572606D03*
X488771Y1589522D03*
Y1583629D03*
X480109Y1583229D03*
Y1587960D03*
X488771Y1594253D03*
X480109Y1593853D03*
X488771Y1609607D03*
Y1604876D03*
Y1598984D03*
X480109Y1609207D03*
Y1598584D03*
Y1603315D03*
X488771Y1614338D03*
X480109Y1613938D03*
Y1618669D03*
X503537Y77784D03*
Y75184D03*
Y80384D03*
Y82984D03*
X506091Y92849D03*
X503537Y85584D03*
X495075Y116496D03*
Y102323D03*
Y109410D03*
Y130670D03*
Y123583D03*
Y137756D03*
X497424Y354559D03*
X492317Y376252D03*
X503682Y455466D03*
X497776Y448466D03*
X493929Y555194D03*
X496729D03*
X493929Y563194D03*
X496729D03*
X493929Y571194D03*
X496729D03*
X492338Y581222D03*
Y591215D03*
X494632Y654622D03*
X501618Y698355D03*
X499012Y699819D03*
X503311Y715652D03*
X500705Y705524D03*
X507546Y738539D03*
X505673Y767961D03*
X500717D03*
X504341Y812040D03*
X491655Y829173D03*
X506246Y824689D03*
X492799Y846488D03*
X503741Y846830D03*
X497467Y833027D03*
X499640Y861538D03*
X499595Y963963D03*
X493050Y976078D03*
X506566Y1000766D03*
Y1004766D03*
Y1016266D03*
Y1030766D03*
X505981Y1052487D03*
X506946Y1123101D03*
Y1125801D03*
X505346Y1129301D03*
X507846D03*
X503820Y1139435D03*
Y1136935D03*
Y1134435D03*
Y1131935D03*
X501320Y1139435D03*
Y1136935D03*
Y1134435D03*
Y1131935D03*
X494918Y1136935D03*
Y1134435D03*
Y1139435D03*
Y1131935D03*
X503820Y1144435D03*
Y1146935D03*
Y1141935D03*
X501320Y1144435D03*
Y1146935D03*
Y1141935D03*
X494918Y1146935D03*
Y1144435D03*
Y1141935D03*
X502562Y1152713D03*
Y1155213D03*
X506451Y1204405D03*
X493821Y1204617D03*
X496136Y1200821D03*
Y1198321D03*
X506451Y1206905D03*
Y1211905D03*
Y1209405D03*
X493821Y1207117D03*
Y1209617D03*
Y1212117D03*
X500824Y1350683D03*
Y1345691D03*
X505780Y1350683D03*
Y1345691D03*
X493540D03*
Y1350683D03*
X505780Y1362595D03*
Y1357603D03*
X500824Y1362595D03*
Y1357603D03*
X493540Y1362595D03*
Y1357603D03*
Y1381801D03*
Y1374881D03*
Y1369889D03*
X505780Y1381801D03*
Y1374881D03*
Y1369889D03*
X500824D03*
Y1381801D03*
Y1374881D03*
Y1394087D03*
X505780Y1399079D03*
X500824D03*
X505780Y1394087D03*
X493540Y1386793D03*
Y1394087D03*
Y1399079D03*
X505780Y1386793D03*
X500824D03*
X505780Y1410991D03*
X500824D03*
X505780Y1405999D03*
X500824D03*
X493540D03*
Y1410991D03*
X497432Y1465513D03*
X506093Y1465913D03*
X497432Y1460782D03*
X506093Y1461182D03*
X497432Y1480867D03*
X506093Y1481267D03*
X497432Y1476136D03*
Y1470244D03*
X506093Y1471805D03*
Y1476536D03*
X497432Y1496221D03*
Y1491490D03*
Y1485598D03*
X506093Y1487159D03*
Y1491890D03*
Y1496621D03*
Y1511976D03*
X497432Y1506845D03*
Y1500952D03*
X506093Y1502514D03*
Y1507245D03*
X497432Y1511576D03*
Y1516307D03*
Y1563144D03*
X506093Y1558813D03*
X497432Y1578498D03*
X506093Y1578898D03*
X497432Y1567875D03*
Y1572606D03*
X506093Y1574167D03*
Y1568275D03*
Y1563544D03*
X497432Y1587960D03*
X506093Y1589522D03*
Y1583629D03*
X497432Y1593853D03*
X506093Y1594253D03*
X497432Y1583229D03*
X506093Y1604876D03*
Y1598984D03*
X497432Y1609207D03*
X506093Y1609607D03*
X497432Y1598584D03*
Y1603315D03*
Y1613938D03*
Y1618669D03*
X506093Y1614338D03*
X492000Y1644980D03*
X513051Y103037D03*
X513185Y116496D03*
Y109410D03*
Y130670D03*
Y123583D03*
X509251Y137756D03*
X517866Y293796D03*
X515366D03*
X523380Y285690D03*
Y288190D03*
X511342Y311124D03*
X520845Y434508D03*
X516845D03*
X512845D03*
X514608Y445874D03*
X510022Y446352D03*
X523705Y444269D03*
X523583Y447201D03*
X521636Y504699D03*
X516636D03*
X519136D03*
X516338Y516979D03*
X521338D03*
X518838D03*
X512404Y629362D03*
X510215Y627948D03*
X511990Y686365D03*
X518001Y694940D03*
X522410Y694881D03*
X518067Y699378D03*
X518530Y703584D03*
X522628Y703884D03*
X508237Y723585D03*
X512502Y738539D03*
X516953Y738575D03*
X521909D03*
X520159Y758832D03*
X509063Y782867D03*
X517194Y773232D03*
X522316Y793574D03*
X509316Y793224D03*
X508130Y787488D03*
X521178Y814001D03*
X521565Y820931D03*
X520720Y846133D03*
X517832Y834558D03*
X508049Y877789D03*
X523272Y880067D03*
X509428Y888390D03*
X521115Y897500D03*
X511025Y911443D03*
X509673Y900295D03*
X516256Y939157D03*
X514886Y952189D03*
X519792Y1031271D03*
X517702Y1098518D03*
X512450Y1098428D03*
X522890Y1098767D03*
X514946Y1123101D03*
X517446D03*
X522846Y1129301D03*
X515346Y1125801D03*
X517846D03*
X510346Y1129301D03*
X512846D03*
X515346D03*
X517846D03*
X520346Y1125801D03*
X522846D03*
X520346Y1129301D03*
X518210Y1155213D03*
Y1152713D03*
X508810D03*
Y1155213D03*
X520751Y1204617D03*
X523066Y1200821D03*
Y1198321D03*
X520751Y1207117D03*
Y1209617D03*
Y1212117D03*
X513064Y1345691D03*
X518020Y1350683D03*
X513064D03*
X518020Y1345691D03*
Y1357603D03*
X513064Y1362595D03*
Y1357603D03*
X518020Y1362595D03*
X513064Y1369889D03*
Y1381801D03*
Y1374881D03*
X518020Y1369889D03*
Y1381801D03*
Y1374881D03*
Y1394087D03*
Y1399079D03*
X513064Y1394087D03*
Y1399079D03*
Y1386793D03*
X518020D03*
Y1405999D03*
Y1410991D03*
X513064D03*
Y1405999D03*
X514755Y1460782D03*
Y1465513D03*
Y1480867D03*
Y1476136D03*
Y1470244D03*
Y1491490D03*
Y1485598D03*
Y1496221D03*
Y1511576D03*
Y1506845D03*
Y1500952D03*
Y1516307D03*
Y1563144D03*
Y1567875D03*
Y1572606D03*
Y1578498D03*
Y1593853D03*
Y1583229D03*
Y1587960D03*
Y1603315D03*
Y1609207D03*
Y1598584D03*
Y1613938D03*
Y1618669D03*
X512000Y1644980D03*
X526468Y94017D03*
X534468D03*
X538477D03*
X530468D03*
X530596Y115401D03*
X535588Y110445D03*
Y115401D03*
X530596Y110445D03*
Y124618D03*
Y129574D03*
X535588Y124618D03*
Y129574D03*
X528509Y151540D03*
X538659Y184619D03*
X532159Y191941D03*
X532026Y188727D03*
X528783Y226141D03*
X525983D03*
X533853Y256535D03*
X525880Y285690D03*
X528680D03*
X525880Y288190D03*
X528680D03*
X532906Y290755D03*
X536906D03*
X540906D03*
X524206Y354119D03*
X533027Y351836D03*
X530215Y364422D03*
X535142Y397552D03*
X532936Y519544D03*
X527936D03*
X525436D03*
X530436D03*
X538826Y633450D03*
X526756Y636005D03*
Y633205D03*
X538826Y636250D03*
Y639050D03*
X526756Y638805D03*
X524653Y643595D03*
X534940Y684489D03*
X539111Y681459D03*
X526956Y694959D03*
X526951Y699443D03*
X535387Y712617D03*
X526933Y703820D03*
X532628Y720776D03*
X526276Y721339D03*
X539763Y734097D03*
X534807D03*
X531763Y739097D03*
X526807D03*
X532450Y767474D03*
X532278Y762736D03*
X531501Y792331D03*
X531260Y794934D03*
X531666Y815724D03*
X531313Y822693D03*
X527733Y847026D03*
X527346Y911458D03*
X528674Y964851D03*
X527046Y1131935D03*
Y1139435D03*
Y1134435D03*
Y1136935D03*
X528274Y1152684D03*
X527046Y1146935D03*
Y1144435D03*
Y1141935D03*
X525304Y1345691D03*
X530260D03*
X537544Y1350683D03*
X525304D03*
X530260D03*
X537544Y1345691D03*
Y1357603D03*
X525304Y1362595D03*
X530260D03*
X525304Y1357603D03*
X530260D03*
X537544Y1362595D03*
Y1374881D03*
X525304Y1369889D03*
Y1381801D03*
Y1374881D03*
X530260Y1369889D03*
Y1381801D03*
Y1374881D03*
X537544Y1369889D03*
Y1381801D03*
Y1399079D03*
Y1394087D03*
X530260D03*
Y1399079D03*
X525304Y1394087D03*
Y1399079D03*
X537544Y1386793D03*
X525304D03*
X530260D03*
X537544Y1410991D03*
Y1405999D03*
X530260D03*
X525304D03*
X530260Y1410991D03*
X525304D03*
X532000Y1644980D03*
X543545Y84140D03*
Y80140D03*
Y76140D03*
X540998Y117557D03*
X545990D03*
Y122513D03*
Y131731D03*
X540998Y122513D03*
Y131731D03*
X544089Y146461D03*
X545990Y136687D03*
X540998D03*
X542991Y152367D03*
X549374Y180527D03*
X544691Y180572D03*
X553097Y192421D03*
X549329Y185121D03*
X544691Y185165D03*
X540639Y206760D03*
X541853Y256535D03*
X542883Y279208D03*
X546987Y281307D03*
X541644Y389047D03*
X553731Y388487D03*
X541706Y381723D03*
X552905Y430829D03*
X550274Y658676D03*
X556574Y684031D03*
Y700031D03*
Y688987D03*
Y716031D03*
Y704987D03*
Y720987D03*
X552384Y762892D03*
X552188Y766577D03*
X553871Y811298D03*
X545741Y804149D03*
X548464Y823156D03*
X540807Y816556D03*
X541129Y828335D03*
Y838865D03*
X545981Y846389D03*
X549241Y841388D03*
X545237Y850319D03*
X548521Y877859D03*
Y874859D03*
X545144Y909025D03*
X544793Y899220D03*
X548215Y1006560D03*
X552923Y997860D03*
X541766Y1018368D03*
X557681Y1035088D03*
X554740Y1345597D03*
X542500Y1345691D03*
X549784Y1345597D03*
X542500Y1350683D03*
X549784D03*
X554740D03*
Y1362595D03*
Y1357603D03*
X542500Y1362595D03*
X549784D03*
X542500Y1357603D03*
X549784D03*
X554740Y1381801D03*
Y1374881D03*
X542500D03*
X549784Y1369889D03*
Y1381801D03*
Y1374881D03*
X542500Y1369889D03*
Y1381801D03*
X554740Y1369889D03*
Y1399079D03*
Y1393993D03*
X542500Y1399079D03*
X549784Y1393993D03*
Y1399079D03*
X542500Y1394087D03*
X554740Y1386793D03*
X549784D03*
X542500D03*
X554740Y1410991D03*
Y1405999D03*
X542500Y1410991D03*
X549784D03*
X542500Y1405999D03*
X549784D03*
X552000Y1644980D03*
X566287Y60922D03*
X561123Y55513D03*
X563224Y96813D03*
X558316Y91951D03*
X556920Y117261D03*
X567100Y110784D03*
X564451Y113394D03*
X567290Y130898D03*
X568841Y134579D03*
X564627Y180665D03*
Y172665D03*
X569969Y195176D03*
X564659Y212864D03*
Y200864D03*
X569829Y203393D03*
X564659Y221864D03*
Y216864D03*
X566416Y252371D03*
X570634Y375453D03*
X559074Y696987D03*
Y692031D03*
Y712987D03*
Y708031D03*
X561886Y728138D03*
X559625Y739609D03*
X557813Y747814D03*
X570578Y749800D03*
X570695Y767052D03*
X564276Y776701D03*
X558241Y796389D03*
X569186Y787332D03*
X561401Y811242D03*
X567316Y806224D03*
X561061Y803606D03*
X563099Y829943D03*
X567316Y827724D03*
X559741Y822149D03*
X572171Y842346D03*
X559196Y846296D03*
X569577Y886913D03*
X560814Y901022D03*
X564923Y997860D03*
X560923D03*
X568923D03*
X556923D03*
X571857Y1009354D03*
X565451Y1035102D03*
X569520Y1102091D03*
X560211D03*
X566020D03*
X569520Y1114691D03*
X566020D03*
X560211D03*
X569520Y1139891D03*
X566020D03*
X560211D03*
X566020Y1127291D03*
X560211D03*
X569520D03*
X566020Y1152491D03*
X560211D03*
X569520D03*
X566020Y1165091D03*
X560211D03*
X569520D03*
X560211Y1177691D03*
X566020D03*
X569520D03*
X566502Y1202103D03*
X569882Y1223749D03*
X562024Y1350683D03*
Y1345691D03*
X566980D03*
Y1350683D03*
X562024Y1357603D03*
X566980D03*
Y1362595D03*
X562024D03*
Y1369889D03*
Y1381801D03*
Y1374881D03*
X566980Y1369889D03*
Y1381801D03*
Y1374881D03*
Y1399079D03*
Y1394087D03*
X562024Y1399079D03*
Y1394087D03*
X566980Y1386793D03*
X562024D03*
X566980Y1410991D03*
X562024D03*
X566980Y1405999D03*
X562024D03*
X565600Y1530800D03*
X569349Y1541947D03*
X560635Y1543531D03*
X566800Y1541800D03*
X582686Y109172D03*
X579686D03*
X581693Y106495D03*
X585437Y116497D03*
X574694Y133298D03*
X585437Y123584D03*
Y130670D03*
X581427Y146012D03*
X583333Y141228D03*
X585437Y137757D03*
X586221Y150847D03*
X588189Y247292D03*
X580898Y253198D03*
X581487Y336676D03*
X573805Y728301D03*
X574620Y772724D03*
X584624Y781850D03*
X581001Y814123D03*
X579758Y817753D03*
X579827Y884000D03*
X579251Y903364D03*
X582706Y908959D03*
X580923Y997860D03*
X576923D03*
X588923D03*
X577666Y1009354D03*
X581166D03*
X572923Y997860D03*
X584923D03*
X581166Y1021954D03*
X577666D03*
X578298Y1215195D03*
X584024Y1209607D03*
X587689Y1505724D03*
X583661Y1529142D03*
X573784Y1530646D03*
X575332Y1523740D03*
X583800Y1518000D03*
X583740Y1520640D03*
X587858Y1517942D03*
X577645Y1540982D03*
X580700Y1544100D03*
X592737Y109410D03*
X590237Y116497D03*
X592737D03*
X597437Y102323D03*
Y109410D03*
Y116496D03*
Y123583D03*
Y130670D03*
X592737Y123583D03*
X590237Y123584D03*
Y130670D03*
X592737D03*
X597437Y137756D03*
X590237Y137757D03*
X590178Y309760D03*
X593690Y450750D03*
X597872Y512743D03*
X592880D03*
X597789Y536382D03*
X602756Y597580D03*
X604979Y599588D03*
X604241Y589556D03*
X604180Y592354D03*
X602695Y594668D03*
X604982Y596095D03*
X605011Y615600D03*
X604979Y607588D03*
X592238Y880612D03*
X597129Y913386D03*
X602385Y940920D03*
X596923Y997860D03*
X592923D03*
X604923D03*
X600923D03*
X602603Y1012354D03*
Y1024954D03*
X604405Y1034870D03*
X591898Y1035011D03*
X590957Y1105091D03*
Y1117691D03*
Y1130291D03*
Y1155491D03*
Y1142891D03*
Y1168091D03*
Y1180691D03*
X592978Y1514812D03*
X591858Y1523542D03*
X598800Y1546400D03*
X605899Y80384D03*
Y82984D03*
Y77784D03*
Y75184D03*
X608453Y92849D03*
X605899Y85584D03*
X615413Y103037D03*
X615547Y116496D03*
Y109410D03*
Y130670D03*
Y123583D03*
X612138Y137756D03*
X617728Y293796D03*
X620228D03*
X614461Y555234D03*
X614176Y562003D03*
X609472Y634946D03*
X612489Y941024D03*
X616923Y997860D03*
X608923D03*
X620151Y1040363D03*
X619086Y1056453D03*
X620715Y1046785D03*
X612000Y1644980D03*
X636830Y94017D03*
X628830D03*
X632830D03*
X632958Y110445D03*
Y115401D03*
Y124618D03*
Y129574D03*
X630871Y151540D03*
X634521Y191941D03*
X634388Y188727D03*
X631145Y226141D03*
X628345D03*
X636215Y256535D03*
X631042Y288190D03*
Y285690D03*
X625742Y288190D03*
X628242Y285690D03*
X625742D03*
X628242Y288190D03*
X635268Y290755D03*
X634455Y389154D03*
Y396240D03*
Y403327D03*
Y410413D03*
Y417500D03*
Y424587D03*
Y431673D03*
Y438760D03*
Y445847D03*
Y467539D03*
Y474626D03*
Y488799D03*
Y481713D03*
Y495886D03*
Y511673D03*
Y518760D03*
Y525847D03*
Y532933D03*
Y540020D03*
Y547106D03*
X633736Y602197D03*
X634200Y595108D03*
X622270Y864781D03*
X630466Y1394087D03*
X625510Y1399079D03*
Y1394087D03*
X630466Y1399079D03*
X625510Y1405999D03*
X630466D03*
X625510Y1410991D03*
X630466D03*
X636015Y1460782D03*
X627354Y1461182D03*
X636015Y1465513D03*
X627354Y1465913D03*
Y1456451D03*
X636015Y1476136D03*
X627354Y1476536D03*
X636015Y1480867D03*
X627354Y1481267D03*
Y1471805D03*
X636015Y1470244D03*
X627354Y1487159D03*
X636015Y1485598D03*
Y1491490D03*
X627354Y1491890D03*
X636015Y1496221D03*
X627354Y1496621D03*
Y1507245D03*
Y1511976D03*
X636015Y1511576D03*
X627354Y1502514D03*
X636015Y1500952D03*
Y1506845D03*
Y1516307D03*
X627354Y1558813D03*
X636015Y1563144D03*
X627354Y1563544D03*
X636015Y1567875D03*
X627354Y1568275D03*
Y1574167D03*
X636015Y1572606D03*
Y1578498D03*
X627354Y1578898D03*
X636015Y1593853D03*
X627354Y1594253D03*
X636015Y1583229D03*
X627354Y1583629D03*
Y1589522D03*
X636015Y1587960D03*
X627354Y1604876D03*
X636015Y1603315D03*
Y1598584D03*
X627354Y1598984D03*
X636015Y1609207D03*
X627354Y1609607D03*
X636015Y1618669D03*
Y1613938D03*
X627354Y1614338D03*
X632000Y1644980D03*
X645907Y76140D03*
Y84140D03*
Y80140D03*
X640839Y94017D03*
X643360Y117557D03*
X637950Y110445D03*
Y115401D03*
X648352Y117557D03*
X643360Y122513D03*
Y131731D03*
X637950Y124618D03*
Y129574D03*
X648352Y122513D03*
Y131731D03*
X646451Y146461D03*
X643360Y136687D03*
X648352D03*
X645353Y152367D03*
X647053Y180572D03*
X651736Y180527D03*
X651691Y185121D03*
X647053Y185165D03*
X641021Y184619D03*
X643001Y206760D03*
X644215Y256535D03*
X645245Y279208D03*
X649349Y281307D03*
X639268Y290755D03*
X643268D03*
X649074Y389154D03*
X647604Y396240D03*
X652381Y414823D03*
X651689Y422864D03*
X651759Y429832D03*
X651364Y436447D03*
X653399Y447953D03*
X652566Y467539D03*
X651308Y472772D03*
X652042Y487711D03*
X652155Y479104D03*
X652566Y495886D03*
X647915Y516841D03*
X651166Y510565D03*
X642862Y550123D03*
X642740Y552872D03*
X644494Y572334D03*
X642185Y562443D03*
X643953Y560675D03*
X642726Y574102D03*
X647361Y653161D03*
X648352Y645467D03*
X650958Y677843D03*
X649990Y1350683D03*
Y1345691D03*
Y1357603D03*
Y1362595D03*
Y1381801D03*
X642706Y1374881D03*
Y1381801D03*
Y1369889D03*
X649990Y1374881D03*
Y1369889D03*
X637750Y1374881D03*
Y1381801D03*
Y1369889D03*
X649990Y1399079D03*
Y1394087D03*
X642706Y1386793D03*
X649990D03*
X637750Y1399079D03*
X642706Y1394087D03*
X637750D03*
X642706Y1399079D03*
X637750Y1386793D03*
X649990Y1405999D03*
Y1410991D03*
X637750D03*
X642706D03*
Y1405999D03*
X637750D03*
X653338Y1465513D03*
X644677Y1461182D03*
Y1456451D03*
Y1465913D03*
X653338Y1460782D03*
X644677Y1476536D03*
Y1471805D03*
X653338Y1480867D03*
Y1470244D03*
Y1476136D03*
X644677Y1481267D03*
X653338Y1491490D03*
X644677Y1496621D03*
Y1491890D03*
Y1487159D03*
X653338Y1496221D03*
Y1485598D03*
X644677Y1511976D03*
X653338Y1511576D03*
Y1500952D03*
Y1506845D03*
X644677Y1502514D03*
Y1507245D03*
X653338Y1516307D03*
X644677Y1558813D03*
X653338Y1563144D03*
X644677Y1563544D03*
X653338Y1572606D03*
Y1578498D03*
X644677Y1578898D03*
Y1574167D03*
X653338Y1567875D03*
X644677Y1568275D03*
X653338Y1587960D03*
Y1593853D03*
X644677Y1594253D03*
Y1589522D03*
X653338Y1583229D03*
X644677Y1583629D03*
X653338Y1609207D03*
X644677Y1598984D03*
Y1604876D03*
Y1609607D03*
X653338Y1603315D03*
Y1598584D03*
Y1613938D03*
X644677Y1614338D03*
X653338Y1618669D03*
X652000Y1644980D03*
X668649Y60922D03*
X666209Y57297D03*
X665423Y96853D03*
X660678Y91951D03*
X659282Y117261D03*
X666813Y113394D03*
X669462Y110784D03*
X669056Y133298D03*
X666989Y172665D03*
Y180665D03*
X655459Y192421D03*
X667021Y200864D03*
Y212864D03*
Y221864D03*
Y216864D03*
X668778Y252371D03*
X667666Y389153D03*
X665166Y396240D03*
X667666D03*
X665166Y403327D03*
X667666Y403326D03*
X665166Y410413D03*
X667666D03*
Y417499D03*
X665166Y424586D03*
X667666D03*
X665166Y417500D03*
Y431673D03*
Y438760D03*
X667666D03*
Y431673D03*
X665166Y445847D03*
X667666Y467539D03*
X665166Y474626D03*
X667666D03*
X665166Y488799D03*
X667666D03*
Y481712D03*
X665166D03*
Y495886D03*
X667666Y518760D03*
X665166D03*
X667666Y511673D03*
Y532933D03*
X665166D03*
Y540020D03*
Y525846D03*
X667666D03*
X669546Y560500D03*
X655752Y668885D03*
X661776Y662981D03*
X656157Y691851D03*
X661768Y705043D03*
X654946Y1350683D03*
X662230D03*
X667186D03*
Y1345691D03*
X654946D03*
X662230D03*
X654946Y1357603D03*
Y1362595D03*
X662230Y1357603D03*
Y1362595D03*
X667186Y1357603D03*
Y1362595D03*
X662230Y1369889D03*
X667186Y1374881D03*
Y1381801D03*
Y1369889D03*
X662230Y1374881D03*
Y1381801D03*
X654946D03*
Y1369889D03*
Y1374881D03*
X667186Y1399079D03*
Y1393993D03*
X662230D03*
Y1399079D03*
X655046D03*
Y1394087D03*
X667186Y1386793D03*
X662230D03*
X654946D03*
X667186Y1410991D03*
Y1405999D03*
X662230D03*
Y1410991D03*
X655046Y1405999D03*
Y1410991D03*
X662000Y1456451D03*
Y1465913D03*
Y1461182D03*
Y1481267D03*
Y1476536D03*
Y1471805D03*
Y1496621D03*
Y1491890D03*
Y1487159D03*
Y1511976D03*
Y1502514D03*
Y1507245D03*
Y1563544D03*
Y1558813D03*
Y1568275D03*
Y1578898D03*
Y1574167D03*
Y1594253D03*
Y1589522D03*
Y1583629D03*
Y1598984D03*
Y1604876D03*
Y1609607D03*
Y1614338D03*
X682048Y109172D03*
X685048D03*
X684055Y106495D03*
X677056Y133298D03*
X671203Y134579D03*
X683789Y146012D03*
X685695Y141228D03*
X677331Y195176D03*
X676950Y198883D03*
X683260Y253198D03*
X686012Y339795D03*
X672466Y389153D03*
Y410413D03*
Y396240D03*
Y403326D03*
Y424586D03*
Y417499D03*
Y438760D03*
Y431673D03*
Y467539D03*
Y474626D03*
Y488799D03*
Y481712D03*
Y518760D03*
Y511673D03*
Y525846D03*
Y532933D03*
X681586Y555000D03*
X681011Y543925D03*
X679426Y1350683D03*
X674470Y1345691D03*
X679426D03*
X674470Y1350683D03*
Y1357603D03*
Y1362595D03*
X679426Y1357603D03*
Y1362595D03*
Y1374881D03*
X674470D03*
Y1381801D03*
X679426D03*
Y1369889D03*
X674470D03*
X679426Y1399079D03*
X674470Y1394087D03*
X679426D03*
X674470Y1399079D03*
Y1386793D03*
X679426D03*
X674470Y1405999D03*
X679426D03*
X674470Y1410991D03*
X679426D03*
X679322Y1461182D03*
Y1456451D03*
Y1465913D03*
X670661Y1460782D03*
Y1465513D03*
Y1470244D03*
Y1476136D03*
X679322Y1481267D03*
Y1476536D03*
Y1471805D03*
X670661Y1480867D03*
X679322Y1487159D03*
X670661Y1496221D03*
Y1485598D03*
Y1491490D03*
X679322Y1496621D03*
Y1491890D03*
X670661Y1500952D03*
Y1506845D03*
X679322Y1511976D03*
Y1502514D03*
Y1507245D03*
X670661Y1511576D03*
Y1516307D03*
X679322Y1558813D03*
X670661Y1563144D03*
X679322Y1563544D03*
Y1578898D03*
Y1574167D03*
Y1568275D03*
X670661Y1572606D03*
Y1578498D03*
Y1567875D03*
X679322Y1583629D03*
X670661Y1587960D03*
Y1593853D03*
Y1583229D03*
X679322Y1594253D03*
Y1589522D03*
Y1604876D03*
Y1609607D03*
X670661Y1603315D03*
Y1598584D03*
Y1609207D03*
X679322Y1598984D03*
Y1614338D03*
X670661Y1618669D03*
Y1613938D03*
X672000Y1644980D03*
X695099Y109410D03*
X687799Y116497D03*
X692599D03*
X695099D03*
X699799Y116496D03*
Y109410D03*
Y102323D03*
X687799Y123584D03*
X695099Y123583D03*
X692599Y123584D03*
X687799Y130670D03*
X692599D03*
X695099D03*
X699799Y123583D03*
Y130670D03*
X687799Y137757D03*
X692599D03*
X699799Y137756D03*
X688583Y150847D03*
X690551Y247292D03*
X700164Y636842D03*
X698936Y678462D03*
X702691Y766471D03*
Y753471D03*
X702677Y771159D03*
Y784659D03*
X698950Y1350683D03*
Y1345597D03*
X686710Y1350683D03*
X691666D03*
X686710Y1345691D03*
X691666D03*
X698950Y1362595D03*
Y1357603D03*
X686710D03*
Y1362595D03*
X691666Y1357603D03*
Y1362595D03*
X698950Y1374881D03*
Y1381801D03*
Y1369889D03*
X691666D03*
Y1374881D03*
Y1381801D03*
X686710Y1374881D03*
Y1369889D03*
Y1381801D03*
X698950Y1399079D03*
Y1394087D03*
X686710D03*
Y1399079D03*
X691666Y1394087D03*
Y1399079D03*
X698950Y1386793D03*
X691666D03*
X686710D03*
X698950Y1405999D03*
Y1410991D03*
X686710D03*
X691666D03*
X686710Y1405999D03*
X691666D03*
X696645Y1461183D03*
Y1456452D03*
Y1465914D03*
X687984Y1460782D03*
Y1465513D03*
Y1470244D03*
Y1476136D03*
X696645Y1481268D03*
Y1471806D03*
Y1476537D03*
X687984Y1480867D03*
X696645Y1491891D03*
X687984Y1496221D03*
Y1485598D03*
Y1491490D03*
X696645Y1496622D03*
Y1487160D03*
Y1511977D03*
Y1502515D03*
Y1507246D03*
X687984Y1511576D03*
Y1500952D03*
Y1506845D03*
Y1516307D03*
X696645Y1558813D03*
Y1563544D03*
X687984Y1563144D03*
X696645Y1574167D03*
Y1578898D03*
X687984Y1572606D03*
Y1578498D03*
X696645Y1568275D03*
X687984Y1567875D03*
Y1583229D03*
X696645Y1589522D03*
Y1594253D03*
X687984Y1587960D03*
Y1593853D03*
X696645Y1583629D03*
Y1598984D03*
Y1609607D03*
X687984Y1603315D03*
Y1598584D03*
Y1609207D03*
X696645Y1604876D03*
X687984Y1613938D03*
X696645Y1614338D03*
X687984Y1618669D03*
X692000Y1644980D03*
X718488Y-27642D03*
X718503Y-25127D03*
X708261Y82984D03*
Y80384D03*
Y77784D03*
Y75184D03*
X710815Y92849D03*
X708261Y85584D03*
X717775Y103037D03*
X717909Y116496D03*
Y109410D03*
Y130670D03*
Y123583D03*
X714500Y137756D03*
X713162Y434493D03*
X711764Y449873D03*
X718691Y465492D03*
Y472579D03*
X716191D03*
X711391D03*
X716191Y479666D03*
X718691D03*
X711391D03*
Y486752D03*
X716191D03*
X718691D03*
X711391Y493839D03*
X716191D03*
Y516713D03*
Y523800D03*
X718691D03*
X711391D03*
Y516713D03*
X718691D03*
Y509626D03*
Y530886D03*
X716191D03*
Y537973D03*
X711391Y530886D03*
Y537973D03*
Y566752D03*
X718691Y559665D03*
Y566752D03*
X716191D03*
X711391Y573839D03*
X718691D03*
X716191D03*
X711391Y588013D03*
X718691Y588012D03*
X716191Y588013D03*
X718691Y580926D03*
X716191D03*
X711391D03*
X716191Y602186D03*
X711391D03*
X718691Y602185D03*
Y595099D03*
X711391D03*
X716191D03*
X711391Y609272D03*
X716191D03*
X718691D03*
X716191Y616359D03*
X711391D03*
X706070Y638125D03*
X716656Y646429D03*
X703669Y665140D03*
X716350Y699477D03*
X703604Y699653D03*
X716146Y1350683D03*
X711190D03*
X716146Y1345691D03*
X711190D03*
X703906Y1350683D03*
Y1345597D03*
X716146Y1357603D03*
X711190D03*
Y1362595D03*
X716146D03*
X703906Y1357603D03*
Y1362595D03*
X716146Y1374881D03*
Y1381801D03*
Y1369889D03*
X711190D03*
Y1374881D03*
Y1381801D03*
X703906D03*
Y1369889D03*
Y1374881D03*
X716146Y1399079D03*
X711190D03*
X716146Y1393993D03*
X711190D03*
X703906Y1394087D03*
Y1399079D03*
X716146Y1386793D03*
X711190D03*
X703906D03*
X716146Y1405999D03*
X711190D03*
X716146Y1410991D03*
X711190D03*
X703906Y1405999D03*
Y1410991D03*
X712000Y1644980D03*
X721741Y-27628D03*
X721756Y-25113D03*
X724781Y-26433D03*
X735192Y94017D03*
X731192D03*
X733233Y151540D03*
X736750Y188727D03*
X730707Y226141D03*
X733507D03*
X733404Y285690D03*
X720090Y293796D03*
X722590D03*
X728104Y288190D03*
X730604Y285690D03*
X728104D03*
X730604Y288190D03*
X733404D03*
X731511Y390500D03*
X734606Y379562D03*
X722097Y410394D03*
Y403307D03*
X723491Y458406D03*
Y451319D03*
Y465492D03*
X723315Y462264D03*
X723491Y472579D03*
Y479665D03*
Y486752D03*
Y493839D03*
Y523799D03*
Y516713D03*
Y509626D03*
Y530886D03*
Y537973D03*
Y566752D03*
Y559665D03*
Y573839D03*
Y588012D03*
Y580926D03*
Y595099D03*
Y602185D03*
Y609272D03*
Y616358D03*
X734819Y646429D03*
X725318Y890354D03*
X720373Y940310D03*
X724547Y958287D03*
X723430Y1350683D03*
X728386Y1345691D03*
X723430D03*
X728386Y1350683D03*
Y1357603D03*
Y1362595D03*
X723430Y1357603D03*
Y1362595D03*
X728386Y1381801D03*
Y1374881D03*
Y1369889D03*
X723430D03*
Y1381801D03*
Y1374881D03*
X728386Y1386793D03*
X723430D03*
X728386Y1398985D03*
Y1393993D03*
X723430Y1398985D03*
Y1393993D03*
X728386Y1410897D03*
Y1405905D03*
X723430Y1410897D03*
Y1405905D03*
X732000Y1644980D03*
X748269Y84140D03*
Y76140D03*
Y80140D03*
X743201Y94017D03*
X739192D03*
X750714Y117557D03*
X745722D03*
X740312Y115401D03*
Y110445D03*
X735320D03*
Y115401D03*
X745722Y131731D03*
Y122513D03*
X740312Y129574D03*
Y124618D03*
X735320D03*
Y129574D03*
X750714Y131731D03*
Y122513D03*
Y136687D03*
X745722D03*
X748813Y146461D03*
X747715Y152367D03*
X749415Y180572D03*
Y185165D03*
X743383Y184619D03*
X736883Y191941D03*
X745363Y206760D03*
X738577Y256535D03*
X746577D03*
X747607Y279208D03*
X751711Y281307D03*
X741630Y290755D03*
X737630D03*
X745630D03*
X741161Y381500D03*
X741602Y465492D03*
X741568Y460250D03*
X739333Y470136D03*
X741602Y472579D03*
X741072Y478958D03*
X741602Y486752D03*
Y493839D03*
Y509626D03*
Y516713D03*
X738062Y537973D03*
X740542Y525483D03*
X740463Y532756D03*
X741602Y559665D03*
Y566752D03*
X741452Y579978D03*
X741602Y573839D03*
X741666Y608117D03*
X741000Y771100D03*
X738707Y987952D03*
X745673Y1007009D03*
X747910Y1345691D03*
Y1350683D03*
X735670D03*
X740626D03*
X735670Y1345691D03*
X740626D03*
X747910Y1357603D03*
Y1362595D03*
X735670Y1357603D03*
Y1362595D03*
X740626Y1357603D03*
Y1362595D03*
X747910Y1374881D03*
Y1381801D03*
Y1369889D03*
X740626Y1381801D03*
Y1369889D03*
Y1374881D03*
X735670Y1381801D03*
Y1369889D03*
Y1374881D03*
X747910Y1386793D03*
X735670Y1393993D03*
X740626D03*
Y1398985D03*
X735670D03*
X740626Y1386793D03*
X735670D03*
Y1405905D03*
Y1410897D03*
X740626Y1405905D03*
Y1410897D03*
X742655Y1445733D03*
X747590Y1627871D03*
X765847Y55513D03*
X762065Y117040D03*
X754098Y180527D03*
X757821Y192421D03*
X754053Y185121D03*
X756201Y288345D03*
Y290845D03*
X753701Y288345D03*
Y290845D03*
Y293645D03*
X756201D03*
X763898Y342319D03*
X766344Y393924D03*
Y389912D03*
Y385912D03*
X758038Y381143D03*
X766344Y409924D03*
Y405924D03*
Y401924D03*
X752341Y407148D03*
X756800Y403824D03*
X758381Y395391D03*
X759543Y445787D03*
X755593Y445908D03*
X765106Y1350683D03*
Y1345597D03*
X760150D03*
Y1350683D03*
X752866Y1345691D03*
Y1350683D03*
X765106Y1362595D03*
Y1357603D03*
X760150D03*
Y1362595D03*
X752866Y1357603D03*
Y1362595D03*
X765106Y1374881D03*
Y1381801D03*
Y1369889D03*
X760150Y1374881D03*
Y1381801D03*
Y1369889D03*
X752866Y1374881D03*
Y1381801D03*
Y1369889D03*
X765106Y1386793D03*
X760150D03*
X752866D03*
X766433Y1583713D03*
X752150Y1627871D03*
X762776Y1629415D03*
X752000Y1644980D03*
X771011Y60922D03*
X767929Y96890D03*
X771824Y110784D03*
X769175Y113394D03*
X779418Y133298D03*
X771960Y130898D03*
X773565Y134579D03*
X769351Y172665D03*
Y180665D03*
X769383Y200864D03*
Y212864D03*
Y221864D03*
Y216864D03*
X771140Y252371D03*
X780968Y303839D03*
X772990Y336324D03*
X777569Y353506D03*
X772390Y1350683D03*
X777346D03*
Y1345691D03*
X772390D03*
Y1357603D03*
Y1362595D03*
X777346Y1357603D03*
Y1362595D03*
X777114Y1442270D03*
X778045Y1622545D03*
X782289Y1620109D03*
X773822Y1627418D03*
X772000Y1644980D03*
X784410Y109172D03*
X787410D03*
X794961Y116497D03*
X797461D03*
X790161D03*
X786417Y106495D03*
X797461Y109410D03*
Y123583D03*
X794961Y123584D03*
X790161D03*
X794961Y130670D03*
X797461D03*
X790161D03*
X794961Y137757D03*
X790161D03*
X788057Y141228D03*
X786151Y146012D03*
X793221Y140296D03*
X790945Y150847D03*
X792913Y247292D03*
X785622Y253198D03*
X788522Y290304D03*
X799937Y347340D03*
X791686Y1025440D03*
X794716Y1186071D03*
X792183Y1334030D03*
Y1331230D03*
X789383Y1334030D03*
Y1331230D03*
X794506Y1411307D03*
X793723Y1468071D03*
X793564Y1642682D03*
X810623Y77784D03*
Y82984D03*
Y80384D03*
Y75184D03*
X813177Y92849D03*
X810623Y85584D03*
X802161Y116496D03*
Y109410D03*
Y102323D03*
Y130670D03*
Y123583D03*
Y137756D03*
X816364Y486870D03*
X813864D03*
X813566Y744187D03*
X812661Y810032D03*
X812980Y824166D03*
X816016Y838036D03*
X813182Y852800D03*
X814731Y889365D03*
X812811Y908162D03*
X809682Y1133284D03*
X806787Y1148000D03*
X815034Y1159455D03*
X809623Y1160168D03*
X809393Y1187252D03*
X807487Y1193019D03*
X815487D03*
X811487D03*
X817446Y1210089D03*
X800627Y1392748D03*
X800703Y1426779D03*
X811457Y1639797D03*
X820137Y103037D03*
X820271Y116496D03*
Y109410D03*
Y130670D03*
Y123583D03*
X816637Y137756D03*
X824952Y293796D03*
X822452D03*
X830466Y285690D03*
Y288190D03*
X825792Y305225D03*
X823529Y467189D03*
X830318Y674164D03*
X829784Y713939D03*
X832284Y731216D03*
X830484Y746701D03*
X819993Y754109D03*
X817500Y760000D03*
X820547Y780314D03*
X826925Y769000D03*
X820500Y777500D03*
X826925Y787000D03*
X820500Y792000D03*
X818500Y814000D03*
X820432Y800529D03*
X826925Y805000D03*
Y823000D03*
X826165Y863000D03*
X819134Y863607D03*
X829000Y852000D03*
X825686Y869496D03*
X826797Y883756D03*
X825508Y913869D03*
X822462Y915095D03*
X818347Y939610D03*
X828193Y949324D03*
X832432Y977982D03*
X832711Y993268D03*
X828385Y1120599D03*
X817006Y1133027D03*
X822006Y1130208D03*
X825744Y1146937D03*
X823220Y1162817D03*
X823487Y1193019D03*
X819487D03*
X826612Y1219254D03*
X819522Y1212164D03*
X821816Y1214458D03*
X832084Y1461072D03*
X831457Y1639797D03*
X844781Y-65613D03*
X841756Y-64293D03*
X838503Y-64307D03*
X841741Y-66808D03*
X838488Y-66822D03*
X841554Y94017D03*
X837554D03*
X845563D03*
X833554D03*
X837682Y110445D03*
Y115401D03*
X848084Y117557D03*
X842674Y115401D03*
Y110445D03*
Y129574D03*
Y124618D03*
X837682D03*
Y129574D03*
X848084Y131731D03*
Y122513D03*
Y136687D03*
X839112Y188727D03*
X839245Y191941D03*
X845745Y184619D03*
X847725Y206760D03*
X833069Y226141D03*
X835869D03*
X848939Y256535D03*
X840939D03*
X832966Y288190D03*
Y285690D03*
X835766Y288190D03*
Y285690D03*
X843992Y290755D03*
X839992D03*
X847992D03*
X835236Y533174D03*
X845729Y661263D03*
X836503Y667845D03*
X845784Y713939D03*
X848284Y731181D03*
X846484Y746701D03*
X841500Y758161D03*
Y776161D03*
Y794161D03*
Y812161D03*
X838685Y832987D03*
X845654Y895437D03*
X833870Y881860D03*
X839381Y915839D03*
X839122Y939655D03*
X843734Y1008778D03*
X848520Y1016855D03*
X850631Y84140D03*
Y80140D03*
Y76140D03*
X864006Y117261D03*
X853076Y117557D03*
Y131731D03*
Y122513D03*
Y136687D03*
X851777Y180572D03*
X856460Y180527D03*
X860183Y192421D03*
X851777Y185165D03*
X856415Y185121D03*
X849969Y279208D03*
X854073Y281307D03*
X864920Y343168D03*
X854086Y385000D03*
X858586D03*
X850733Y461382D03*
X850832Y473382D03*
X850738Y477382D03*
X850909Y482382D03*
X853900Y627700D03*
X858202Y646330D03*
X851111Y656635D03*
X856145Y677887D03*
X855646Y685230D03*
X858186Y713170D03*
X867227Y722060D03*
X849500Y761000D03*
X864575Y770500D03*
X849500Y779000D03*
X864575Y788500D03*
X849500Y797000D03*
Y815000D03*
X864575Y806500D03*
X865004Y831273D03*
X864464Y828503D03*
X864575Y824500D03*
X851782Y823720D03*
X851161Y855205D03*
X856628Y915242D03*
X864253D03*
X849600Y915266D03*
X855867Y935540D03*
X849088Y951081D03*
X852247Y1009529D03*
X849996Y1091073D03*
X850023Y1095179D03*
X863342Y1120636D03*
X855542D03*
X858142D03*
X860842D03*
X863442Y1130336D03*
X858242D03*
X855642D03*
X860942D03*
Y1139336D03*
X863442D03*
X861119Y1148080D03*
X863619D03*
X851457Y1639797D03*
X873373Y60922D03*
X868209Y55513D03*
X870395Y96738D03*
X865402Y91951D03*
X871713Y172665D03*
Y180665D03*
X871745Y200864D03*
Y212864D03*
Y216864D03*
Y221864D03*
X876246Y302754D03*
X869313Y688486D03*
X872069Y700894D03*
X876286Y686970D03*
X880501Y710611D03*
X873021Y715729D03*
X877616Y749484D03*
X873318Y744597D03*
X873250Y798750D03*
X872700Y816615D03*
X872628Y915242D03*
X880628D03*
X876481Y941126D03*
X868908Y933640D03*
X867199Y949372D03*
X869390Y978003D03*
X878004Y1224406D03*
X883142Y1259935D03*
X875700Y1299700D03*
X871457Y1639797D03*
X886011Y154100D03*
X895780Y237517D03*
Y232634D03*
X886261Y252090D03*
X885741Y261150D03*
X894844Y418983D03*
X889219Y426952D03*
X887770Y415290D03*
X890270D03*
X897344Y418983D03*
X894519Y426952D03*
X889596Y437264D03*
X896388Y437614D03*
X887096Y437264D03*
X892019Y426952D03*
X897019D03*
X882891Y536122D03*
X896449Y550863D03*
X893949Y550363D03*
X882949Y557363D03*
X887949Y608863D03*
X894449Y606363D03*
X884903Y694119D03*
X886836Y729778D03*
X889083Y780371D03*
X888545Y785528D03*
X888514Y797602D03*
X891916Y808965D03*
X882609Y994245D03*
X897056Y1091391D03*
X891055Y1095407D03*
X897056Y1095984D03*
X884906Y1102760D03*
X884890Y1098724D03*
X893190Y1208069D03*
X894887Y1227209D03*
X891003Y1292765D03*
X890738Y1311132D03*
X891457Y1639797D03*
X898813Y146461D03*
X897715Y152367D03*
X898851Y231496D03*
Y238583D03*
Y245669D03*
X910977Y238583D03*
X898851Y259843D03*
X898576Y253056D03*
X910977Y252756D03*
Y257480D03*
X898851Y274016D03*
X910977Y266929D03*
X898851D03*
X912786Y306697D03*
X901848Y307782D03*
Y312738D03*
X909417Y323302D03*
X912085Y332335D03*
X898888Y437614D03*
X906996Y530707D03*
X902459Y530755D03*
X911630Y543998D03*
X910578Y550186D03*
X909362Y555614D03*
X898156Y554812D03*
X909024Y586768D03*
X908730Y619120D03*
X913686D03*
X899898Y619040D03*
X904854D03*
X910036Y702285D03*
X910753Y715864D03*
X912864Y864189D03*
Y870488D03*
Y867338D03*
X899693Y895207D03*
X904833Y915340D03*
X912628Y928101D03*
X911355Y944909D03*
X906710Y962433D03*
X906909Y951494D03*
X909296Y1020224D03*
X909300Y1014639D03*
X901739Y1091346D03*
X897815Y1078042D03*
X901366Y1078069D03*
X901694Y1095940D03*
X911071Y1123803D03*
X905771D03*
X903171D03*
X908371D03*
X910971Y1114103D03*
X908271D03*
X903071D03*
X905671D03*
X911699Y1129488D03*
X909041Y1126328D03*
X911641D03*
X903908Y1132870D03*
X904063Y1135946D03*
X901940Y1236799D03*
Y1229899D03*
Y1232399D03*
Y1246199D03*
Y1243699D03*
Y1239299D03*
X904703Y1297398D03*
X911457Y1639797D03*
X919175Y113394D03*
X921824Y110784D03*
X921418Y133298D03*
X929418D03*
X923565Y134579D03*
X920142Y308501D03*
X926801Y323302D03*
X923902Y332411D03*
X924600Y533706D03*
X920961Y550075D03*
X915949Y563363D03*
X915712Y613792D03*
X915194Y666671D03*
X928043Y677795D03*
X917286Y679625D03*
X924932Y701051D03*
X920628Y928101D03*
X928628D03*
X916628D03*
X924628D03*
X924487Y951244D03*
X918648Y964717D03*
X915490Y969886D03*
X916749Y1080659D03*
Y1088659D03*
X917110Y1101902D03*
X927598Y1120636D03*
X924898D03*
X914661Y1132612D03*
X914299Y1129488D03*
X914241Y1126328D03*
X924919Y1130336D03*
X927619D03*
X924919Y1139336D03*
X927419D03*
X925097Y1147708D03*
X927597D03*
X927146Y1328597D03*
Y1323641D03*
X929094Y1542353D03*
Y1545353D03*
X926041Y1554503D03*
Y1551503D03*
Y1548503D03*
Y1557503D03*
Y1560503D03*
X944961Y116497D03*
X934410Y109172D03*
X936417Y106495D03*
X937410Y109172D03*
X940161Y116497D03*
Y123584D03*
X944961D03*
X940161Y130670D03*
X944961D03*
X940161Y137757D03*
X944961D03*
X936151Y146012D03*
X938057Y141228D03*
X940945Y150847D03*
X932388Y330517D03*
X932622Y336817D03*
X944694Y352192D03*
X931627Y561578D03*
Y565578D03*
X943825Y581222D03*
Y591215D03*
X935281Y677795D03*
X945626Y789761D03*
X932000Y831000D03*
X942634Y886520D03*
X933700Y887508D03*
X944839Y902400D03*
X938188Y900853D03*
X944628Y928101D03*
X932628D03*
X936628D03*
X940497D03*
X941981Y1224406D03*
X947119Y1259935D03*
X933254Y1308273D03*
X940848Y1310181D03*
X930441Y1455039D03*
Y1458039D03*
Y1464039D03*
Y1461039D03*
Y1467039D03*
X938670Y1510528D03*
X941270D03*
Y1505328D03*
X938670D03*
X940170Y1507928D03*
X943870Y1510528D03*
Y1505328D03*
X945370Y1507928D03*
X942770D03*
X935094Y1542353D03*
X932094D03*
X935094Y1545353D03*
X932094D03*
X938094Y1542353D03*
Y1545353D03*
X941094Y1542353D03*
X944094D03*
X941094Y1545353D03*
X944094D03*
X931457Y1639797D03*
X960623Y82984D03*
Y77784D03*
Y80384D03*
Y75184D03*
Y85584D03*
X947461Y116497D03*
X952161Y116496D03*
Y109410D03*
Y102323D03*
X947461Y109410D03*
Y130670D03*
X952161D03*
Y123583D03*
X947461D03*
X952161Y137756D03*
X949443Y208206D03*
X949579Y330517D03*
X949813Y336817D03*
X956863Y451466D03*
X953816Y555194D03*
X951016D03*
X953816Y571194D03*
X951016D03*
X953816Y563194D03*
X951016D03*
X946625Y581222D03*
X949425D03*
Y591215D03*
X946625D03*
X948427Y611091D03*
X957551Y698251D03*
X954023Y725336D03*
X951195Y727165D03*
X952681Y735256D03*
X956323Y748412D03*
X957474Y764426D03*
X955086Y779798D03*
X956051Y793937D03*
X947735Y824921D03*
X948935Y835800D03*
X954700Y842700D03*
X947735Y854935D03*
X953091Y857440D03*
X953217Y861440D03*
X955967Y860376D03*
X946700Y849200D03*
X950251Y874268D03*
X950291Y870240D03*
Y866240D03*
X953145Y874240D03*
X952738Y886624D03*
X953587Y902814D03*
X961479Y927643D03*
X957671Y991564D03*
X946642Y991361D03*
X961033Y1091391D03*
X948883Y1102760D03*
X948867Y1098724D03*
X955032Y1095407D03*
X961033Y1095984D03*
X957167Y1208069D03*
X958864Y1227209D03*
X949970Y1321749D03*
X952070Y1367717D03*
X949070D03*
X956238Y1455139D03*
Y1458139D03*
Y1461139D03*
Y1464139D03*
X952676Y1461039D03*
Y1464039D03*
Y1458039D03*
Y1455039D03*
X956238Y1467139D03*
Y1469902D03*
X952676Y1467039D03*
X946470Y1510528D03*
Y1505328D03*
X947094Y1545353D03*
Y1542353D03*
X951457Y1639797D03*
X963177Y92849D03*
X970137Y103037D03*
X970271Y116496D03*
Y109410D03*
Y130670D03*
Y123583D03*
X966347Y137756D03*
X974952Y293796D03*
X972452D03*
X972147Y323681D03*
X975932Y437508D03*
X971932D03*
X962769Y458466D03*
X973695Y448874D03*
X969109Y449352D03*
X978723Y504699D03*
X976223D03*
X973723D03*
X978425Y516979D03*
X973425D03*
X975925D03*
X967302Y627948D03*
X969491Y629362D03*
X963187Y667620D03*
X973138Y667621D03*
X978059Y747438D03*
X976764Y786563D03*
X964070Y807686D03*
Y813006D03*
X977218Y802178D03*
X964036Y818961D03*
X968319Y826191D03*
X976635Y835018D03*
X976800Y838011D03*
X974282D03*
X976902Y847135D03*
X971808Y851242D03*
X975925Y854783D03*
X978201Y897500D03*
X969806Y993033D03*
X965716Y1091346D03*
X965671Y1095940D03*
X967148Y1123803D03*
X969748D03*
X969648Y1114103D03*
X967048D03*
X972348Y1123803D03*
X975048D03*
X972248Y1114103D03*
X974948D03*
X970485Y1132870D03*
X967885D03*
X968874Y1145169D03*
X966374D03*
X965917Y1236799D03*
Y1229899D03*
Y1232399D03*
Y1246199D03*
Y1243699D03*
Y1239299D03*
X978727Y1284908D03*
X971467Y1509515D03*
X974067D03*
X972567Y1512115D03*
X969967D03*
X976667Y1509515D03*
X977767Y1506915D03*
X975167D03*
X969967D03*
X972567D03*
X975167Y1512115D03*
X977767D03*
X971140Y1514693D03*
X968540D03*
X973740D03*
X976340D03*
X971457Y1639797D03*
X983554Y94017D03*
X987554D03*
X991554D03*
X987682Y115401D03*
X992674D03*
Y110445D03*
X987682D03*
X992674Y124618D03*
X987682D03*
Y129574D03*
X992674D03*
X985595Y151540D03*
X989245Y191941D03*
X989112Y188727D03*
X983069Y226141D03*
X985869D03*
X990939Y256535D03*
X985766Y288190D03*
X982966D03*
X985766Y285690D03*
X982966D03*
X980466Y288190D03*
Y285690D03*
X993992Y290755D03*
X989992D03*
X979932Y437508D03*
X982792Y447269D03*
X982670Y450201D03*
X989936Y519531D03*
X987436D03*
X982436D03*
X984936D03*
X983843Y633205D03*
Y636005D03*
Y638805D03*
X984307Y748432D03*
X985030Y781204D03*
X988329Y781445D03*
X991990Y773974D03*
X984963Y785387D03*
X979313Y814316D03*
X987903Y818645D03*
X993061Y833135D03*
X979203Y837159D03*
X988820Y858903D03*
X980529Y879097D03*
X988231Y878203D03*
X984892Y868720D03*
X987790Y896596D03*
X995133Y888503D03*
X982787Y899757D03*
X988461Y1013841D03*
X980726Y1080659D03*
Y1088659D03*
X981087Y1101902D03*
X988389Y1302558D03*
X980501Y1369685D03*
X983501D03*
X979538Y1464039D03*
Y1461039D03*
Y1458039D03*
Y1455039D03*
Y1467039D03*
Y1469802D03*
X979267Y1509515D03*
X984467D03*
X981867D03*
X985567Y1512115D03*
Y1506915D03*
X980367D03*
X982967D03*
Y1512115D03*
X980367D03*
X989667Y1509515D03*
X992267D03*
X987067D03*
X988167Y1512115D03*
X990767D03*
Y1506915D03*
X988167D03*
X984140Y1514693D03*
X981540D03*
X978940D03*
X986740D03*
X989340D03*
X991457Y1639797D03*
X1005256Y-25113D03*
X1002003Y-25027D03*
X1005241Y-27628D03*
X1001988Y-27542D03*
X1008281Y-26433D03*
X1000631Y84140D03*
Y76140D03*
Y80140D03*
X995563Y94017D03*
X1003076Y117557D03*
X998084D03*
X1003076Y122513D03*
Y131731D03*
X998084Y122513D03*
Y131731D03*
X1001175Y146461D03*
X1003076Y136687D03*
X998084D03*
X1000077Y152367D03*
X1001777Y180572D03*
X1006460Y180527D03*
X1010183Y192421D03*
X1001777Y185165D03*
X1006415Y185121D03*
X995745Y184619D03*
X997725Y206760D03*
X998939Y256535D03*
X999826Y278734D03*
X1004061Y280808D03*
X997992Y290755D03*
X1004544Y318050D03*
X1004933Y314535D03*
X997921Y333654D03*
X995913Y633450D03*
Y636250D03*
Y639050D03*
X1008342Y761735D03*
X1003539Y762632D03*
X1002834Y777394D03*
X1006053Y787745D03*
X999825Y819488D03*
X1002887Y834342D03*
X1000369D03*
X1005607Y874859D03*
Y877859D03*
X1002930Y906785D03*
X1010009Y998100D03*
X1005301Y1006560D03*
X999700Y1018400D03*
X1008312Y1363533D03*
X1008452Y1376752D03*
X1008483Y1372734D03*
X1006211Y1397662D03*
X1009338Y1391597D03*
Y1388597D03*
X1002538Y1463939D03*
Y1460939D03*
Y1457939D03*
Y1454939D03*
Y1466939D03*
Y1469702D03*
X1008549Y1509815D03*
X1007049Y1507215D03*
X1011149Y1509815D03*
X1009649Y1507215D03*
Y1512415D03*
X1007049D03*
X1008222Y1514993D03*
X1005622D03*
X1010822D03*
X1023373Y60922D03*
X1018209Y55513D03*
X1020254Y97068D03*
X1014006Y117261D03*
X1021537Y113394D03*
X1024186Y110784D03*
X1024289Y130898D03*
X1025927Y134579D03*
X1021713Y180665D03*
Y172665D03*
X1026915Y203393D03*
X1021745Y212864D03*
Y200864D03*
Y221864D03*
Y216864D03*
X1023502Y252371D03*
X1013354Y323362D03*
X1013327Y327453D03*
X1013318Y333190D03*
X1022845Y340944D03*
X1013313Y339909D03*
X1015195Y428305D03*
X1015804Y760454D03*
X1026090Y770943D03*
X1019375Y783056D03*
X1018044Y793592D03*
X1015800Y807535D03*
X1014587Y802788D03*
X1025859Y802275D03*
X1020703Y833659D03*
X1021221Y848712D03*
X1025219Y842155D03*
X1025239Y845070D03*
X1022009Y997860D03*
X1018009D03*
X1026009D03*
X1014009D03*
X1014767Y1035088D03*
X1022594Y1035114D03*
X1017297Y1102091D03*
X1026606Y1102591D03*
X1023106Y1102091D03*
X1017297Y1114691D03*
X1023106D03*
X1026606D03*
X1023106Y1127291D03*
X1026606D03*
X1017297Y1139891D03*
X1023106D03*
X1026606D03*
X1017297Y1127291D03*
X1026606Y1152491D03*
X1017297D03*
X1023106D03*
X1017297Y1165091D03*
X1023106D03*
X1026606D03*
X1017297Y1177691D03*
X1023106D03*
X1026606D03*
X1022420Y1203204D03*
X1026968Y1223749D03*
X1025434Y1320606D03*
X1011829Y1347471D03*
Y1342515D03*
X1015286Y1344924D03*
X1021623Y1373216D03*
X1012338Y1388597D03*
Y1391597D03*
X1015338D03*
Y1388597D03*
X1021338D03*
Y1391597D03*
X1018338D03*
Y1388597D03*
X1027338D03*
Y1391597D03*
X1024338D03*
Y1388597D03*
X1025138Y1463839D03*
Y1460839D03*
Y1457839D03*
Y1454839D03*
Y1466839D03*
Y1469602D03*
X1013749Y1509815D03*
X1016349D03*
X1021549D03*
X1018949D03*
X1024149D03*
X1022649Y1507215D03*
X1025249D03*
X1017449D03*
X1020049D03*
X1014849D03*
X1012249D03*
X1026749Y1509815D03*
X1012249Y1512415D03*
X1014849D03*
X1025249D03*
X1022649D03*
X1020049D03*
X1017449D03*
X1013422Y1514993D03*
X1023822D03*
X1021222D03*
X1018622D03*
X1016022D03*
X1026422D03*
X1011457Y1639797D03*
X1036772Y109172D03*
X1039772D03*
X1038779Y106495D03*
X1042523Y116497D03*
X1031780Y133298D03*
X1042523Y130670D03*
Y123584D03*
X1038513Y146012D03*
X1040419Y141228D03*
X1042523Y137757D03*
X1043307Y150847D03*
X1037984Y253198D03*
X1031354Y325901D03*
X1031382Y340947D03*
X1031310Y337888D03*
X1031377Y333671D03*
X1031362Y329268D03*
X1038796Y763272D03*
X1042880Y794924D03*
X1028155Y879413D03*
X1030300Y881400D03*
X1043252Y902501D03*
X1030009Y997860D03*
X1034009D03*
X1038252Y1009354D03*
X1034752D03*
X1028943D03*
X1042009Y997860D03*
X1038009D03*
X1034752Y1021954D03*
X1038252D03*
X1043553Y1035384D03*
X1040600Y1210600D03*
X1035384Y1215195D03*
X1034513Y1333665D03*
X1042586Y1345824D03*
X1030338Y1391597D03*
Y1388597D03*
X1029349Y1509815D03*
X1027849Y1507215D03*
Y1512415D03*
X1031457Y1639797D03*
X1049823Y109410D03*
X1054523Y116496D03*
Y109410D03*
Y102323D03*
X1049823Y116497D03*
X1047323D03*
X1049823Y130670D03*
X1047323D03*
Y123584D03*
X1049823Y123583D03*
X1054523Y130670D03*
Y123583D03*
Y137756D03*
X1047323Y137757D03*
X1045275Y247292D03*
X1050777Y450750D03*
X1054876Y536382D03*
X1059843Y597580D03*
X1059782Y594668D03*
X1062098Y615600D03*
X1044112Y778835D03*
X1045744Y800835D03*
X1048328Y808166D03*
X1057961Y931919D03*
X1046009Y997860D03*
X1054009D03*
X1050009D03*
X1058009D03*
X1059689Y1012354D03*
Y1024954D03*
X1048043Y1105091D03*
Y1117691D03*
Y1130291D03*
Y1155491D03*
Y1142891D03*
Y1168091D03*
Y1180691D03*
X1051249Y1290288D03*
X1052221Y1336984D03*
X1058891Y1345691D03*
Y1350683D03*
X1053935Y1345691D03*
Y1350683D03*
X1058891Y1362595D03*
X1053935D03*
X1058891Y1357603D03*
X1053935D03*
X1058891Y1381801D03*
Y1374881D03*
Y1369889D03*
X1053935Y1381801D03*
Y1374881D03*
Y1369889D03*
X1058891Y1386793D03*
X1053935D03*
X1051457Y1639797D03*
X1071988Y-66722D03*
X1075241Y-66808D03*
X1072003Y-64207D03*
X1075256Y-64293D03*
X1062985Y82984D03*
Y75184D03*
Y77784D03*
Y80384D03*
X1065539Y92849D03*
X1062985Y85584D03*
X1072499Y103037D03*
X1072633Y116496D03*
Y109410D03*
Y130670D03*
Y123583D03*
X1069224Y137756D03*
X1074814Y293796D03*
X1061325Y339509D03*
X1060679Y360151D03*
Y364276D03*
X1071548Y555234D03*
X1071263Y562003D03*
X1062066Y599588D03*
X1061328Y589556D03*
X1061267Y592354D03*
X1062069Y596095D03*
X1062066Y607588D03*
X1066559Y634946D03*
X1066009Y997860D03*
X1062009D03*
X1074009D03*
X1070778Y1012252D03*
X1066933Y1040567D03*
X1071641Y1058029D03*
X1060172Y1050481D03*
X1071348Y1050503D03*
X1066175Y1350683D03*
Y1345691D03*
X1071131Y1350683D03*
Y1345691D03*
X1066175Y1357603D03*
Y1362595D03*
X1071131Y1357603D03*
Y1362595D03*
X1066175Y1381801D03*
Y1369795D03*
Y1374881D03*
X1071131Y1381801D03*
Y1369795D03*
Y1374881D03*
X1066175Y1393993D03*
Y1399079D03*
Y1386793D03*
X1071131Y1399079D03*
Y1393993D03*
Y1386793D03*
X1066175Y1405999D03*
Y1410991D03*
X1071131Y1405999D03*
Y1410991D03*
X1071457Y1639797D03*
X1078281Y-65613D03*
X1089916Y94017D03*
X1085916D03*
X1090044Y110445D03*
Y115401D03*
Y124618D03*
Y129574D03*
X1087957Y151540D03*
X1091607Y191941D03*
X1091474Y188727D03*
X1085431Y226141D03*
X1088231D03*
X1088128Y285690D03*
Y288190D03*
X1085328D03*
X1082828Y285690D03*
X1085328D03*
X1082828Y288190D03*
X1077314Y293796D03*
X1092354Y290755D03*
X1077602Y314060D03*
X1091542Y389154D03*
Y410413D03*
Y396240D03*
Y403327D03*
Y417500D03*
Y424587D03*
Y431673D03*
Y438760D03*
Y445847D03*
Y467539D03*
Y474626D03*
Y488799D03*
Y481713D03*
Y495886D03*
Y511673D03*
Y518760D03*
Y525847D03*
Y532933D03*
Y540020D03*
Y547106D03*
X1090823Y602197D03*
X1091287Y595108D03*
X1079809Y1034386D03*
X1090655Y1350683D03*
Y1345691D03*
X1083371D03*
Y1350683D03*
X1078415Y1345691D03*
Y1350683D03*
X1090655Y1357603D03*
Y1362595D03*
X1083371Y1357603D03*
Y1362595D03*
X1078415D03*
Y1357603D03*
X1090655Y1381801D03*
Y1374881D03*
Y1369889D03*
X1083371D03*
Y1374881D03*
Y1381801D03*
X1078415Y1369889D03*
Y1374881D03*
Y1381801D03*
X1090655Y1394087D03*
Y1399079D03*
Y1386793D03*
X1083371D03*
Y1399079D03*
Y1394087D03*
X1078415Y1386793D03*
Y1394087D03*
Y1399079D03*
X1090655Y1405999D03*
Y1410991D03*
X1083371Y1405999D03*
Y1410991D03*
X1078415Y1405999D03*
Y1410991D03*
X1092000Y1644980D03*
X1102993Y84140D03*
Y76140D03*
Y80140D03*
X1097925Y94017D03*
X1093916D03*
X1100446Y117557D03*
X1095036Y115401D03*
Y110445D03*
X1105438Y117557D03*
X1095036Y129574D03*
Y124618D03*
X1105438Y131731D03*
Y122513D03*
X1100446Y131731D03*
Y122513D03*
X1103537Y146461D03*
X1100446Y136687D03*
X1105438D03*
X1102439Y152367D03*
X1104139Y180572D03*
X1108822Y180527D03*
X1104139Y185165D03*
X1108777Y185121D03*
X1098107Y184619D03*
X1100087Y206760D03*
X1101301Y256535D03*
X1093301D03*
X1102331Y279208D03*
X1106435Y281307D03*
X1096354Y290755D03*
X1100354D03*
X1100703Y340560D03*
X1101999Y353495D03*
X1093994Y374003D03*
X1106161Y389154D03*
X1104691Y396240D03*
X1108776Y422864D03*
X1108846Y429832D03*
X1108451Y436447D03*
X1108395Y472772D03*
X1105002Y516841D03*
X1108253Y510565D03*
X1099949Y550123D03*
X1099827Y552872D03*
X1101581Y572334D03*
X1099272Y562443D03*
X1101040Y560675D03*
X1099813Y574102D03*
X1104448Y653161D03*
X1108045Y677843D03*
X1107851Y1345691D03*
X1102895Y1350683D03*
Y1345691D03*
X1107851Y1350683D03*
X1095611D03*
Y1345691D03*
X1107851Y1357603D03*
X1102895Y1362595D03*
Y1357603D03*
X1107851Y1362595D03*
X1095611Y1357603D03*
Y1362595D03*
X1107851Y1369889D03*
Y1374881D03*
Y1381801D03*
X1102895Y1374881D03*
Y1369889D03*
Y1381801D03*
X1095611D03*
Y1374881D03*
Y1369889D03*
X1107851Y1386793D03*
Y1394087D03*
Y1399079D03*
X1102895Y1386793D03*
Y1394087D03*
Y1399079D03*
X1095611D03*
Y1394087D03*
Y1386793D03*
X1107851Y1405999D03*
Y1410991D03*
X1102895Y1405999D03*
Y1410991D03*
X1095611Y1405999D03*
Y1410991D03*
X1099900Y1535700D03*
X1107620Y1606752D03*
X1123052Y57511D03*
X1122613Y97042D03*
X1116368Y117261D03*
X1123899Y113394D03*
X1124075Y180665D03*
Y172665D03*
X1112545Y192421D03*
X1124107Y200864D03*
Y212864D03*
Y216864D03*
Y221864D03*
X1123500Y329000D03*
Y339000D03*
Y334000D03*
X1124753Y389153D03*
X1122253Y396240D03*
X1124753D03*
X1122253Y403327D03*
X1124753Y403326D03*
X1122253Y410413D03*
X1124753D03*
X1109468Y414823D03*
X1122253Y424586D03*
X1124753D03*
X1122253Y417500D03*
X1124753Y417499D03*
X1122253Y438760D03*
X1124753D03*
Y431673D03*
X1122253D03*
X1110486Y447953D03*
X1122253Y445847D03*
X1109653Y467539D03*
X1124753D03*
X1122253Y474626D03*
X1124753D03*
X1122253Y488799D03*
X1124753D03*
X1109129Y487711D03*
X1109242Y479104D03*
X1124753Y481712D03*
X1122253D03*
Y495886D03*
X1109653D03*
X1124753Y518760D03*
X1122253D03*
X1124753Y511673D03*
Y532933D03*
X1122253D03*
Y540020D03*
Y525846D03*
X1124753D03*
X1118863Y662981D03*
X1112839Y668885D03*
X1113244Y691851D03*
X1118855Y705043D03*
X1115135Y1345691D03*
Y1350683D03*
X1120091Y1345691D03*
Y1350683D03*
X1115135Y1357603D03*
Y1362595D03*
X1120091Y1357603D03*
Y1362595D03*
X1115135Y1374881D03*
Y1381801D03*
Y1369889D03*
X1120091D03*
Y1374881D03*
Y1381801D03*
X1115135Y1394087D03*
Y1399079D03*
Y1386793D03*
X1120091Y1399079D03*
Y1394087D03*
Y1386793D03*
X1115135Y1405999D03*
Y1410991D03*
X1120091Y1405999D03*
Y1410991D03*
X1112000Y1644980D03*
X1125735Y60922D03*
X1139134Y109172D03*
X1141141Y106495D03*
X1126548Y110784D03*
X1134142Y133298D03*
X1126142D03*
X1140875Y146012D03*
X1128289Y134579D03*
X1129277Y203393D03*
X1140346Y253198D03*
X1125864Y252371D03*
X1129553Y389153D03*
Y396240D03*
Y403326D03*
Y410413D03*
Y424586D03*
Y417499D03*
Y431673D03*
Y438760D03*
X1126931Y453564D03*
X1130355Y453483D03*
X1129553Y467539D03*
X1125178Y459792D03*
X1129553Y474626D03*
Y488799D03*
Y481712D03*
Y518760D03*
Y511673D03*
Y532933D03*
Y525846D03*
X1138098Y543925D03*
X1138673Y555000D03*
X1126633Y560500D03*
X1139615Y1350683D03*
Y1345691D03*
X1132331D03*
Y1350683D03*
X1127375D03*
Y1345691D03*
X1139615Y1357603D03*
Y1362595D03*
X1132331D03*
Y1357603D03*
X1127375D03*
Y1362595D03*
X1139615Y1374881D03*
Y1369889D03*
Y1381801D03*
X1132331Y1369889D03*
Y1381801D03*
Y1374881D03*
X1127375Y1369889D03*
Y1381801D03*
Y1374881D03*
X1139615Y1394087D03*
Y1399079D03*
Y1386793D03*
X1132331D03*
Y1394087D03*
Y1399079D03*
X1127375Y1386793D03*
Y1394087D03*
Y1399079D03*
X1139615Y1405999D03*
Y1410991D03*
X1132331Y1405999D03*
Y1410991D03*
X1127375Y1405999D03*
Y1410991D03*
X1129637Y1465913D03*
Y1461182D03*
Y1456451D03*
X1138298Y1465513D03*
Y1460782D03*
X1129637Y1476536D03*
Y1481267D03*
X1138298Y1476136D03*
Y1470244D03*
Y1480867D03*
X1129637Y1471805D03*
Y1496621D03*
X1138298Y1491490D03*
Y1485598D03*
Y1496221D03*
X1129637Y1491890D03*
Y1487159D03*
X1138298Y1500952D03*
Y1511576D03*
X1129637Y1507245D03*
Y1502514D03*
Y1511976D03*
X1138298Y1506845D03*
Y1516307D03*
X1129637Y1563544D03*
Y1558813D03*
X1138298Y1563144D03*
Y1572606D03*
X1129637Y1568275D03*
Y1578898D03*
Y1574167D03*
X1138298Y1567875D03*
Y1578498D03*
X1129637Y1583629D03*
Y1594253D03*
Y1589522D03*
X1138298Y1583229D03*
Y1593853D03*
Y1587960D03*
Y1598584D03*
Y1603315D03*
X1129637Y1609607D03*
Y1598984D03*
Y1604876D03*
X1138298Y1609207D03*
X1129637Y1614338D03*
X1138298Y1613938D03*
Y1618669D03*
X1132000Y1644980D03*
X1142134Y109172D03*
X1156885Y116496D03*
Y102323D03*
Y109410D03*
X1152185D03*
Y116497D03*
X1149685D03*
X1144885D03*
X1152185Y130670D03*
X1149685D03*
Y123584D03*
X1152185Y123583D03*
X1144885Y130670D03*
Y123584D03*
X1156885Y130670D03*
Y123583D03*
X1142781Y141228D03*
X1156885Y137756D03*
X1149685Y137757D03*
X1144885D03*
X1145669Y150847D03*
X1147637Y247292D03*
X1145761Y324148D03*
X1157251Y636842D03*
X1156023Y678462D03*
X1149345Y771517D03*
X1145910Y794217D03*
X1151277Y790996D03*
X1149627Y813323D03*
X1146985Y812642D03*
X1152510Y844642D03*
X1156811Y1350683D03*
Y1345691D03*
X1151855D03*
Y1350683D03*
X1144571D03*
Y1345691D03*
X1156811Y1357603D03*
Y1362595D03*
X1151855D03*
Y1357603D03*
X1144571D03*
Y1362595D03*
X1156811Y1374881D03*
Y1369889D03*
Y1381801D03*
X1151855Y1374881D03*
Y1369889D03*
Y1381801D03*
X1144571Y1369889D03*
Y1381801D03*
Y1374881D03*
X1156811Y1386793D03*
Y1399079D03*
Y1394087D03*
X1151855Y1386793D03*
Y1399079D03*
Y1394087D03*
X1144571D03*
Y1399079D03*
Y1386793D03*
X1156811Y1405999D03*
Y1410991D03*
X1151855Y1405999D03*
Y1410991D03*
X1144571Y1405999D03*
Y1410991D03*
X1146960Y1465913D03*
Y1461182D03*
X1155621Y1465513D03*
Y1460782D03*
X1146960Y1456451D03*
X1155621Y1480867D03*
X1146960Y1471805D03*
Y1476536D03*
Y1481267D03*
X1155621Y1476136D03*
Y1470244D03*
Y1491490D03*
Y1485598D03*
Y1496221D03*
X1146960Y1487159D03*
Y1491890D03*
Y1496621D03*
Y1507245D03*
Y1502514D03*
X1155621Y1506845D03*
Y1500952D03*
Y1511576D03*
X1146960Y1511976D03*
X1155621Y1516307D03*
X1146960Y1563544D03*
X1155621Y1563144D03*
X1146960Y1558813D03*
X1155621Y1572606D03*
X1146960Y1568275D03*
X1155621Y1567875D03*
X1146960Y1574167D03*
Y1578898D03*
X1155621Y1578498D03*
X1146960Y1594253D03*
X1155621Y1593853D03*
Y1587960D03*
X1146960Y1583629D03*
X1155621Y1583229D03*
X1146960Y1589522D03*
Y1609607D03*
Y1604876D03*
Y1598984D03*
X1155621Y1609207D03*
Y1598584D03*
Y1603315D03*
X1146960Y1614338D03*
X1155621Y1613938D03*
Y1618669D03*
X1152000Y1644980D03*
X1165347Y82984D03*
Y75184D03*
Y77784D03*
Y80384D03*
X1167756Y92734D03*
X1165347Y85584D03*
X1171586Y137756D03*
X1168902Y431029D03*
X1167931Y435029D03*
X1169173Y427017D03*
X1168851Y449873D03*
X1171255Y456287D03*
X1173278Y472579D03*
X1168478D03*
X1173278Y479666D03*
X1168478D03*
Y486752D03*
X1173278D03*
X1168478Y493839D03*
X1173278D03*
X1168478Y523800D03*
Y516713D03*
X1173278D03*
Y523800D03*
Y537973D03*
X1168478D03*
X1173278Y530886D03*
X1168478D03*
X1173278Y566752D03*
X1168478D03*
Y580926D03*
X1173278D03*
Y588013D03*
X1168478D03*
X1173278Y573839D03*
X1168478D03*
Y602186D03*
X1173278D03*
Y595099D03*
X1168478D03*
X1173278Y609272D03*
X1168478D03*
Y616359D03*
X1173278D03*
X1163157Y638125D03*
X1160756Y665140D03*
X1157985Y791142D03*
X1161291Y791662D03*
X1173697Y791911D03*
X1160516Y800900D03*
X1169051Y1345597D03*
Y1350683D03*
X1164095D03*
Y1345597D03*
X1169051Y1357603D03*
Y1362595D03*
X1164095Y1357603D03*
Y1362595D03*
X1169051Y1381801D03*
Y1374881D03*
Y1369889D03*
X1164095D03*
Y1381801D03*
Y1374881D03*
X1169051Y1393993D03*
Y1399079D03*
Y1386793D03*
X1164095Y1393993D03*
Y1399079D03*
Y1386793D03*
X1169051Y1410991D03*
Y1405999D03*
X1164095D03*
Y1410991D03*
X1164283Y1465913D03*
Y1456451D03*
Y1461182D03*
X1172944Y1465513D03*
Y1460782D03*
Y1470244D03*
Y1480867D03*
X1164283Y1471805D03*
Y1476536D03*
Y1481267D03*
X1172944Y1476136D03*
X1164283Y1487159D03*
Y1491890D03*
Y1496621D03*
X1172944Y1491490D03*
Y1485598D03*
Y1496221D03*
X1164283Y1507245D03*
Y1502514D03*
X1172944Y1506845D03*
Y1500952D03*
Y1511576D03*
X1164283Y1511976D03*
X1172944Y1516307D03*
X1164283Y1558813D03*
Y1563544D03*
X1172944Y1563144D03*
Y1567875D03*
X1164283Y1574167D03*
Y1578898D03*
X1172944Y1578498D03*
Y1572606D03*
X1164283Y1568275D03*
Y1583629D03*
X1172944Y1583229D03*
X1164283Y1589522D03*
Y1594253D03*
X1172944Y1593853D03*
Y1587960D03*
Y1598584D03*
Y1603315D03*
X1164283Y1609607D03*
Y1604876D03*
Y1598984D03*
X1172944Y1609207D03*
X1164283Y1614338D03*
X1172944Y1613938D03*
Y1618669D03*
X1172000Y1644980D03*
X1188278Y94017D03*
X1174861Y103037D03*
X1174995Y116496D03*
Y109410D03*
Y130670D03*
Y123583D03*
X1187793Y226141D03*
X1190593D03*
X1179676Y293796D03*
X1187690Y288190D03*
X1185190Y285690D03*
X1187690D03*
X1185190Y288190D03*
X1177176Y293796D03*
X1182911Y336516D03*
X1177036Y334148D03*
X1188598Y390500D03*
X1179184Y410394D03*
Y403307D03*
X1180578Y458406D03*
Y451319D03*
X1180402Y462264D03*
X1175778Y465492D03*
X1180578D03*
X1175778Y472579D03*
X1180578D03*
X1175778Y479666D03*
X1180578Y479665D03*
Y486752D03*
X1175778D03*
X1180578Y493839D03*
X1175778Y509626D03*
X1180578Y523799D03*
Y516713D03*
Y509626D03*
X1175778Y516713D03*
Y523800D03*
X1180578Y537973D03*
X1175778Y530886D03*
X1180578D03*
Y559665D03*
Y566752D03*
X1175778D03*
Y559665D03*
Y580926D03*
X1180578D03*
Y588012D03*
X1175778D03*
X1180578Y573839D03*
X1175778D03*
Y602185D03*
X1180578D03*
X1175778Y595099D03*
X1180578D03*
X1175778Y609272D03*
X1180578Y616358D03*
Y609272D03*
X1177745Y771744D03*
X1177566Y778539D03*
X1190062Y844378D03*
X1187703Y849734D03*
X1186742Y855466D03*
X1183431Y868340D03*
X1177775Y894053D03*
X1178480Y915220D03*
X1178000Y936500D03*
X1187200Y963400D03*
X1181291Y1350683D03*
Y1345691D03*
X1176335D03*
Y1350683D03*
X1181291Y1362595D03*
Y1357603D03*
X1176335Y1362595D03*
Y1357603D03*
X1181291Y1369889D03*
Y1381801D03*
Y1374881D03*
X1176335Y1369889D03*
Y1381801D03*
Y1374881D03*
X1181291Y1386793D03*
Y1399079D03*
Y1394087D03*
X1176335Y1386793D03*
Y1399079D03*
Y1394087D03*
X1181291Y1405999D03*
Y1410991D03*
X1176335Y1405999D03*
Y1410991D03*
X1181605Y1465913D03*
Y1456451D03*
Y1461182D03*
Y1471805D03*
Y1476536D03*
Y1481267D03*
Y1487159D03*
Y1491890D03*
Y1496621D03*
Y1507245D03*
Y1502514D03*
Y1511976D03*
Y1558813D03*
Y1563544D03*
Y1568275D03*
Y1574167D03*
Y1578898D03*
Y1583629D03*
Y1589522D03*
Y1594253D03*
Y1598984D03*
Y1609607D03*
Y1604876D03*
Y1614338D03*
X1205355Y84140D03*
Y76140D03*
Y80140D03*
X1196278Y94017D03*
X1200287D03*
X1192278D03*
X1202808Y117557D03*
X1197398Y110445D03*
Y115401D03*
X1192406Y110445D03*
Y115401D03*
X1197398Y129574D03*
Y124618D03*
X1192406D03*
Y129574D03*
X1202808Y122513D03*
Y131731D03*
X1205899Y146461D03*
X1202808Y136687D03*
X1204801Y152367D03*
X1190319Y151540D03*
X1200469Y184619D03*
X1193969Y191941D03*
X1193836Y188727D03*
X1202449Y206760D03*
X1203663Y256535D03*
X1195663D03*
X1204693Y279208D03*
X1194716Y290755D03*
X1202716D03*
X1190490Y285690D03*
Y288190D03*
X1198716Y290755D03*
X1198248Y381500D03*
X1198689Y465492D03*
X1198655Y460250D03*
X1196420Y470136D03*
X1198689Y472579D03*
Y486752D03*
Y479665D03*
Y493839D03*
Y509626D03*
Y516713D03*
X1195149Y537973D03*
X1197629Y525483D03*
X1197550Y532756D03*
X1198689Y559665D03*
Y566752D03*
X1198539Y579978D03*
X1198689Y573839D03*
X1198753Y608117D03*
X1198997Y790610D03*
X1198845Y998504D03*
X1204919Y1021860D03*
X1202268Y1013551D03*
X1190267Y1465513D03*
Y1460782D03*
X1198928Y1465914D03*
Y1456452D03*
Y1461183D03*
Y1481268D03*
X1190267Y1476136D03*
Y1470244D03*
Y1480867D03*
X1198928Y1476537D03*
Y1471806D03*
X1190267Y1485598D03*
Y1496221D03*
X1198928Y1491891D03*
Y1487160D03*
Y1496622D03*
X1190267Y1491490D03*
Y1506845D03*
Y1500952D03*
Y1511576D03*
X1198928Y1507246D03*
Y1502515D03*
Y1511977D03*
X1190267Y1516307D03*
X1198928Y1558813D03*
X1190267Y1563144D03*
X1198928Y1563544D03*
X1190267Y1567875D03*
X1198928Y1568275D03*
X1190267Y1578498D03*
Y1572606D03*
X1198928Y1578898D03*
Y1574167D03*
X1190267Y1583229D03*
X1198928Y1583629D03*
X1190267Y1593853D03*
Y1587960D03*
X1198928Y1594253D03*
Y1589522D03*
X1190267Y1609207D03*
Y1598584D03*
Y1603315D03*
X1198928Y1609607D03*
Y1598984D03*
Y1604876D03*
X1190267Y1613938D03*
Y1618669D03*
X1198928Y1614338D03*
X1192000Y1644980D03*
X1218730Y117261D03*
X1207800Y117557D03*
Y122513D03*
Y131731D03*
Y136687D03*
X1206501Y180572D03*
X1211184Y180527D03*
X1214907Y192421D03*
X1206501Y185165D03*
X1211139Y185121D03*
X1208797Y281307D03*
X1220985Y342319D03*
X1212680Y445908D03*
X1216630Y445787D03*
X1212000Y1644980D03*
X1222933Y55513D03*
X1228097Y60922D03*
X1225041Y97080D03*
X1228910Y110784D03*
X1226261Y113394D03*
X1229195Y130898D03*
X1236504Y133298D03*
X1230651Y134579D03*
X1226437Y180665D03*
Y172665D03*
X1226469Y200864D03*
Y212864D03*
Y216864D03*
Y221864D03*
X1228226Y252371D03*
X1238055Y303839D03*
X1230077Y336324D03*
X1234656Y353506D03*
X1223431Y393924D03*
Y389912D03*
Y385912D03*
Y409924D03*
Y405924D03*
Y401924D03*
X1229548Y1350683D03*
Y1345691D03*
X1234504D03*
Y1350683D03*
X1229548Y1362595D03*
Y1357603D03*
X1234504D03*
Y1362595D03*
X1229548Y1369889D03*
Y1374881D03*
Y1381801D03*
X1234504Y1369889D03*
Y1374881D03*
Y1381801D03*
X1229548Y1386793D03*
X1234504D03*
X1232000Y1644980D03*
X1243503Y106495D03*
X1244496Y109172D03*
X1241496D03*
X1247247Y116497D03*
X1254547Y109410D03*
Y116497D03*
X1252047D03*
X1247247Y123584D03*
Y130670D03*
X1252047Y123584D03*
X1254547Y123583D03*
Y130670D03*
X1252047D03*
X1243237Y146012D03*
X1245143Y141228D03*
X1247247Y137757D03*
X1252047D03*
X1250307Y140296D03*
X1248031Y150847D03*
X1249999Y247292D03*
X1242708Y253198D03*
X1248064Y567813D03*
Y572769D03*
Y581987D03*
Y586943D03*
Y601116D03*
Y596160D03*
Y615289D03*
Y610333D03*
X1246800Y1001600D03*
X1249200Y1014000D03*
X1248721Y1025864D03*
X1251802Y1186071D03*
X1254028Y1350683D03*
Y1345691D03*
X1241788D03*
Y1350683D03*
X1246744Y1345691D03*
Y1350683D03*
X1254028Y1357603D03*
Y1362595D03*
X1241788D03*
Y1357603D03*
X1246744Y1362595D03*
Y1357603D03*
X1254028Y1381801D03*
Y1374881D03*
Y1369889D03*
X1241788Y1374881D03*
Y1369795D03*
Y1381801D03*
X1246744Y1374881D03*
Y1369795D03*
Y1381801D03*
X1254028Y1386793D03*
Y1399079D03*
Y1394087D03*
X1241788Y1399079D03*
Y1393993D03*
Y1386793D03*
X1246744Y1393993D03*
Y1399079D03*
Y1386793D03*
X1254028Y1410991D03*
Y1405999D03*
X1241788Y1410991D03*
Y1405999D03*
X1246744Y1410991D03*
Y1405999D03*
X1245900Y1528000D03*
X1267709Y82984D03*
Y75184D03*
Y77784D03*
Y80384D03*
X1270263Y92849D03*
X1267709Y85584D03*
X1259247Y116496D03*
Y102323D03*
Y109410D03*
Y130670D03*
Y123583D03*
Y137756D03*
X1258925Y324075D03*
X1270951Y491870D03*
X1270515Y908277D03*
X1269876Y1132319D03*
X1263873Y1148000D03*
X1266709Y1160168D03*
X1258736Y1188223D03*
X1268573Y1193019D03*
X1264573D03*
X1266268Y1345691D03*
Y1350683D03*
X1258984D03*
Y1345691D03*
X1266268Y1362595D03*
Y1357603D03*
X1258984Y1362595D03*
Y1357603D03*
X1266268Y1369889D03*
Y1374881D03*
Y1381801D03*
X1258984D03*
Y1369889D03*
Y1374881D03*
X1266268Y1399079D03*
Y1394087D03*
Y1386793D03*
X1258984Y1394087D03*
Y1386793D03*
Y1399079D03*
X1266268Y1410991D03*
Y1405999D03*
X1258984D03*
Y1410991D03*
X1263242Y1523458D03*
X1262985Y1519459D03*
X1260260Y1546500D03*
X1277223Y103037D03*
X1277357Y116496D03*
Y109410D03*
Y130670D03*
Y123583D03*
X1273555Y137756D03*
X1279538Y293796D03*
X1282038D03*
X1283494Y339495D03*
X1287437Y370010D03*
X1280616Y472189D03*
X1273451Y491870D03*
X1279539Y772576D03*
Y776576D03*
X1274417Y861964D03*
X1282317Y880193D03*
X1285493Y892175D03*
X1277039Y916484D03*
X1284021Y940008D03*
X1273865Y1132497D03*
X1282830Y1146937D03*
X1272120Y1159455D03*
X1280306Y1162817D03*
X1276573Y1193019D03*
X1280573D03*
X1272573D03*
X1277108Y1211664D03*
X1279402Y1213958D03*
X1275032Y1209589D03*
X1284198Y1218754D03*
X1283464Y1345691D03*
Y1350683D03*
X1278508Y1345691D03*
Y1350683D03*
X1271224Y1345691D03*
Y1350683D03*
X1283464Y1362595D03*
Y1357603D03*
X1278508D03*
Y1362595D03*
X1271224D03*
Y1357603D03*
X1283464Y1381801D03*
Y1369889D03*
Y1374881D03*
X1278508Y1381801D03*
Y1369889D03*
Y1374881D03*
X1271224Y1369889D03*
Y1374881D03*
Y1381801D03*
X1283464Y1386793D03*
Y1399079D03*
Y1394087D03*
X1278508Y1386793D03*
Y1399079D03*
Y1394087D03*
X1271224D03*
Y1399079D03*
Y1386793D03*
X1283464Y1410991D03*
Y1405999D03*
X1278508Y1410991D03*
Y1405999D03*
X1271224Y1410991D03*
Y1405999D03*
X1291756Y-25143D03*
X1288503Y-25157D03*
X1291741Y-27658D03*
X1288488Y-27672D03*
X1294781Y-26463D03*
X1302649Y94017D03*
X1298640D03*
X1290640D03*
X1294640D03*
X1299760Y110445D03*
Y115401D03*
X1294768Y110445D03*
Y115401D03*
Y129574D03*
X1299760D03*
Y124618D03*
X1294768D03*
X1296331Y191941D03*
X1302831Y184619D03*
X1296198Y188727D03*
X1292955Y226141D03*
X1290155D03*
X1298025Y256535D03*
X1290052Y288190D03*
X1292852D03*
Y285690D03*
X1305078Y290755D03*
X1297078D03*
X1301078D03*
X1287552Y288190D03*
X1290052Y285690D03*
X1287552D03*
X1294425Y321425D03*
X1299959Y351454D03*
X1296783Y511956D03*
X1303520Y748403D03*
X1300516Y832047D03*
X1300504Y835985D03*
X1300204Y859088D03*
X1300097Y851193D03*
X1300091Y854824D03*
X1291955Y901295D03*
X1289547Y928047D03*
X1298090Y940852D03*
X1295453Y940953D03*
X1302988Y1345691D03*
Y1350683D03*
X1290748D03*
Y1345691D03*
X1295704Y1350683D03*
Y1345691D03*
X1302988Y1362595D03*
Y1357603D03*
X1290748Y1362595D03*
Y1357603D03*
X1295704Y1362595D03*
Y1357603D03*
X1302988Y1374881D03*
Y1381801D03*
Y1369889D03*
X1290748D03*
Y1381801D03*
Y1374881D03*
X1295704Y1381801D03*
Y1374881D03*
Y1369889D03*
X1302988Y1386793D03*
Y1399079D03*
Y1394087D03*
X1290748Y1399079D03*
Y1394087D03*
Y1386793D03*
X1295704Y1394087D03*
Y1399079D03*
Y1386793D03*
X1302988Y1410991D03*
Y1405999D03*
X1290748Y1410991D03*
Y1405999D03*
X1295704Y1410991D03*
Y1405999D03*
X1302866Y1461182D03*
Y1456451D03*
Y1465913D03*
Y1476536D03*
Y1471805D03*
Y1481267D03*
Y1491890D03*
Y1487159D03*
Y1496621D03*
Y1507245D03*
Y1502514D03*
Y1511976D03*
Y1558813D03*
Y1563544D03*
Y1578898D03*
Y1574167D03*
Y1568275D03*
Y1594253D03*
Y1589522D03*
Y1583629D03*
Y1609607D03*
Y1598984D03*
Y1604876D03*
Y1614338D03*
X1292000Y1644980D03*
X1307717Y84140D03*
Y76140D03*
Y80140D03*
X1310162Y117557D03*
X1305170D03*
X1310162Y122513D03*
Y131731D03*
X1305170Y122513D03*
Y131731D03*
X1310162Y136687D03*
X1305170D03*
X1313546Y180527D03*
X1308863Y180572D03*
Y185165D03*
X1317269Y192421D03*
X1313501Y185121D03*
X1304811Y206760D03*
X1306025Y256535D03*
X1307055Y279208D03*
X1311159Y281307D03*
X1314569Y318013D03*
X1312069D03*
X1317584Y313058D03*
X1316017Y349889D03*
X1308410Y370899D03*
X1313691Y402642D03*
X1316191D03*
X1309117Y398949D03*
X1306617Y401949D03*
X1308066Y413611D03*
X1310866D03*
X1313366D03*
X1315866D03*
X1315806Y423944D03*
X1313306D03*
X1310806D03*
X1308006D03*
X1307919Y478382D03*
X1307825Y482382D03*
X1305134Y812065D03*
X1313756Y829871D03*
X1308857Y836076D03*
X1316906Y842470D03*
Y867665D03*
Y883413D03*
Y892862D03*
X1316893Y925603D03*
X1318375Y943951D03*
X1303907Y960093D03*
X1307580Y990314D03*
X1304664Y1023462D03*
X1309937Y1037038D03*
X1319326Y1040723D03*
X1317437Y1152684D03*
X1307167Y1245696D03*
X1308276Y1276446D03*
X1315228Y1345691D03*
Y1350683D03*
X1307944D03*
Y1345691D03*
X1315228Y1362595D03*
Y1357603D03*
X1307944D03*
Y1362595D03*
X1315228Y1381801D03*
Y1369889D03*
Y1374881D03*
X1307944D03*
Y1381801D03*
Y1369889D03*
X1315228Y1399079D03*
Y1394087D03*
Y1386793D03*
X1307944D03*
Y1399079D03*
Y1394087D03*
X1315228Y1410991D03*
Y1405999D03*
X1307944Y1410991D03*
Y1405999D03*
X1311527Y1465513D03*
Y1460782D03*
Y1480867D03*
Y1476136D03*
Y1470244D03*
Y1491490D03*
Y1485598D03*
Y1496221D03*
Y1506845D03*
Y1500952D03*
Y1511576D03*
Y1516307D03*
Y1563144D03*
Y1567875D03*
Y1578498D03*
Y1572606D03*
Y1583229D03*
Y1593853D03*
Y1587960D03*
Y1609207D03*
Y1598584D03*
Y1603315D03*
Y1613938D03*
Y1618669D03*
X1312000Y1644980D03*
X1331756Y-64193D03*
X1328503Y-64207D03*
X1331741Y-66708D03*
X1328488Y-66722D03*
X1334781Y-65513D03*
X1321092Y117261D03*
X1328799Y172665D03*
Y180665D03*
X1328831Y212864D03*
Y200864D03*
Y221864D03*
Y216864D03*
X1330414Y310058D03*
X1325458D03*
X1322540Y313058D03*
X1333332D03*
X1331085Y334347D03*
X1323816D03*
Y341615D03*
X1331085Y348868D03*
X1323816D03*
X1332927Y468607D03*
X1326912Y493153D03*
X1325630Y513238D03*
X1335000Y590500D03*
Y586500D03*
Y633000D03*
Y637000D03*
Y677500D03*
Y681500D03*
Y724500D03*
Y728500D03*
X1324217Y780595D03*
X1332654Y836170D03*
X1323205Y861367D03*
X1335803Y851918D03*
Y877114D03*
X1326355Y886562D03*
X1328457Y959986D03*
X1321104Y964398D03*
X1323554Y967623D03*
X1331890Y1051919D03*
X1331359Y1098898D03*
X1334161Y1098518D03*
X1333905Y1123101D03*
X1331405D03*
X1323405D03*
X1320279Y1131935D03*
Y1134435D03*
Y1136935D03*
Y1139435D03*
X1334305Y1129301D03*
X1331805D03*
X1329305D03*
X1326805D03*
X1324305D03*
X1321805D03*
X1334305Y1125801D03*
X1331805D03*
X1323405D03*
X1320279Y1141935D03*
Y1146935D03*
Y1144435D03*
X1326269Y1152713D03*
Y1155213D03*
X1320493Y1204405D03*
X1334793Y1204617D03*
X1320493Y1206905D03*
Y1211905D03*
Y1209405D03*
X1334793Y1207117D03*
Y1209617D03*
Y1212117D03*
X1330070Y1297498D03*
X1335470D03*
X1332424Y1345691D03*
Y1350683D03*
X1327468D03*
Y1345691D03*
X1320184Y1350683D03*
Y1345691D03*
X1332424Y1362595D03*
Y1357603D03*
X1327468D03*
Y1362595D03*
X1320184D03*
Y1357603D03*
X1332424Y1381801D03*
Y1369889D03*
Y1374881D03*
X1327468Y1381801D03*
Y1369889D03*
Y1374881D03*
X1320184Y1381801D03*
Y1374881D03*
Y1369889D03*
X1332424Y1386793D03*
Y1394087D03*
Y1399079D03*
X1327468Y1386793D03*
Y1394087D03*
Y1399079D03*
X1320184D03*
Y1394087D03*
Y1386793D03*
X1332424Y1410991D03*
Y1405999D03*
X1327468Y1410991D03*
Y1405999D03*
X1320184Y1410991D03*
Y1405999D03*
X1328850Y1465513D03*
Y1460782D03*
X1320189Y1465913D03*
Y1456451D03*
Y1461182D03*
X1328850Y1476136D03*
Y1470244D03*
X1320189Y1481267D03*
X1328850Y1480867D03*
X1320189Y1471805D03*
Y1476536D03*
X1328850Y1491490D03*
Y1485598D03*
X1320189Y1496621D03*
X1328850Y1496221D03*
X1320189Y1487159D03*
Y1491890D03*
Y1502514D03*
X1328850Y1506845D03*
Y1500952D03*
Y1511576D03*
X1320189Y1511976D03*
Y1507245D03*
X1328850Y1516307D03*
X1320189Y1558813D03*
Y1563544D03*
X1328850Y1563144D03*
Y1567875D03*
X1320189Y1574167D03*
Y1578898D03*
X1328850Y1578498D03*
Y1572606D03*
X1320189Y1568275D03*
X1328850Y1583229D03*
X1320189Y1589522D03*
Y1594253D03*
X1328850Y1593853D03*
Y1587960D03*
X1320189Y1583629D03*
X1328850Y1603315D03*
X1320189Y1609607D03*
Y1604876D03*
Y1598984D03*
X1328850Y1609207D03*
Y1598584D03*
Y1613938D03*
Y1618669D03*
X1320189Y1614338D03*
X1332000Y1644980D03*
X1340320Y151540D03*
X1338288Y313058D03*
X1338378Y334347D03*
X1338275Y341603D03*
X1338378Y348830D03*
X1345451Y699032D03*
X1347136Y780040D03*
X1351550Y839320D03*
Y855068D03*
X1345252D03*
X1342103D03*
Y861367D03*
X1338953D03*
Y858218D03*
X1338952Y855067D03*
X1338953Y870814D03*
X1342103Y867665D03*
X1338953D03*
X1351550Y873964D03*
X1345252D03*
X1342103D03*
X1338952Y873965D03*
X1345252Y892862D03*
X1341820Y947407D03*
X1347380Y1057998D03*
Y1055498D03*
X1344880D03*
Y1057998D03*
X1347380Y1060498D03*
Y1062998D03*
X1344880D03*
Y1060498D03*
X1339349Y1098767D03*
X1339305Y1129301D03*
X1336805D03*
X1339305Y1125801D03*
X1336805D03*
X1343505Y1136935D03*
Y1134435D03*
Y1139435D03*
Y1131935D03*
X1349907D03*
Y1134435D03*
Y1136935D03*
Y1139435D03*
X1352407Y1131935D03*
Y1134435D03*
Y1136935D03*
Y1139435D03*
X1343505Y1146935D03*
Y1144435D03*
Y1141935D03*
X1349907D03*
Y1146935D03*
Y1144435D03*
X1352407Y1141935D03*
Y1146935D03*
Y1144435D03*
X1336669Y1152713D03*
Y1155213D03*
X1351405Y1154902D03*
Y1152402D03*
X1347423Y1204405D03*
X1337108Y1200821D03*
Y1198321D03*
X1347423Y1209405D03*
Y1211905D03*
Y1206905D03*
X1340870Y1297498D03*
X1346270D03*
X1351670D03*
X1351948Y1350683D03*
Y1345691D03*
X1339708Y1345597D03*
Y1350683D03*
X1344664Y1345597D03*
Y1350683D03*
X1351948Y1357603D03*
Y1362595D03*
X1339708D03*
Y1357603D03*
X1344664Y1362595D03*
Y1357603D03*
X1351948Y1374881D03*
Y1381801D03*
Y1369889D03*
X1339708Y1374881D03*
Y1381801D03*
Y1369889D03*
X1344664D03*
Y1374881D03*
Y1381801D03*
X1351948Y1386793D03*
Y1394087D03*
Y1399079D03*
X1339708D03*
Y1393993D03*
Y1386793D03*
X1344664Y1393993D03*
Y1399079D03*
Y1386793D03*
X1351948Y1410991D03*
Y1405999D03*
X1339708Y1410991D03*
Y1405999D03*
X1344664Y1410991D03*
Y1405999D03*
X1337512Y1461182D03*
X1346173Y1465513D03*
Y1460782D03*
X1337512Y1465913D03*
Y1456451D03*
X1346173Y1476136D03*
Y1470244D03*
X1337512Y1481267D03*
X1346173Y1480867D03*
X1337512Y1471805D03*
Y1476536D03*
X1346173Y1485598D03*
Y1491490D03*
X1337512Y1487159D03*
Y1491890D03*
Y1496621D03*
X1346173Y1496221D03*
X1337512Y1507245D03*
Y1502514D03*
X1346173Y1506845D03*
Y1500952D03*
Y1511576D03*
X1337512Y1511976D03*
X1346173Y1516307D03*
X1337512Y1558813D03*
Y1563544D03*
X1346173Y1563144D03*
X1337512Y1574167D03*
Y1578898D03*
X1346173Y1578498D03*
Y1572606D03*
X1337512Y1568275D03*
X1346173Y1567875D03*
X1337512Y1583629D03*
X1346173Y1583229D03*
X1337512Y1589522D03*
Y1594253D03*
X1346173Y1593853D03*
Y1587960D03*
X1337512Y1609607D03*
Y1604876D03*
Y1598984D03*
X1346173Y1609207D03*
Y1598584D03*
Y1603315D03*
X1337512Y1614338D03*
X1346173Y1613938D03*
Y1618669D03*
X1352000Y1644980D03*
X1355900Y146461D03*
X1354802Y152367D03*
X1355255Y561032D03*
Y607532D03*
Y652032D03*
X1364148Y836170D03*
X1354699Y855068D03*
X1357849Y861367D03*
X1354699D03*
X1357849Y858218D03*
X1357850Y855067D03*
X1360999Y851918D03*
Y877114D03*
X1357850Y873965D03*
X1354699Y873964D03*
X1357849Y870814D03*
Y867665D03*
X1354699D03*
X1363173Y994483D03*
X1363905Y1000855D03*
X1366493Y1000828D03*
X1367884Y1018825D03*
X1357265Y1022766D03*
X1364237Y1043140D03*
X1357265Y1030266D03*
X1363941Y1047047D03*
X1366289Y1098518D03*
X1361037Y1098428D03*
X1355533Y1123101D03*
X1363533D03*
X1366033D03*
X1366433Y1129301D03*
X1355533Y1125801D03*
X1363933D03*
X1366433D03*
X1353933Y1129301D03*
X1356433D03*
X1358933D03*
X1361433D03*
X1363933D03*
X1357397Y1155213D03*
Y1152713D03*
X1366797D03*
Y1155213D03*
X1361723Y1204617D03*
X1364038Y1198321D03*
Y1200821D03*
X1361723Y1212117D03*
Y1209617D03*
Y1207117D03*
X1357070Y1297498D03*
X1356904Y1345691D03*
Y1350683D03*
Y1357603D03*
Y1362595D03*
Y1381801D03*
Y1369889D03*
Y1374881D03*
Y1386793D03*
Y1394087D03*
Y1399079D03*
Y1410991D03*
Y1405999D03*
X1354834Y1465913D03*
Y1456451D03*
Y1461182D03*
X1363496Y1465513D03*
Y1460782D03*
X1354834Y1481267D03*
X1363496Y1476136D03*
Y1470244D03*
Y1480867D03*
X1354834Y1471805D03*
Y1476536D03*
Y1487159D03*
Y1496621D03*
X1363496Y1485598D03*
Y1491490D03*
Y1496221D03*
X1354834Y1491890D03*
Y1502514D03*
Y1511976D03*
X1363496Y1511576D03*
Y1506845D03*
Y1500952D03*
X1354834Y1507245D03*
X1363496Y1516307D03*
X1354834Y1558813D03*
Y1563544D03*
X1363496Y1563144D03*
Y1572606D03*
X1354834Y1568275D03*
Y1574167D03*
Y1578898D03*
X1363496Y1567875D03*
Y1578498D03*
X1354834Y1583629D03*
Y1589522D03*
Y1594253D03*
X1363496Y1583229D03*
Y1593853D03*
Y1587960D03*
X1354834Y1609607D03*
Y1604876D03*
Y1598984D03*
X1363496Y1609207D03*
Y1598584D03*
Y1603315D03*
X1354834Y1614338D03*
X1363496Y1613938D03*
Y1618669D03*
X1376262Y113394D03*
X1378911Y110784D03*
X1378505Y133298D03*
X1380652Y134579D03*
X1378227Y252371D03*
X1383556Y558338D03*
X1383184Y587653D03*
X1383425Y593575D03*
X1383556Y604838D03*
X1381118Y634033D03*
X1383425Y640075D03*
X1381244Y673623D03*
X1383425Y684140D03*
X1381932Y722547D03*
X1383425Y731575D03*
X1383046Y829871D03*
X1379896Y842470D03*
Y858218D03*
X1370447Y867665D03*
Y886562D03*
X1371379Y986717D03*
X1370384Y1004680D03*
X1376601Y1030218D03*
X1374451Y1090568D03*
Y1093068D03*
X1371477Y1098767D03*
X1375633Y1136935D03*
Y1134435D03*
Y1139435D03*
Y1131935D03*
X1383366D03*
Y1134435D03*
Y1136935D03*
Y1139435D03*
X1368933Y1125801D03*
X1371433D03*
X1368933Y1129301D03*
X1371433D03*
X1383024Y1152684D03*
X1376861D03*
X1375633Y1146935D03*
Y1144435D03*
Y1141935D03*
X1383366D03*
Y1146935D03*
Y1144435D03*
X1377390Y1244055D03*
Y1250760D03*
Y1254164D03*
X1372300Y1422900D03*
X1372157Y1461183D03*
Y1456452D03*
Y1465914D03*
Y1471806D03*
Y1476537D03*
Y1481268D03*
Y1487160D03*
Y1491891D03*
Y1496622D03*
Y1502515D03*
Y1507246D03*
Y1511977D03*
Y1558813D03*
Y1563544D03*
Y1568275D03*
Y1574167D03*
Y1578898D03*
Y1583629D03*
Y1589522D03*
Y1594253D03*
Y1604876D03*
Y1598984D03*
Y1609607D03*
Y1614338D03*
X1372000Y1644980D03*
X1391497Y109172D03*
X1394497D03*
X1393504Y106495D03*
X1397248Y116497D03*
X1386505Y133298D03*
X1397248Y130670D03*
Y123584D03*
X1393238Y146012D03*
X1395144Y141228D03*
X1397248Y137757D03*
X1398032Y150847D03*
X1400000Y247292D03*
X1392709Y253198D03*
X1391086Y577192D03*
X1400912Y581222D03*
Y591215D03*
X1391587Y627817D03*
X1388414Y675000D03*
X1388241Y722000D03*
X1396916Y862829D03*
X1395561Y876204D03*
X1396163Y868597D03*
X1398247Y926261D03*
X1390322Y1057998D03*
Y1055498D03*
X1392822D03*
Y1057998D03*
X1390322Y1060498D03*
Y1062998D03*
X1392822D03*
Y1060498D03*
X1399748Y1098518D03*
X1394496Y1098428D03*
X1388992Y1123101D03*
X1396992D03*
X1399492D03*
X1385866Y1131935D03*
Y1134435D03*
Y1136935D03*
Y1139435D03*
X1388992Y1125801D03*
X1397392D03*
X1399892D03*
X1387392Y1129301D03*
X1389892D03*
X1392392D03*
X1394892D03*
X1397392D03*
X1399892D03*
X1391856Y1155213D03*
Y1152713D03*
X1385866Y1141935D03*
Y1146935D03*
Y1144435D03*
X1393695Y1204405D03*
Y1206905D03*
Y1211905D03*
Y1209405D03*
X1385992Y1285466D03*
X1390492D03*
X1392000Y1644980D03*
X1409248Y109410D03*
Y102323D03*
X1404548Y116497D03*
X1402048D03*
X1404548Y109410D03*
X1409248Y116496D03*
X1402048Y130670D03*
Y123584D03*
X1404548Y123583D03*
X1409248Y130670D03*
Y123583D03*
X1404548Y130670D03*
X1409248Y137756D03*
X1402048Y137757D03*
X1408666Y324733D03*
X1411950Y448466D03*
X1408103Y555194D03*
X1410903D03*
X1408103Y563194D03*
X1410903D03*
X1408103Y571194D03*
X1410903D03*
X1406512Y581222D03*
X1403712D03*
Y591215D03*
X1406512D03*
X1405514Y611091D03*
X1405000Y656000D03*
Y699000D03*
X1404689Y910897D03*
X1413575Y915186D03*
X1413322Y958908D03*
X1404317Y989436D03*
X1411038Y985379D03*
X1404936Y1098767D03*
X1415494Y1139435D03*
Y1136935D03*
Y1134435D03*
Y1131935D03*
X1409092Y1136935D03*
Y1134435D03*
Y1139435D03*
Y1131935D03*
X1402392Y1125801D03*
X1404892D03*
X1402392Y1129301D03*
X1404892D03*
X1409092Y1141935D03*
X1416736Y1152713D03*
Y1155213D03*
X1402256D03*
Y1152713D03*
X1415494Y1144435D03*
Y1146935D03*
Y1141935D03*
X1409092Y1146935D03*
Y1144435D03*
X1407995Y1204617D03*
X1410310Y1200821D03*
Y1198321D03*
X1407995Y1207117D03*
Y1209617D03*
Y1212117D03*
X1415903Y1282590D03*
X1404019Y1285290D03*
X1414346Y1303020D03*
X1412000Y1644980D03*
X1417710Y82984D03*
Y75184D03*
Y77784D03*
Y80384D03*
X1420264Y92849D03*
X1417710Y85584D03*
X1427224Y103037D03*
X1427358Y116496D03*
Y109410D03*
Y130670D03*
Y123583D03*
X1423515Y137756D03*
X1429539Y293796D03*
X1432039D03*
X1431019Y434508D03*
X1427019D03*
X1424196Y446352D03*
X1428782Y445874D03*
X1417856Y455466D03*
X1433310Y504699D03*
X1430810D03*
X1433012Y516979D03*
X1430512D03*
X1427233Y628183D03*
X1424389Y627948D03*
X1426000Y709000D03*
Y713000D03*
Y757000D03*
Y753000D03*
X1422813Y910065D03*
X1424126Y900295D03*
X1427553Y939200D03*
X1427473Y965621D03*
X1420740Y1004766D03*
Y1000766D03*
Y1016266D03*
Y1030766D03*
X1420107Y1052514D03*
X1431876Y1098518D03*
X1426624Y1098428D03*
X1421120Y1123101D03*
X1429120D03*
X1431620D03*
X1422020Y1129301D03*
X1424520D03*
X1427020D03*
X1429520D03*
X1432020D03*
X1417994Y1139435D03*
Y1136935D03*
Y1134435D03*
Y1131935D03*
X1421120Y1125801D03*
X1429520D03*
X1432020D03*
X1419520Y1129301D03*
X1432384Y1155213D03*
Y1152713D03*
X1422984D03*
Y1155213D03*
X1417994Y1144435D03*
Y1146935D03*
Y1141935D03*
X1420625Y1204405D03*
Y1206905D03*
Y1209405D03*
X1425652Y1297411D03*
X1433386Y1343309D03*
X1428840Y1407740D03*
X1423065Y1508327D03*
X1432499Y1512175D03*
X1424245Y1543338D03*
X1425558Y1537432D03*
X1425260Y1558072D03*
X1433558Y1555366D03*
X1423701Y1563978D03*
X1432000Y1644980D03*
X1444641Y94017D03*
X1448641D03*
X1440641D03*
X1449761Y115401D03*
Y110445D03*
X1444769D03*
Y115401D03*
X1449761Y124618D03*
X1444769D03*
Y129574D03*
X1449761D03*
X1442682Y151540D03*
X1446332Y191941D03*
X1446199Y188727D03*
X1442956Y226141D03*
X1440156D03*
X1448026Y256535D03*
X1440053Y285690D03*
X1437553D03*
X1440053Y288190D03*
X1442853D03*
Y285690D03*
X1447079Y290755D03*
X1437553Y288190D03*
X1437758Y362584D03*
X1435019Y434508D03*
X1437757Y447201D03*
X1437879Y444269D03*
X1435810Y504699D03*
X1447036Y519518D03*
X1435512Y516979D03*
X1444536Y519518D03*
X1439536D03*
X1442036D03*
X1435241Y593796D03*
X1440930Y636005D03*
Y633205D03*
Y638805D03*
X1437784Y683532D03*
X1436567Y727532D03*
X1443000Y798500D03*
Y794500D03*
Y842500D03*
Y838500D03*
X1438188Y867633D03*
X1437703Y880067D03*
X1449072Y892581D03*
X1435288Y897500D03*
X1444453Y938806D03*
X1439449Y979009D03*
X1440610Y1021567D03*
X1435266Y1031522D03*
X1437064Y1098767D03*
X1441220Y1131935D03*
Y1139435D03*
Y1134435D03*
Y1136935D03*
X1434520Y1125801D03*
X1437020D03*
X1434520Y1129301D03*
X1437020D03*
X1441220Y1141935D03*
Y1144435D03*
Y1146935D03*
X1442448Y1152684D03*
X1434925Y1204617D03*
X1437240Y1200821D03*
Y1198321D03*
X1434925Y1207117D03*
Y1209617D03*
Y1212117D03*
X1436408Y1303462D03*
X1444438Y1308312D03*
X1439482D03*
X1441286Y1335776D03*
X1457718Y84140D03*
Y76140D03*
Y80140D03*
X1452650Y94017D03*
X1460163Y117557D03*
X1455171D03*
Y122513D03*
X1460163Y131731D03*
Y122513D03*
X1455171Y131731D03*
X1458262Y146461D03*
X1460163Y136687D03*
X1455171D03*
X1457164Y152367D03*
X1463547Y180527D03*
X1458864Y180572D03*
Y185165D03*
X1463502Y185121D03*
X1452832Y184619D03*
X1454812Y206760D03*
X1456026Y256535D03*
X1457056Y279208D03*
X1461160Y281307D03*
X1455079Y290755D03*
X1451079D03*
X1458982Y356861D03*
X1453000Y633450D03*
Y636250D03*
Y639050D03*
X1453032Y769032D03*
X1453775Y813032D03*
X1461241Y867475D03*
X1462694Y874859D03*
Y877859D03*
X1460472Y885985D03*
X1459420Y899226D03*
X1451005Y931848D03*
X1462819Y949996D03*
X1462000Y960378D03*
X1460655Y964253D03*
X1466076Y979746D03*
X1462388Y1006560D03*
X1455939Y1018368D03*
X1465503Y1030233D03*
X1460592Y1345691D03*
Y1350683D03*
X1465548Y1345691D03*
Y1350683D03*
X1460592Y1357603D03*
Y1362595D03*
X1465548Y1357603D03*
Y1362595D03*
X1460592Y1381801D03*
Y1374881D03*
Y1369889D03*
X1465548Y1381801D03*
Y1374881D03*
Y1369889D03*
X1460592Y1386793D03*
X1465548D03*
X1452000Y1644980D03*
X1480460Y60922D03*
X1475296Y55513D03*
X1471093Y117261D03*
X1478624Y113394D03*
X1481273Y110784D03*
X1481368Y130898D03*
X1478800Y180665D03*
Y172665D03*
X1467270Y192421D03*
X1478832Y200864D03*
Y212864D03*
Y216864D03*
Y221864D03*
X1480589Y252371D03*
X1473900Y433100D03*
X1478710Y685630D03*
X1473525Y710052D03*
X1474425Y716075D03*
X1479962Y727500D03*
X1471415Y748629D03*
X1474425Y760075D03*
X1473634Y864337D03*
X1481454Y911570D03*
X1474075Y920575D03*
X1474349Y949394D03*
X1468500Y974181D03*
X1479096Y997860D03*
X1471096D03*
X1475096D03*
X1467096D03*
X1471854Y1035088D03*
X1479624Y1035102D03*
X1468371Y1030701D03*
X1480193Y1102091D03*
X1474384D03*
X1480193Y1114691D03*
X1474384D03*
X1480193Y1127291D03*
X1474384D03*
X1480193Y1139891D03*
X1474384D03*
X1480193Y1152491D03*
X1474384D03*
X1480193Y1165091D03*
X1474384D03*
X1480193Y1177691D03*
X1474384D03*
X1480675Y1202103D03*
X1477788Y1350683D03*
Y1345691D03*
X1472832Y1350683D03*
Y1345691D03*
X1477788Y1357603D03*
Y1362595D03*
X1472832Y1357603D03*
Y1362595D03*
X1477788Y1381801D03*
Y1369795D03*
Y1374881D03*
X1472832Y1381801D03*
Y1369795D03*
Y1374881D03*
X1477788Y1386793D03*
Y1399079D03*
Y1393993D03*
X1472832Y1386793D03*
Y1393993D03*
Y1399079D03*
X1477788Y1405999D03*
Y1410991D03*
X1472832Y1405999D03*
Y1410991D03*
X1476094Y1465913D03*
Y1461182D03*
Y1456451D03*
Y1471805D03*
Y1481267D03*
Y1476536D03*
Y1491890D03*
Y1487159D03*
Y1496621D03*
Y1502514D03*
Y1511976D03*
Y1507245D03*
Y1563544D03*
Y1558813D03*
Y1568275D03*
Y1578898D03*
Y1574167D03*
Y1583629D03*
Y1594253D03*
Y1589522D03*
Y1609607D03*
Y1598984D03*
Y1604876D03*
Y1614338D03*
X1472000Y1644980D03*
X1493859Y109172D03*
X1496859D03*
X1495866Y106495D03*
X1488867Y133298D03*
X1495600Y146012D03*
X1497506Y141228D03*
X1483014Y134579D03*
X1495071Y253198D03*
X1486360Y358700D03*
Y354200D03*
X1496473Y769000D03*
X1491062Y793003D03*
X1491425Y801575D03*
X1496845Y813000D03*
X1491425Y845575D03*
X1489650Y836985D03*
X1489805Y866386D03*
X1497488Y873839D03*
X1491414Y875383D03*
X1494000Y884000D03*
X1498084Y894825D03*
X1492101Y894860D03*
X1496383Y898023D03*
X1496500Y919000D03*
X1496000Y922000D03*
X1487075Y920925D03*
X1485100Y943900D03*
X1496425Y943075D03*
X1496072Y950044D03*
X1482591Y961909D03*
X1486500Y947000D03*
X1485226Y973886D03*
X1492560Y974654D03*
X1495339Y1009354D03*
X1491839D03*
X1486030D03*
X1491096Y997860D03*
X1483096D03*
X1495096D03*
X1487096D03*
X1495339Y1021954D03*
X1491839D03*
X1486030D03*
X1483693Y1102091D03*
Y1114691D03*
Y1127291D03*
Y1139891D03*
Y1152491D03*
Y1165091D03*
Y1177691D03*
X1498197Y1209607D03*
X1492471Y1215195D03*
X1484055Y1223749D03*
X1497312Y1350683D03*
Y1345691D03*
X1485072D03*
Y1350683D03*
X1490028Y1345691D03*
Y1350683D03*
X1497312Y1357603D03*
Y1362595D03*
X1485072D03*
Y1357603D03*
X1490028D03*
Y1362595D03*
X1485072Y1369889D03*
Y1374881D03*
Y1381801D03*
X1490028Y1369889D03*
Y1374881D03*
Y1381801D03*
X1497312D03*
Y1374881D03*
Y1369889D03*
Y1386793D03*
Y1394087D03*
Y1399079D03*
X1485072Y1394087D03*
Y1399079D03*
Y1386793D03*
X1490028Y1399079D03*
Y1394087D03*
Y1386793D03*
X1497312Y1405999D03*
Y1410991D03*
X1485072Y1405999D03*
Y1410991D03*
X1490028Y1405999D03*
Y1410991D03*
X1484755Y1465513D03*
Y1460782D03*
X1493417Y1465913D03*
Y1456451D03*
Y1461182D03*
Y1471805D03*
Y1476536D03*
Y1481267D03*
X1484755Y1476136D03*
Y1470244D03*
Y1480867D03*
Y1496221D03*
X1493417Y1487159D03*
Y1491890D03*
Y1496621D03*
X1484755Y1491490D03*
Y1485598D03*
Y1506845D03*
Y1500952D03*
Y1511576D03*
X1493417Y1507245D03*
Y1502514D03*
Y1511976D03*
X1484755Y1516307D03*
Y1563144D03*
X1493417Y1558813D03*
Y1563544D03*
Y1578898D03*
X1484755Y1567875D03*
Y1578498D03*
Y1572606D03*
X1493417Y1568275D03*
Y1574167D03*
X1484755Y1583229D03*
Y1593853D03*
Y1587960D03*
X1493417Y1583629D03*
Y1589522D03*
Y1594253D03*
X1484755Y1609207D03*
Y1598584D03*
Y1603315D03*
X1493417Y1609607D03*
Y1604876D03*
Y1598984D03*
X1484755Y1613938D03*
Y1618669D03*
X1493417Y1614338D03*
X1492000Y1644980D03*
X1511610Y116496D03*
Y109410D03*
Y102323D03*
X1499610Y116497D03*
X1506910D03*
X1504410D03*
X1506910Y109410D03*
X1511610Y123583D03*
X1499610Y130670D03*
Y123584D03*
X1506910Y130670D03*
X1504410D03*
Y123584D03*
X1506910Y123583D03*
X1511610Y130670D03*
Y137756D03*
X1499610Y137757D03*
X1504410D03*
X1500394Y150847D03*
X1502362Y247292D03*
X1501807Y323766D03*
X1507864Y450750D03*
X1511963Y536382D03*
X1510280Y899732D03*
X1514354Y938811D03*
X1510500Y931500D03*
X1513955Y950396D03*
X1505888Y965964D03*
X1514000Y968739D03*
X1510740Y973740D03*
X1507096Y997860D03*
X1503096D03*
X1511096D03*
X1499096D03*
X1505130Y1105091D03*
Y1117691D03*
Y1130291D03*
Y1142891D03*
Y1155491D03*
Y1168091D03*
Y1180691D03*
X1509552Y1350683D03*
Y1345691D03*
X1514508Y1350683D03*
Y1345691D03*
X1502268Y1350683D03*
Y1345691D03*
X1509552Y1362595D03*
Y1357603D03*
X1514508D03*
Y1362595D03*
X1502268Y1357603D03*
Y1362595D03*
X1509552Y1374881D03*
Y1369889D03*
Y1381801D03*
X1514508Y1374881D03*
Y1369889D03*
Y1381801D03*
X1502268D03*
Y1374881D03*
Y1369889D03*
X1509552Y1394087D03*
Y1399079D03*
Y1386793D03*
X1514508Y1394087D03*
Y1399079D03*
Y1386793D03*
X1502268D03*
Y1399079D03*
Y1394087D03*
X1509552Y1405999D03*
Y1410991D03*
X1514508Y1405999D03*
Y1410991D03*
X1502268Y1405999D03*
Y1410991D03*
X1502078Y1465513D03*
Y1460782D03*
X1510740Y1465913D03*
Y1456451D03*
Y1461182D03*
X1502078Y1470244D03*
Y1480867D03*
X1510740Y1471805D03*
Y1476536D03*
Y1481267D03*
X1502078Y1476136D03*
Y1491490D03*
Y1485598D03*
Y1496221D03*
X1510740Y1487159D03*
Y1491890D03*
Y1496621D03*
Y1507245D03*
Y1502514D03*
Y1511976D03*
X1502078Y1506845D03*
Y1500952D03*
Y1511576D03*
Y1516307D03*
X1510740Y1563544D03*
X1502078Y1563144D03*
X1510740Y1558813D03*
Y1578898D03*
X1502078Y1567875D03*
Y1578498D03*
Y1572606D03*
X1510740Y1568275D03*
Y1574167D03*
X1502078Y1583229D03*
Y1593853D03*
Y1587960D03*
X1510740Y1583629D03*
Y1589522D03*
Y1594253D03*
X1502078Y1609207D03*
Y1598584D03*
Y1603315D03*
X1510740Y1609607D03*
Y1604876D03*
Y1598984D03*
X1502078Y1613938D03*
Y1618669D03*
X1510740Y1614338D03*
X1512000Y1644980D03*
X1520072Y82984D03*
Y75184D03*
Y77784D03*
Y80384D03*
X1522626Y92849D03*
X1520072Y85584D03*
X1529586Y103037D03*
X1529720Y116496D03*
Y109410D03*
Y130670D03*
Y123583D03*
X1526311Y137756D03*
X1528635Y555234D03*
X1528350Y562003D03*
X1519156Y596095D03*
X1516869Y594668D03*
X1518354Y592354D03*
X1518415Y589556D03*
X1519153Y599588D03*
X1516930Y597580D03*
X1519185Y615600D03*
X1519153Y607588D03*
X1523646Y634946D03*
X1519063Y876339D03*
X1517344Y896999D03*
X1515743Y888133D03*
X1517344Y903179D03*
X1517153Y908367D03*
X1523000Y923740D03*
X1526611Y921442D03*
X1525740Y928740D03*
X1528087Y936394D03*
X1524500Y949500D03*
X1530174Y956986D03*
X1525522Y971075D03*
X1523966Y980281D03*
X1515096Y997860D03*
X1531096D03*
X1519096D03*
X1523096D03*
X1516776Y1024954D03*
Y1012354D03*
X1526748Y1345691D03*
Y1350683D03*
X1521792Y1345691D03*
Y1350683D03*
X1526748Y1357603D03*
Y1362595D03*
X1521792Y1357603D03*
Y1362595D03*
X1526748Y1369889D03*
Y1374881D03*
Y1381801D03*
X1521792Y1374881D03*
Y1381801D03*
Y1369889D03*
X1526748Y1386793D03*
Y1399079D03*
Y1394087D03*
X1521792Y1386793D03*
Y1394087D03*
Y1399079D03*
X1526748Y1405999D03*
Y1410991D03*
X1521792Y1405999D03*
Y1410991D03*
X1519401Y1465513D03*
Y1460782D03*
X1528062Y1465913D03*
Y1456451D03*
Y1461182D03*
Y1481267D03*
X1519401Y1476136D03*
Y1470244D03*
Y1480867D03*
X1528062Y1471805D03*
Y1476536D03*
X1519401Y1491490D03*
Y1485598D03*
Y1496221D03*
X1528062Y1487159D03*
Y1491890D03*
Y1496621D03*
X1519401Y1506845D03*
Y1500952D03*
Y1511576D03*
X1528062Y1507245D03*
Y1502514D03*
Y1511976D03*
X1519401Y1516307D03*
Y1563144D03*
X1528062Y1558813D03*
Y1563544D03*
Y1578898D03*
X1519401Y1567875D03*
Y1578498D03*
Y1572606D03*
X1528062Y1568275D03*
Y1574167D03*
X1519401Y1587960D03*
X1528062Y1583629D03*
Y1589522D03*
Y1594253D03*
X1519401Y1583229D03*
Y1593853D03*
Y1609207D03*
Y1598584D03*
Y1603315D03*
X1528062Y1609607D03*
Y1604876D03*
Y1598984D03*
X1519401Y1613938D03*
Y1618669D03*
X1528062Y1614338D03*
X1547003Y94017D03*
X1543003D03*
X1547131Y110445D03*
Y115401D03*
Y129574D03*
Y124618D03*
X1545044Y151540D03*
X1548561Y188727D03*
X1542518Y226141D03*
X1545318D03*
X1531901Y293796D03*
X1539915Y288190D03*
X1542415Y285690D03*
X1539915D03*
X1542415Y288190D03*
X1545215D03*
Y285690D03*
X1534401Y293796D03*
X1541283Y354553D03*
X1546272Y1350683D03*
Y1345691D03*
X1534032Y1350683D03*
Y1345691D03*
X1538988D03*
Y1350683D03*
X1546272Y1357603D03*
Y1362595D03*
X1534032Y1357603D03*
Y1362595D03*
X1538988D03*
Y1357603D03*
X1546272Y1374881D03*
Y1369889D03*
Y1381801D03*
X1534032Y1369889D03*
Y1381801D03*
Y1374881D03*
X1538988Y1369889D03*
Y1381801D03*
Y1374881D03*
X1546272Y1386793D03*
Y1394087D03*
Y1399079D03*
X1534032Y1394087D03*
Y1399079D03*
Y1386793D03*
X1538988Y1394087D03*
Y1399079D03*
Y1386793D03*
X1546272Y1405999D03*
Y1410991D03*
X1534032Y1405999D03*
Y1410991D03*
X1538988Y1405999D03*
Y1410991D03*
X1545385Y1461183D03*
X1536724Y1465513D03*
Y1460782D03*
X1545385Y1465914D03*
Y1456452D03*
X1536724Y1476136D03*
Y1470244D03*
Y1480867D03*
X1545385Y1476537D03*
Y1471806D03*
Y1481268D03*
X1536724Y1491490D03*
Y1485598D03*
Y1496221D03*
X1545385Y1491891D03*
Y1487160D03*
Y1496622D03*
X1536724Y1506845D03*
Y1500952D03*
Y1511576D03*
X1545385Y1507246D03*
Y1502515D03*
Y1511977D03*
X1536724Y1516307D03*
X1545385Y1563544D03*
Y1558813D03*
X1536724Y1563144D03*
Y1567875D03*
X1545385Y1568275D03*
X1536724Y1578498D03*
Y1572606D03*
X1545385Y1578898D03*
Y1574167D03*
Y1594253D03*
Y1589522D03*
X1536724Y1583229D03*
X1545385Y1583629D03*
X1536724Y1593853D03*
Y1587960D03*
Y1609207D03*
Y1598584D03*
Y1603315D03*
X1545385Y1609607D03*
Y1598984D03*
Y1604876D03*
Y1614338D03*
X1536724Y1613938D03*
Y1618669D03*
X1532000Y1644980D03*
X1560080Y84140D03*
Y76140D03*
Y80140D03*
X1555012Y94017D03*
X1551003D03*
X1562525Y117557D03*
X1557533D03*
X1552123Y115401D03*
Y110445D03*
X1562525Y122513D03*
X1552123Y129574D03*
Y124618D03*
X1557533Y131731D03*
Y122513D03*
X1562525Y131731D03*
X1560624Y146461D03*
X1557533Y136687D03*
X1562525D03*
X1559526Y152367D03*
X1561226Y180572D03*
X1548694Y191941D03*
X1555194Y184619D03*
X1561226Y185165D03*
X1557174Y206760D03*
X1550388Y256535D03*
X1558388D03*
X1559418Y279208D03*
X1563522Y281307D03*
X1549441Y290755D03*
X1553441D03*
X1557441D03*
X1554403Y352363D03*
X1563248Y389154D03*
X1548629D03*
Y403327D03*
Y410413D03*
X1561778Y396240D03*
X1548629D03*
Y417500D03*
Y424587D03*
Y438760D03*
Y431673D03*
Y445847D03*
Y467539D03*
Y474626D03*
Y488799D03*
Y481713D03*
Y495886D03*
Y511673D03*
Y518760D03*
X1562089Y516841D03*
X1548629Y540020D03*
Y525847D03*
Y532933D03*
Y547106D03*
X1556914Y552872D03*
X1557036Y550123D03*
X1556359Y562443D03*
X1558668Y572334D03*
X1558127Y560675D03*
X1556900Y574102D03*
X1547910Y602197D03*
X1548374Y595108D03*
X1561535Y653161D03*
X1565132Y677843D03*
X1547813Y906581D03*
X1551099Y959096D03*
X1558512Y1345691D03*
Y1350683D03*
X1563468D03*
Y1345691D03*
X1551228Y1350683D03*
Y1345691D03*
X1563468Y1362595D03*
X1551228Y1357603D03*
Y1362595D03*
X1558512D03*
Y1357603D03*
X1563468D03*
X1558512Y1374881D03*
Y1369889D03*
Y1381801D03*
X1563468Y1374881D03*
Y1369889D03*
Y1381801D03*
X1551228Y1369889D03*
Y1381801D03*
Y1374881D03*
X1558512Y1399079D03*
Y1394087D03*
Y1386793D03*
X1563468Y1399079D03*
Y1394087D03*
Y1386793D03*
X1551228D03*
Y1394087D03*
Y1399079D03*
X1558512Y1405999D03*
Y1410991D03*
X1563468Y1405999D03*
Y1410991D03*
X1551228Y1405999D03*
Y1410991D03*
X1552000Y1644980D03*
X1576256Y-25273D03*
X1573003Y-25287D03*
X1576241Y-27788D03*
X1572988Y-27802D03*
X1579281Y-26693D03*
X1573455Y117261D03*
X1565909Y180527D03*
X1569632Y192421D03*
X1565864Y185121D03*
X1571625Y333549D03*
X1579340Y396240D03*
Y403327D03*
Y410413D03*
X1566555Y414823D03*
X1565863Y422864D03*
X1579340Y417500D03*
Y424586D03*
X1565933Y429832D03*
X1565538Y436447D03*
X1579340Y431673D03*
Y438760D03*
X1567573Y447953D03*
X1579340Y445847D03*
X1566740Y467539D03*
X1565482Y472772D03*
X1579340Y474626D03*
Y488799D03*
X1566216Y487711D03*
X1566329Y479104D03*
X1579340Y481712D03*
Y495886D03*
X1566740D03*
X1579340Y518760D03*
X1565050Y511673D03*
X1579340Y540020D03*
Y532933D03*
Y525846D03*
X1574222Y629872D03*
X1569926Y668885D03*
X1575950Y662981D03*
X1570331Y691851D03*
X1575942Y705043D03*
X1575708Y1345597D03*
X1570752Y1350683D03*
Y1345597D03*
X1575708Y1350683D03*
X1570752Y1357603D03*
Y1362595D03*
X1575708D03*
Y1357603D03*
Y1381801D03*
Y1374881D03*
Y1369889D03*
X1570752D03*
Y1381801D03*
Y1374881D03*
X1575708Y1386793D03*
Y1399079D03*
Y1393993D03*
X1570752Y1386793D03*
Y1393993D03*
Y1399079D03*
X1575708Y1405999D03*
Y1410991D03*
X1570752Y1405999D03*
Y1410991D03*
X1572000Y1644980D03*
X1586256Y-64207D03*
X1583003D03*
X1586241Y-66722D03*
X1582988D03*
X1589281Y-65613D03*
X1582822Y60922D03*
X1580327Y57448D03*
X1580986Y113394D03*
X1583635Y110784D03*
X1591229Y133298D03*
X1583229D03*
X1585376Y134579D03*
X1581162Y180665D03*
Y172665D03*
X1581194Y212864D03*
Y200864D03*
Y221864D03*
Y216864D03*
X1582951Y252371D03*
X1586640Y389153D03*
X1581840D03*
Y403326D03*
Y410413D03*
X1586640D03*
X1581840Y396240D03*
X1586640D03*
Y403326D03*
Y417499D03*
X1581840D03*
Y424586D03*
X1586640D03*
X1581840Y438760D03*
X1586640D03*
Y431673D03*
X1581840D03*
X1586640Y467539D03*
X1581840D03*
Y474626D03*
X1586640D03*
X1581840Y488799D03*
X1586640D03*
X1581840Y481712D03*
X1586640D03*
X1581840Y518760D03*
Y511673D03*
X1586640D03*
Y518760D03*
Y525846D03*
Y532933D03*
X1581840D03*
Y525846D03*
X1595185Y543925D03*
X1595760Y555000D03*
X1583720Y560500D03*
X1587948Y1350683D03*
Y1345691D03*
X1582992D03*
Y1350683D03*
X1587948Y1362595D03*
Y1357603D03*
X1582992Y1362595D03*
Y1357603D03*
Y1369889D03*
Y1381801D03*
Y1374881D03*
X1587948Y1369889D03*
Y1381801D03*
Y1374881D03*
X1582992Y1399079D03*
Y1394087D03*
Y1386793D03*
X1587948Y1399079D03*
Y1394087D03*
Y1386793D03*
X1582992Y1405999D03*
Y1410991D03*
X1587948Y1405999D03*
Y1410991D03*
X1592020Y1433061D03*
X1591610Y1469940D03*
X1591586Y1505130D03*
X1609272Y109410D03*
X1601972Y116497D03*
X1609272D03*
X1606772D03*
X1596221Y109172D03*
X1599221D03*
X1598228Y106495D03*
X1601972Y123584D03*
Y130670D03*
X1606772Y123584D03*
X1609272Y123583D03*
Y130670D03*
X1606772D03*
Y137757D03*
X1597962Y146012D03*
X1599868Y141228D03*
X1601972Y137757D03*
X1602756Y150847D03*
X1604724Y247292D03*
X1597433Y253198D03*
X1608240Y329000D03*
X1603664Y342596D03*
X1598223Y351003D03*
X1599127Y375587D03*
X1596714Y383003D03*
X1614338Y636842D03*
X1610620Y1345691D03*
Y1350683D03*
Y1357603D03*
Y1362595D03*
Y1381801D03*
Y1374881D03*
Y1369889D03*
Y1386793D03*
X1597225Y1437014D03*
X1603363Y1460570D03*
X1597457Y1452556D03*
X1598500Y1472500D03*
X1606745Y1474242D03*
X1602580Y1483108D03*
X1598000Y1486000D03*
X1604000Y1516000D03*
X1600700Y1534300D03*
X1622434Y82984D03*
Y80384D03*
Y75184D03*
Y77784D03*
X1624988Y92849D03*
X1622434Y85584D03*
X1613972Y116496D03*
Y102323D03*
Y109410D03*
Y130670D03*
Y123583D03*
Y137756D03*
X1625952Y431029D03*
X1626260Y427017D03*
X1625018Y435029D03*
X1625938Y449873D03*
X1625565Y472579D03*
Y479666D03*
Y486752D03*
Y493839D03*
Y523800D03*
Y516713D03*
Y537973D03*
Y530886D03*
Y566752D03*
Y588013D03*
Y573839D03*
Y580926D03*
Y602186D03*
Y595099D03*
Y609272D03*
Y616359D03*
X1620244Y638125D03*
X1617843Y665140D03*
X1613110Y678462D03*
X1624148Y708258D03*
X1627455Y759489D03*
X1619612Y783152D03*
X1620359Y774830D03*
X1619569Y796035D03*
X1620755Y787530D03*
X1613235Y808466D03*
X1620479Y815730D03*
X1620072Y801630D03*
X1616255Y824405D03*
X1619859Y839519D03*
X1615576Y1345691D03*
Y1350683D03*
X1622860D03*
Y1345691D03*
X1627816Y1350683D03*
Y1345691D03*
X1615576Y1357603D03*
Y1362595D03*
X1622860Y1357603D03*
Y1362595D03*
X1627816Y1357603D03*
Y1362595D03*
X1622860Y1381801D03*
Y1369795D03*
Y1374881D03*
X1627816Y1381801D03*
Y1369795D03*
Y1374881D03*
X1615576Y1381801D03*
Y1374881D03*
Y1369889D03*
Y1386793D03*
X1622860D03*
Y1393993D03*
Y1399079D03*
X1627816Y1386793D03*
Y1399079D03*
Y1393993D03*
X1622860Y1405999D03*
Y1410991D03*
X1627816Y1405999D03*
Y1410991D03*
X1618800Y1528558D03*
X1614200Y1519500D03*
X1614360Y1542860D03*
X1618600Y1532000D03*
X1631948Y103037D03*
X1632082Y116496D03*
Y109410D03*
Y130670D03*
Y123583D03*
X1628673Y137756D03*
X1644880Y226141D03*
X1644777Y288190D03*
X1642277Y285690D03*
X1644777D03*
X1642277Y288190D03*
X1636763Y293796D03*
X1634263D03*
X1635987Y335616D03*
X1630703Y350655D03*
X1636468Y345595D03*
X1636271Y410394D03*
Y403307D03*
X1637665Y458406D03*
Y451319D03*
X1637489Y462264D03*
X1632865Y465492D03*
X1637665D03*
Y472579D03*
X1632865D03*
X1630365D03*
Y479666D03*
X1632865D03*
X1637665Y479665D03*
Y486752D03*
X1630365D03*
X1632865D03*
X1630365Y493839D03*
X1637665D03*
X1632865Y509626D03*
Y516713D03*
X1630365D03*
Y523800D03*
X1632865D03*
X1637665Y523799D03*
Y516713D03*
Y509626D03*
X1630365Y530886D03*
X1637665D03*
X1632865D03*
X1637665Y537973D03*
X1630365D03*
X1637665Y559665D03*
Y566752D03*
X1630365D03*
X1632865D03*
Y559665D03*
Y573839D03*
X1630365Y580926D03*
X1632865D03*
X1637665D03*
Y588012D03*
X1630365Y588013D03*
X1632865Y588012D03*
X1637665Y573839D03*
X1630365D03*
X1632865Y602185D03*
X1630365Y602186D03*
X1637665Y602185D03*
Y595099D03*
X1632865D03*
X1630365D03*
Y616359D03*
X1632865Y609272D03*
X1630365D03*
X1637665Y616358D03*
Y609272D03*
X1637526Y699930D03*
X1637472Y717830D03*
X1631031Y732430D03*
X1628813Y727045D03*
X1631187Y750630D03*
X1629969Y740826D03*
X1644304Y891353D03*
X1640056Y1345691D03*
Y1350683D03*
X1635100Y1345691D03*
Y1350683D03*
X1640056Y1357603D03*
Y1362595D03*
X1635100D03*
Y1357603D03*
X1640056Y1369889D03*
Y1374881D03*
Y1381801D03*
X1635100Y1369889D03*
Y1374881D03*
Y1381801D03*
X1640056Y1399079D03*
Y1394087D03*
Y1386793D03*
X1635100Y1394087D03*
Y1399079D03*
Y1386793D03*
Y1405999D03*
Y1410991D03*
X1640056Y1405999D03*
Y1410991D03*
X1649365Y94017D03*
X1657374D03*
X1653365D03*
X1645365D03*
X1659895Y117557D03*
X1654485Y110445D03*
Y115401D03*
X1649493Y110445D03*
Y115401D03*
X1659895Y122513D03*
Y131731D03*
X1654485Y124618D03*
Y129574D03*
X1649493Y124618D03*
Y129574D03*
X1659895Y136687D03*
X1647406Y151540D03*
X1651056Y191941D03*
X1657556Y184619D03*
X1650923Y188727D03*
X1659536Y206760D03*
X1647680Y226141D03*
X1660750Y256535D03*
X1652750D03*
X1647577Y285690D03*
Y288190D03*
X1655803Y290755D03*
X1651803D03*
X1659803D03*
X1645685Y390500D03*
X1655335Y381500D03*
X1653507Y470136D03*
X1655776Y465492D03*
X1655742Y460250D03*
X1655776Y472579D03*
Y486752D03*
Y479665D03*
Y493839D03*
Y509626D03*
Y516713D03*
X1652236Y537973D03*
X1654716Y525483D03*
X1654637Y532756D03*
X1655776Y559665D03*
Y566752D03*
X1655626Y579978D03*
X1655776Y573839D03*
X1655840Y608117D03*
X1654572Y771702D03*
X1645128Y929263D03*
X1645342Y962120D03*
X1657091Y990823D03*
X1649571Y983857D03*
X1647340Y1350683D03*
Y1345691D03*
X1652296Y1350683D03*
Y1345691D03*
X1659580Y1350683D03*
Y1345691D03*
X1647340Y1357603D03*
Y1362595D03*
X1652296Y1357603D03*
Y1362595D03*
X1659580D03*
Y1357603D03*
X1647340Y1381801D03*
Y1374881D03*
Y1369889D03*
X1652296Y1381801D03*
Y1374881D03*
Y1369889D03*
X1659580Y1374881D03*
Y1369889D03*
Y1381801D03*
X1647340Y1386793D03*
Y1394087D03*
Y1399079D03*
X1652296Y1386793D03*
Y1399079D03*
Y1394087D03*
X1659580D03*
Y1399079D03*
Y1386793D03*
X1647340Y1405999D03*
Y1410991D03*
X1652296Y1405999D03*
Y1410991D03*
X1659580Y1405999D03*
Y1410991D03*
X1657983Y1460782D03*
X1649322Y1456451D03*
Y1465913D03*
X1657983Y1465513D03*
X1649322Y1461182D03*
Y1476536D03*
X1657983Y1476136D03*
Y1470244D03*
X1649322Y1471805D03*
Y1481267D03*
X1657983Y1480867D03*
X1649322Y1487159D03*
Y1496621D03*
X1657983Y1496221D03*
X1649322Y1491890D03*
X1657983Y1491490D03*
Y1485598D03*
Y1500952D03*
X1649322Y1502514D03*
X1657983Y1511576D03*
X1649322Y1511976D03*
Y1507245D03*
X1657983Y1506845D03*
Y1516307D03*
X1649322Y1558813D03*
Y1563544D03*
X1657983Y1563144D03*
Y1572606D03*
X1649322Y1574167D03*
Y1568275D03*
X1657983Y1567875D03*
X1649322Y1578898D03*
X1657983Y1578498D03*
X1649322Y1583629D03*
X1657983Y1583229D03*
X1649322Y1594253D03*
X1657983Y1593853D03*
Y1587960D03*
X1649322Y1589522D03*
Y1609607D03*
X1657983Y1609207D03*
X1649322Y1598984D03*
X1657983Y1598584D03*
Y1603315D03*
X1649322Y1604876D03*
Y1614338D03*
X1657983Y1613938D03*
Y1618669D03*
X1652000Y1644980D03*
X1662442Y84140D03*
Y76140D03*
Y80140D03*
X1675817Y117261D03*
X1664887Y117557D03*
Y122513D03*
Y131731D03*
X1662986Y146461D03*
X1664887Y136687D03*
X1661888Y152367D03*
X1663588Y180572D03*
X1668271Y180527D03*
X1671994Y192421D03*
X1663588Y185165D03*
X1668226Y185121D03*
X1661780Y279208D03*
X1665884Y281307D03*
X1669767Y445908D03*
X1673717Y445787D03*
X1664536Y1350683D03*
Y1345691D03*
X1671820D03*
Y1350683D03*
X1676776Y1345691D03*
Y1350683D03*
X1664536Y1357603D03*
Y1362595D03*
X1671820Y1357603D03*
Y1362595D03*
X1676776Y1357603D03*
Y1362595D03*
X1664536Y1374881D03*
Y1369889D03*
Y1381801D03*
X1671820Y1374881D03*
Y1381801D03*
Y1369889D03*
X1676776D03*
Y1374881D03*
Y1381801D03*
X1664536Y1394087D03*
Y1399079D03*
Y1386793D03*
X1671820D03*
Y1394087D03*
Y1399079D03*
X1676776Y1386793D03*
Y1399079D03*
Y1394087D03*
X1664536Y1405999D03*
Y1410991D03*
X1671820Y1405999D03*
Y1410991D03*
X1676776Y1405999D03*
Y1410991D03*
X1666645Y1465913D03*
Y1456451D03*
Y1461182D03*
X1675306Y1465513D03*
Y1460782D03*
X1666645Y1471805D03*
Y1476536D03*
Y1481267D03*
X1675306Y1476136D03*
Y1470244D03*
Y1480867D03*
X1666645Y1487159D03*
Y1491890D03*
Y1496621D03*
X1675306Y1491490D03*
Y1485598D03*
Y1496221D03*
Y1511576D03*
X1666645Y1511976D03*
Y1507245D03*
Y1502514D03*
X1675306Y1506845D03*
Y1500952D03*
Y1516307D03*
X1666645Y1558813D03*
Y1563544D03*
X1675306Y1563144D03*
Y1578498D03*
Y1572606D03*
X1666645Y1568275D03*
X1675306Y1567875D03*
X1666645Y1574167D03*
Y1578898D03*
Y1583629D03*
X1675306Y1583229D03*
X1666645Y1589522D03*
Y1594253D03*
X1675306Y1593853D03*
Y1587960D03*
X1666645Y1604876D03*
Y1598984D03*
X1675306Y1609207D03*
Y1598584D03*
Y1603315D03*
X1666645Y1609607D03*
Y1614338D03*
X1675306Y1613938D03*
Y1618669D03*
X1672000Y1644980D03*
X1685184Y60922D03*
X1680020Y55513D03*
X1683348Y113394D03*
X1685997Y110784D03*
X1686171Y130898D03*
X1693591Y133298D03*
X1687738Y134579D03*
X1683524Y172665D03*
Y180665D03*
X1683556Y200864D03*
Y212864D03*
Y221864D03*
Y216864D03*
X1685313Y252371D03*
X1687164Y336324D03*
X1678072Y342319D03*
X1691743Y353506D03*
X1680518Y385912D03*
Y393924D03*
Y389912D03*
Y409924D03*
Y405924D03*
Y401924D03*
X1677933Y418838D03*
X1689016Y1345691D03*
Y1350683D03*
X1684060D03*
Y1345691D03*
X1689016Y1362595D03*
Y1357603D03*
X1684060D03*
Y1362595D03*
X1689016Y1369889D03*
Y1381801D03*
Y1374881D03*
X1684060Y1369889D03*
Y1381801D03*
Y1374881D03*
X1689016Y1394087D03*
Y1399079D03*
Y1386793D03*
X1684060Y1394087D03*
Y1399079D03*
Y1386793D03*
X1689016Y1405999D03*
Y1410991D03*
X1684060Y1405999D03*
Y1410991D03*
X1683968Y1465913D03*
Y1456451D03*
Y1461182D03*
X1692629Y1465513D03*
Y1460782D03*
X1683968Y1471805D03*
Y1476536D03*
Y1481267D03*
X1692629Y1476136D03*
Y1470244D03*
Y1480867D03*
X1683968Y1487159D03*
Y1491890D03*
Y1496621D03*
X1692629Y1491490D03*
Y1485598D03*
Y1496221D03*
X1683968Y1502514D03*
Y1511976D03*
X1692629Y1506845D03*
Y1500952D03*
Y1511576D03*
X1683968Y1507245D03*
X1692629Y1516307D03*
X1683968Y1558813D03*
Y1563544D03*
X1692629Y1563144D03*
Y1572606D03*
X1683968Y1568275D03*
Y1574167D03*
Y1578898D03*
X1692629Y1567875D03*
Y1578498D03*
X1683968Y1583629D03*
Y1589522D03*
Y1594253D03*
X1692629Y1583229D03*
Y1593853D03*
Y1587960D03*
X1683968Y1598984D03*
X1692629Y1609207D03*
Y1598584D03*
Y1603315D03*
X1683968Y1609607D03*
Y1604876D03*
Y1614338D03*
X1692629Y1613938D03*
Y1618669D03*
X1692000Y1644980D03*
X1698583Y109172D03*
X1701583D03*
X1700590Y106495D03*
X1709134Y116497D03*
X1704334D03*
X1709134Y123584D03*
Y130670D03*
X1704334Y123584D03*
Y130670D03*
X1700324Y146012D03*
X1702230Y141228D03*
X1709134Y137757D03*
X1704334D03*
X1705118Y150847D03*
X1707086Y247292D03*
X1699795Y253198D03*
X1701495Y289735D03*
X1695142Y303839D03*
X1708889Y1189221D03*
X1696300Y1350683D03*
Y1345691D03*
X1701256Y1350683D03*
Y1345691D03*
X1708540D03*
Y1350683D03*
X1696300Y1357603D03*
Y1362595D03*
X1701256Y1357603D03*
Y1362595D03*
X1708540D03*
Y1357603D03*
X1696300Y1374881D03*
Y1369889D03*
Y1381801D03*
X1701256Y1369889D03*
Y1381801D03*
Y1374881D03*
X1708540D03*
Y1369889D03*
Y1381801D03*
X1696300Y1386793D03*
Y1394087D03*
Y1399079D03*
X1701256Y1386793D03*
Y1394087D03*
Y1399079D03*
X1708540D03*
Y1394087D03*
Y1386793D03*
X1696300Y1405999D03*
Y1410991D03*
X1701256Y1405999D03*
Y1410991D03*
X1708540Y1405999D03*
Y1410991D03*
X1701290Y1465913D03*
Y1456451D03*
Y1461182D03*
Y1471805D03*
Y1476536D03*
Y1481267D03*
Y1487159D03*
Y1491890D03*
Y1496621D03*
Y1507245D03*
Y1502514D03*
Y1511976D03*
Y1558813D03*
Y1563544D03*
Y1568275D03*
Y1574167D03*
Y1578898D03*
Y1583629D03*
Y1589522D03*
Y1594253D03*
Y1609607D03*
Y1604876D03*
Y1598984D03*
Y1614338D03*
X1724796Y82984D03*
Y77784D03*
Y80384D03*
Y75184D03*
Y85584D03*
X1716334Y116496D03*
Y109410D03*
Y102323D03*
X1711634Y116497D03*
Y109410D03*
X1716334Y130670D03*
Y123583D03*
X1711634D03*
Y130670D03*
X1716334Y137756D03*
X1720960Y1148000D03*
X1723796Y1160168D03*
X1725660Y1193019D03*
X1721660D03*
X1711783Y1193848D03*
X1713496Y1350683D03*
Y1345691D03*
X1720780Y1350683D03*
Y1345597D03*
X1725736Y1350683D03*
Y1345597D03*
X1713496Y1357603D03*
Y1362595D03*
X1720780Y1357603D03*
Y1362595D03*
X1725736Y1357603D03*
Y1362595D03*
X1713496Y1374881D03*
Y1369889D03*
Y1381801D03*
X1720780Y1369889D03*
Y1381801D03*
Y1374881D03*
X1725736Y1381801D03*
Y1374881D03*
Y1369889D03*
X1713496Y1399079D03*
Y1394087D03*
Y1386793D03*
X1720780D03*
Y1393993D03*
Y1399079D03*
X1725736Y1386793D03*
Y1399079D03*
Y1393993D03*
X1713496Y1405999D03*
Y1410991D03*
X1720780Y1405999D03*
Y1410991D03*
X1725736Y1405999D03*
Y1410991D03*
X1709952Y1465513D03*
Y1460782D03*
X1718613Y1465914D03*
Y1456452D03*
Y1461183D03*
Y1476537D03*
Y1471806D03*
Y1481268D03*
X1709952Y1476136D03*
Y1470244D03*
Y1480867D03*
Y1491490D03*
Y1485598D03*
Y1496221D03*
X1718613Y1491891D03*
Y1487160D03*
Y1496622D03*
Y1502515D03*
Y1511977D03*
X1709952Y1506845D03*
Y1500952D03*
Y1511576D03*
X1718613Y1507246D03*
X1709952Y1516307D03*
Y1563144D03*
X1718613Y1563544D03*
Y1558813D03*
X1709952Y1567875D03*
X1718613Y1568275D03*
X1709952Y1578498D03*
Y1572606D03*
X1718613Y1578898D03*
Y1574167D03*
Y1589522D03*
X1709952Y1583229D03*
X1718613Y1583629D03*
X1709952Y1593853D03*
Y1587960D03*
X1718613Y1594253D03*
Y1609607D03*
Y1598984D03*
Y1604876D03*
X1709952Y1609207D03*
Y1598584D03*
Y1603315D03*
Y1618669D03*
X1718613Y1614338D03*
X1709952Y1613938D03*
X1712000Y1644980D03*
X1727350Y92849D03*
X1734310Y103037D03*
X1734444Y116496D03*
Y109410D03*
Y130670D03*
Y123583D03*
X1730647Y137756D03*
X1739125Y293796D03*
X1736625D03*
X1737703Y472189D03*
X1728038Y491870D03*
X1730538D03*
X1730675Y1132361D03*
X1726963Y1132319D03*
X1739917Y1146937D03*
X1729207Y1159455D03*
X1737393Y1162817D03*
X1733660Y1193019D03*
X1729660D03*
X1737660D03*
X1733695Y1212164D03*
X1735989Y1214458D03*
X1731619Y1210089D03*
X1740785Y1219254D03*
X1737976Y1350683D03*
Y1345691D03*
X1733020D03*
Y1350683D03*
X1737976Y1362595D03*
Y1357603D03*
X1733020Y1362595D03*
Y1357603D03*
X1737976Y1369889D03*
Y1374881D03*
X1733020Y1369889D03*
Y1381801D03*
Y1374881D03*
X1737976Y1381801D03*
Y1399079D03*
Y1394087D03*
Y1386793D03*
X1733020Y1399079D03*
Y1394087D03*
Y1386793D03*
X1737976Y1405999D03*
Y1410991D03*
X1733020Y1405999D03*
Y1410991D03*
X1732000Y1644980D03*
X1755727Y94017D03*
X1747727D03*
X1751727D03*
X1751855Y110445D03*
Y115401D03*
X1756847D03*
Y110445D03*
X1751855Y129574D03*
Y124618D03*
X1756847D03*
Y129574D03*
X1753418Y191941D03*
X1753285Y188727D03*
X1747242Y226141D03*
X1750042D03*
X1755112Y256535D03*
X1749939Y288190D03*
X1747139D03*
X1744639D03*
X1749939Y285690D03*
X1744639D03*
X1747139D03*
X1758165Y290755D03*
X1754165D03*
X1744524Y370010D03*
X1753474Y542699D03*
X1757402Y825111D03*
Y820155D03*
X1744937Y912517D03*
X1747937D03*
X1750751Y910785D03*
X1748081Y984379D03*
X1756192Y996132D03*
X1743224Y1119055D03*
X1752000Y1644980D03*
X1764804Y84140D03*
Y76140D03*
Y80140D03*
X1759736Y94017D03*
X1767249Y117557D03*
X1762257D03*
Y122513D03*
Y131731D03*
X1767249Y122513D03*
Y131731D03*
X1762257Y136687D03*
X1767249D03*
X1765950Y180572D03*
X1770633Y180527D03*
X1774356Y192421D03*
X1759918Y184619D03*
X1770588Y185121D03*
X1765950Y185165D03*
X1761898Y206760D03*
X1763112Y256535D03*
X1764142Y279208D03*
X1768246Y281307D03*
X1762165Y290755D03*
X1765497Y370899D03*
X1766204Y398949D03*
X1770778Y402642D03*
X1773278D03*
X1763704Y401949D03*
X1767953Y413611D03*
X1770453D03*
X1772953D03*
X1772893Y423944D03*
X1770393D03*
X1767893D03*
X1765093D03*
X1765153Y413611D03*
X1764912Y482382D03*
X1765006Y478382D03*
X1761953Y706827D03*
Y865160D03*
X1772599Y993053D03*
X1762898Y992883D03*
X1764744Y1101930D03*
Y1097879D03*
X1766899Y1121122D03*
X1769499D03*
X1772099D03*
X1774799D03*
X1766999Y1130822D03*
X1772199D03*
X1769599D03*
X1774339Y1437975D03*
X1774216Y1470165D03*
X1772000Y1644980D03*
X1788884Y59871D03*
X1782382Y55513D03*
X1778179Y117261D03*
X1785886Y172665D03*
Y180665D03*
X1785918Y200864D03*
Y212864D03*
Y216864D03*
Y221864D03*
X1790014Y468607D03*
X1784602Y564092D03*
X1782600Y874500D03*
X1774899Y1130822D03*
Y1139822D03*
X1777399D03*
Y1147822D03*
X1774899D03*
X1785961Y1224892D03*
X1791099Y1260421D03*
X1779868Y1446668D03*
X1786564Y1478858D03*
X1777131Y1604357D03*
X1791570Y74535D03*
X1793149Y662810D03*
X1798705Y718793D03*
X1805013Y1091877D03*
X1792847Y1099210D03*
X1799012Y1095893D03*
X1805013Y1096470D03*
X1792863Y1103246D03*
X1801147Y1208555D03*
X1802844Y1227695D03*
X1793976Y1440762D03*
X1807270Y1468535D03*
X1793879Y1472952D03*
X1792000Y1644980D03*
X1816322Y977215D03*
X1823074Y992833D03*
X1812296Y1075688D03*
X1809696Y1091832D03*
X1809651Y1096426D03*
X1823028Y1124289D03*
X1817728D03*
X1815128D03*
X1820328D03*
X1822928Y1114589D03*
X1820228D03*
X1815028D03*
X1817628D03*
X1815865Y1133356D03*
X1809897Y1237285D03*
Y1230385D03*
Y1232885D03*
Y1239785D03*
Y1244185D03*
Y1246685D03*
X1807393Y1436345D03*
X1812000Y1644980D03*
X1831511Y978888D03*
X1831914Y992877D03*
X1824706Y1081145D03*
Y1089145D03*
X1837933Y1636171D03*
X1832000Y1644980D03*
G54D33*
X141337Y1228542D03*
X141336Y1247242D03*
Y1239762D03*
X161909Y1129429D03*
X160039Y1228543D03*
X169389Y1121948D03*
X167519Y1198621D03*
Y1213582D03*
X174999Y1228543D03*
X182480D03*
X167519D03*
X189960D03*
X197440D03*
X210531Y1211712D03*
X212401Y1228543D03*
X204921D03*
X213969Y1453293D03*
Y1464293D03*
X218011Y1211712D03*
X227362Y1228543D03*
X219881D03*
X227249Y1464293D03*
Y1453293D03*
X242322Y1250984D03*
X234842D03*
Y1254724D03*
X242322D03*
X249803Y1250984D03*
X257283D03*
Y1254724D03*
X249803D03*
X264763D03*
Y1250984D03*
X272244Y1254724D03*
Y1250984D03*
X279724D03*
Y1254724D03*
X294685Y1127558D03*
Y1135039D03*
Y1194881D03*
Y1202362D03*
X290944Y1191141D03*
X294685Y1209842D03*
X287204Y1254724D03*
Y1250984D03*
X302165Y1108858D03*
X298425Y1112598D03*
X309645D03*
Y1120078D03*
X305905Y1116338D03*
X298425Y1120078D03*
X305905Y1123818D03*
X309645Y1135039D03*
Y1127558D03*
X311515Y1136909D03*
X304035Y1140649D03*
X305905Y1131299D03*
X296555Y1151869D03*
X304035Y1155610D03*
Y1148129D03*
X296555Y1144389D03*
X311515D03*
Y1151869D03*
X296555Y1159350D03*
Y1166830D03*
X304035Y1170570D03*
X300295D03*
X311515Y1159350D03*
X300295Y1185531D03*
Y1178051D03*
X296555Y1174310D03*
X298425Y1187401D03*
X304035Y1185531D03*
Y1178051D03*
Y1193011D03*
X302165Y1198621D03*
X305905Y1206102D03*
X302165Y1213582D03*
Y1206102D03*
X298425Y1221062D03*
Y1217322D03*
X313385Y1105117D03*
X317125Y1116338D03*
Y1123818D03*
X313385D03*
Y1116338D03*
X315255Y1136909D03*
X313384Y1131299D03*
X315255Y1144389D03*
Y1151869D03*
Y1159350D03*
Y1166830D03*
Y1181791D03*
Y1189271D03*
Y1174310D03*
X313385Y1198621D03*
Y1206102D03*
X320866Y1217322D03*
X317125Y1221062D03*
X313385Y1213582D03*
X324606Y1209842D03*
Y1217322D03*
X320866Y1221062D03*
X324606D03*
X320866Y1236023D03*
Y1224803D03*
X324606Y1232283D03*
Y1236023D03*
Y1224803D03*
Y1243503D03*
X598424Y1228542D03*
X598423Y1239762D03*
Y1247242D03*
X618996Y1129429D03*
X617126Y1228543D03*
X626476Y1121948D03*
X624606Y1198621D03*
Y1213582D03*
X632086Y1228543D03*
X624606D03*
X639567D03*
X647047D03*
X667618Y1211712D03*
X654527Y1228543D03*
X662008D03*
X669488D03*
X675098Y1211712D03*
X676968Y1228543D03*
X684449D03*
X699409Y1254724D03*
X691929Y1250984D03*
Y1254724D03*
X699409Y1250984D03*
X706890D03*
X714370Y1254724D03*
Y1250984D03*
X706890Y1254724D03*
X729331Y1250984D03*
X721850D03*
Y1254724D03*
X729331D03*
X748031Y1194881D03*
X744291Y1254724D03*
Y1250984D03*
X736811Y1254724D03*
Y1250984D03*
X762992Y1116338D03*
X766732Y1120078D03*
X762992Y1123818D03*
X766732Y1112598D03*
X759252Y1108858D03*
X755512Y1120078D03*
X761122Y1140649D03*
X762992Y1131299D03*
X766732Y1135039D03*
Y1127558D03*
X751772D03*
Y1135039D03*
X753642Y1144389D03*
X761122Y1148129D03*
Y1155610D03*
X753642Y1151869D03*
X757382Y1170570D03*
X761122D03*
X753642Y1166830D03*
Y1159350D03*
Y1181791D03*
Y1174310D03*
X757382Y1178051D03*
Y1185531D03*
X761122Y1178051D03*
Y1185531D03*
X753642Y1189271D03*
X759252Y1191141D03*
X762992D03*
X755512Y1194881D03*
X759252Y1198621D03*
X751772Y1202362D03*
X755512Y1221062D03*
Y1217322D03*
X759252Y1213582D03*
X762992Y1206102D03*
X759252D03*
X751772Y1209842D03*
X770472Y1105117D03*
Y1123818D03*
X774212D03*
X770472Y1116338D03*
X774212D03*
X770471Y1131299D03*
X770472Y1138779D03*
X772342Y1151869D03*
Y1144389D03*
X768602Y1151869D03*
Y1144389D03*
X772342Y1166830D03*
X768602Y1159350D03*
X772342D03*
Y1174310D03*
Y1181791D03*
Y1196751D03*
X770472Y1198621D03*
X781693Y1217322D03*
X777953D03*
X774212Y1221062D03*
X781693Y1209842D03*
X770472Y1213582D03*
Y1206102D03*
X777953Y1221062D03*
X781693D03*
Y1224803D03*
X777953D03*
X781693Y1232283D03*
X777953Y1236023D03*
X781693D03*
Y1243503D03*
X1055510Y1228542D03*
X1055509Y1239762D03*
Y1247242D03*
X1074212Y1228543D03*
X1083562Y1121948D03*
X1076082Y1129429D03*
X1081692Y1198621D03*
Y1213582D03*
Y1228543D03*
X1089172D03*
X1104133D03*
X1096653D03*
X1124704Y1211712D03*
X1119094Y1228543D03*
X1111613D03*
X1132184Y1211712D03*
X1126574Y1228543D03*
X1134054D03*
X1141535D03*
X1149015Y1254724D03*
X1156495D03*
X1149015Y1250984D03*
X1156495D03*
X1171456D03*
X1163976D03*
X1171456Y1254724D03*
X1163976D03*
X1178936D03*
Y1250984D03*
X1186417D03*
Y1254724D03*
X1203247Y1193011D03*
X1201377Y1250984D03*
X1193897D03*
X1201377Y1254724D03*
X1193897D03*
X1216338Y1108858D03*
X1212598Y1120078D03*
X1220078Y1116338D03*
Y1123818D03*
X1218208Y1140649D03*
X1208858Y1127558D03*
X1220078Y1131299D03*
X1208858Y1135039D03*
X1210728Y1151869D03*
X1218208Y1155610D03*
Y1148129D03*
X1210728Y1144389D03*
Y1159350D03*
Y1166830D03*
X1218208Y1170570D03*
X1214468D03*
X1210728Y1181791D03*
Y1189271D03*
X1218208Y1185531D03*
Y1178051D03*
X1214468Y1185531D03*
Y1178051D03*
X1210728Y1174310D03*
X1212598Y1194881D03*
X1218208Y1193011D03*
X1214468D03*
X1216338Y1198621D03*
X1208858Y1202362D03*
X1220078Y1206102D03*
X1216338D03*
X1212598Y1221062D03*
Y1217322D03*
X1216338Y1213582D03*
X1208858Y1209842D03*
X1227558Y1105117D03*
X1223818Y1112598D03*
Y1120078D03*
X1227558Y1116338D03*
X1231298D03*
X1227558Y1123818D03*
X1231298D03*
X1229428Y1136909D03*
X1223818Y1127558D03*
X1227557Y1131299D03*
X1223818Y1135039D03*
X1225688Y1144389D03*
Y1151869D03*
X1229428Y1144389D03*
Y1151869D03*
Y1159350D03*
X1225688D03*
X1229428Y1166830D03*
Y1181791D03*
Y1189271D03*
Y1174310D03*
Y1196751D03*
X1227558Y1198621D03*
Y1206102D03*
X1235039Y1217322D03*
X1231298Y1221062D03*
X1227558Y1213582D03*
X1235039Y1221062D03*
Y1224803D03*
Y1236023D03*
X1238779Y1217322D03*
Y1209842D03*
Y1221062D03*
Y1224803D03*
Y1232283D03*
Y1236023D03*
Y1243503D03*
X1514468Y1166829D03*
Y1174309D03*
Y1181790D03*
X1512597Y1228542D03*
X1512596Y1239762D03*
Y1247242D03*
X1540649Y1121948D03*
X1533169Y1129429D03*
X1538779Y1198621D03*
Y1213582D03*
X1531299Y1228543D03*
X1538779D03*
X1546259D03*
X1561220D03*
X1553740D03*
X1576181D03*
X1568700D03*
X1589271Y1211712D03*
X1581791D03*
X1583661Y1228543D03*
X1591141D03*
X1598622D03*
X1606102Y1250984D03*
Y1254724D03*
X1621063D03*
X1613582Y1250984D03*
Y1254724D03*
X1621063Y1250984D03*
X1636023Y1254724D03*
Y1250984D03*
X1643504D03*
X1628543D03*
Y1254724D03*
X1643504D03*
X1660334Y1204232D03*
Y1200491D03*
Y1193011D03*
Y1196751D03*
Y1207972D03*
X1650984Y1250984D03*
Y1254724D03*
X1658464D03*
Y1250984D03*
X1673425Y1108858D03*
X1669685Y1112598D03*
Y1120078D03*
X1675295Y1140649D03*
X1665945Y1127558D03*
Y1135039D03*
X1667815Y1151869D03*
X1675295Y1155610D03*
Y1148129D03*
X1667815Y1144389D03*
Y1159350D03*
Y1166830D03*
X1675295Y1170570D03*
X1671555D03*
Y1185531D03*
Y1178051D03*
X1667815Y1174310D03*
Y1181791D03*
Y1189271D03*
X1675295Y1185531D03*
Y1178051D03*
X1669685Y1194881D03*
X1675295Y1193011D03*
X1671555D03*
X1665945Y1202362D03*
X1673425Y1198621D03*
X1669685Y1221062D03*
Y1217322D03*
X1673425Y1213582D03*
X1665945Y1209842D03*
X1673425Y1206102D03*
X1684645Y1105117D03*
X1677165Y1116338D03*
X1680905Y1112598D03*
X1677165Y1123818D03*
X1680905Y1120078D03*
X1684645Y1116338D03*
X1688385D03*
X1684645Y1123818D03*
X1688385D03*
X1686515Y1136909D03*
X1682775D03*
X1680905Y1127558D03*
X1677165Y1131299D03*
X1684644D03*
X1680905Y1135039D03*
X1682775Y1144389D03*
Y1151869D03*
X1686515Y1144389D03*
Y1151869D03*
Y1159350D03*
X1682775D03*
X1686515Y1166830D03*
Y1174310D03*
Y1181791D03*
Y1189271D03*
X1684645Y1198621D03*
X1692126Y1217322D03*
X1688385Y1221062D03*
X1684645Y1213582D03*
Y1206102D03*
X1677165D03*
X1692126Y1221062D03*
Y1224803D03*
Y1236023D03*
X1695866Y1217322D03*
Y1209842D03*
Y1221062D03*
Y1232283D03*
Y1236023D03*
Y1224803D03*
Y1243503D03*
G54D26*
X73872Y1348187D03*
X81752D03*
X73872Y1360099D03*
X81752D03*
X73872Y1384297D03*
Y1372385D03*
X81752Y1384297D03*
Y1372385D03*
X86112Y1348187D03*
X98352D03*
X93992D03*
X86112Y1360099D03*
X98352D03*
X93992D03*
X86112Y1384297D03*
Y1372385D03*
X98352Y1384297D03*
Y1372385D03*
X93992D03*
Y1384297D03*
X86112Y1396583D03*
X93992D03*
X98352D03*
X86112Y1408495D03*
X93992D03*
X98352D03*
X110592Y1348187D03*
X106232D03*
X110592Y1360099D03*
X106232D03*
X110592Y1384297D03*
X106232D03*
Y1372385D03*
X110592D03*
Y1396583D03*
X106232D03*
X110592Y1408495D03*
X106232D03*
X118472Y1348187D03*
X122832D03*
X130712D03*
X118472Y1360099D03*
X122832D03*
X130712D03*
X118472Y1384297D03*
Y1372385D03*
X122832Y1384297D03*
Y1372385D03*
X130712Y1384297D03*
Y1372385D03*
X118472Y1396583D03*
X122832D03*
X130712D03*
X118472Y1408495D03*
X122832D03*
X130712D03*
X146948Y1080806D03*
Y1103247D03*
X143208D03*
X146948Y1133169D03*
Y1140649D03*
X139468Y1136909D03*
X143208Y1125688D03*
Y1133169D03*
Y1140649D03*
X146948Y1125688D03*
X143208Y1144389D03*
Y1151870D03*
X146948Y1144389D03*
Y1151870D03*
X140707Y1170569D03*
X143208Y1159350D03*
X146948D03*
X148818Y1183661D03*
X140707Y1178050D03*
X145078Y1187401D03*
Y1183661D03*
X148818Y1187401D03*
X146947Y1174310D03*
X141337Y1191142D03*
X145078Y1194881D03*
Y1202362D03*
X148818Y1194881D03*
Y1202362D03*
X141337Y1198622D03*
X145078Y1198621D03*
Y1191141D03*
X148818D03*
Y1198621D03*
X145078Y1221062D03*
X148818D03*
X141337Y1206103D03*
X145078Y1209842D03*
Y1217322D03*
X148818Y1209842D03*
Y1217322D03*
X141337Y1213583D03*
Y1221063D03*
X148818Y1213582D03*
X145078D03*
Y1206102D03*
X148818D03*
Y1224803D03*
X145078Y1232283D03*
Y1236023D03*
X148818Y1232283D03*
Y1236023D03*
X145078Y1224803D03*
X148818Y1247243D03*
X145078D03*
X148818Y1254724D03*
Y1239763D03*
X145078D03*
X135072Y1348187D03*
X142952D03*
X147312D03*
X135072Y1360099D03*
X147312D03*
X142952D03*
X135072Y1384297D03*
Y1372385D03*
X147312Y1384297D03*
Y1372385D03*
X142952Y1384297D03*
Y1372385D03*
X135072Y1396583D03*
X147312D03*
X142952D03*
X135072Y1408495D03*
X147312D03*
X142952D03*
X150688Y1077066D03*
X158169Y1106988D03*
X165649D03*
X161909D03*
X158169Y1118208D03*
Y1121948D03*
X154429D03*
X150689D03*
X165649Y1114468D03*
X161909D03*
X158169Y1133169D03*
X161909Y1140649D03*
X158169Y1125688D03*
X154429Y1129429D03*
X150689D03*
Y1136909D03*
X154429Y1140649D03*
X150689D03*
X165649D03*
Y1129429D03*
Y1136909D03*
X158169Y1140649D03*
X150689Y1151870D03*
X158169Y1155610D03*
X154429D03*
X150689D03*
X161909Y1144389D03*
Y1148129D03*
Y1151870D03*
Y1155610D03*
X150689Y1144389D03*
Y1148129D03*
Y1159350D03*
X158169Y1166830D03*
X150688D03*
X154429Y1170570D03*
X150688D03*
X161909Y1159350D03*
X160039Y1187401D03*
X156299Y1183661D03*
X152559D03*
X161909Y1174310D03*
Y1178051D03*
X165649Y1181791D03*
X161909D03*
X158169Y1174310D03*
X154429D03*
X150688Y1178051D03*
Y1174310D03*
X156299Y1179921D03*
X160039Y1183661D03*
X163779D03*
X156299Y1187401D03*
X163779D03*
X152559D03*
X156299Y1198621D03*
X152559D03*
X163779D03*
X160039D03*
X152559Y1191141D03*
X156299D03*
X160039D03*
X163779D03*
X156299Y1202362D03*
Y1194881D03*
X152559Y1202362D03*
Y1194881D03*
X163779D03*
Y1202362D03*
X160039Y1206102D03*
X156299D03*
X152559D03*
X163779D03*
X156299Y1213582D03*
X152559D03*
X160039Y1221062D03*
X156299D03*
X152559D03*
X163779D03*
X156299Y1217322D03*
Y1209842D03*
X152559D03*
X163779D03*
Y1217322D03*
X152559D03*
Y1228543D03*
X160039Y1224803D03*
X152559D03*
X156299Y1232283D03*
Y1236023D03*
X163779D03*
Y1232283D03*
Y1224803D03*
X156299D03*
Y1228543D03*
X163779D03*
X152559Y1250984D03*
Y1254724D03*
X160039D03*
X156299Y1243503D03*
X160039Y1239763D03*
X152559D03*
Y1243503D03*
X160039D03*
X163779Y1239763D03*
X156299Y1247243D03*
X163779Y1243503D03*
X160039Y1250984D03*
X163779Y1247243D03*
X152559Y1258465D03*
X160039D03*
X159552Y1348187D03*
X155192D03*
X159552Y1360099D03*
X155192D03*
X159552Y1372385D03*
Y1384297D03*
X155192D03*
Y1372385D03*
X159552Y1396583D03*
X155192D03*
X159552Y1408495D03*
X155192D03*
X174998Y1071455D03*
X182479D03*
X178740Y1090157D03*
X174999D03*
X171259D03*
X182480D03*
X178740Y1093897D03*
Y1097637D03*
X174999Y1101377D03*
X169389Y1106988D03*
X171259Y1093897D03*
X174999Y1105117D03*
X182480Y1101377D03*
Y1105117D03*
X174999Y1108858D03*
X178740D03*
X176870Y1114468D03*
Y1118208D03*
Y1121948D03*
X178740Y1112598D03*
X173129Y1110728D03*
X169389D03*
X180610Y1114468D03*
Y1118208D03*
Y1121948D03*
X182480Y1112598D03*
Y1108858D03*
X180610Y1136909D03*
X173129Y1133169D03*
X169389D03*
X176870Y1140649D03*
Y1125688D03*
Y1129429D03*
Y1133169D03*
Y1136909D03*
X173129Y1140649D03*
X169389D03*
X180610D03*
Y1125688D03*
Y1129429D03*
Y1133169D03*
Y1148129D03*
X173129Y1144389D03*
X169389D03*
X173129Y1148129D03*
Y1155610D03*
Y1151870D03*
X180610Y1155610D03*
Y1151870D03*
Y1144389D03*
X176870Y1170570D03*
X173129Y1159350D03*
Y1166830D03*
Y1170570D03*
X180610Y1166830D03*
Y1159350D03*
Y1174310D03*
Y1181791D03*
X173129Y1174310D03*
Y1178051D03*
Y1181791D03*
X171259Y1187401D03*
X174999D03*
X180610Y1178051D03*
X167519Y1183661D03*
X178740Y1187401D03*
X182480D03*
X176870Y1185531D03*
X173129D03*
X167519Y1187401D03*
X171259Y1202362D03*
Y1194881D03*
X174999Y1202362D03*
Y1194881D03*
X167519Y1191141D03*
X178740D03*
Y1194881D03*
Y1198621D03*
Y1202362D03*
X182480Y1191141D03*
Y1198621D03*
Y1202362D03*
X174999Y1198621D03*
Y1191141D03*
X167519Y1194881D03*
X171259Y1198621D03*
Y1191141D03*
X167519Y1202362D03*
X171259Y1209842D03*
X174999Y1217322D03*
X171259Y1221062D03*
X174999D03*
X171259Y1217322D03*
X167519Y1206102D03*
X178740D03*
Y1209842D03*
Y1213582D03*
Y1221062D03*
X182480D03*
X178740Y1217322D03*
X182480Y1206102D03*
Y1209842D03*
Y1213582D03*
Y1217322D03*
X167519Y1209842D03*
X171259Y1213582D03*
Y1206102D03*
X174999D03*
X167519Y1217322D03*
X174999Y1213582D03*
X178740Y1228543D03*
X171259Y1224803D03*
Y1228543D03*
X178740Y1224803D03*
Y1232283D03*
Y1236023D03*
X171259Y1232283D03*
X174999Y1224803D03*
X171259Y1236023D03*
X182480Y1224803D03*
X167519D03*
Y1254724D03*
X182480Y1243503D03*
X171259Y1250984D03*
X174999Y1247243D03*
Y1239763D03*
X171259D03*
X167519D03*
Y1243503D03*
Y1250984D03*
X178740Y1247243D03*
X182480Y1254724D03*
Y1250984D03*
X171259Y1247243D03*
X174999Y1250984D03*
X171259Y1243503D03*
X174999Y1254724D03*
X178740Y1243503D03*
X175000Y1258465D03*
X182480D03*
X167519D03*
X167432Y1348187D03*
X171792D03*
X179672D03*
X167432Y1360099D03*
X171792D03*
X179672D03*
X167432Y1384297D03*
Y1372385D03*
X171792Y1384297D03*
Y1372385D03*
X179672Y1384297D03*
Y1372385D03*
X171792Y1396583D03*
X179672D03*
X167432D03*
Y1408495D03*
X171792D03*
X179672D03*
X197439Y1071455D03*
X189959D03*
X193700Y1090157D03*
X189960D03*
X186220D03*
X197440D03*
X193700Y1093897D03*
X189960Y1101377D03*
X186220Y1097637D03*
X189960Y1105117D03*
X186220Y1093897D03*
X193700Y1097637D03*
X197440Y1101377D03*
Y1105117D03*
X189960Y1093897D03*
X195570Y1121948D03*
X191830Y1118208D03*
X188090D03*
X184350D03*
X191830Y1121948D03*
X188090D03*
X184350D03*
X195570Y1118208D03*
X186220Y1108858D03*
X189960D03*
X193700D03*
X197440D03*
X191830Y1125688D03*
X188090D03*
X184350D03*
X188090Y1129429D03*
X184350D03*
X188090Y1133169D03*
X184350D03*
X188090Y1136909D03*
Y1140649D03*
X184350D03*
X195570Y1133169D03*
Y1129429D03*
Y1125688D03*
Y1136909D03*
X188090Y1144389D03*
Y1151870D03*
X191830Y1155610D03*
Y1148129D03*
X195570Y1151869D03*
Y1144389D03*
X188090Y1159350D03*
Y1170570D03*
X191830Y1166830D03*
X195570Y1159350D03*
Y1170570D03*
X188090Y1185531D03*
X195570Y1189271D03*
X191830Y1181791D03*
Y1174310D03*
X195570Y1185531D03*
Y1178051D03*
X188090Y1196751D03*
Y1200491D03*
Y1204232D03*
X191830D03*
Y1196751D03*
Y1200491D03*
X184350Y1193011D03*
Y1196751D03*
X195570Y1200491D03*
Y1196751D03*
Y1193011D03*
Y1204232D03*
X186220Y1198621D03*
X193700Y1209842D03*
X191830Y1207972D03*
X189960Y1209842D03*
X195570Y1207972D03*
X193700Y1213582D03*
X191830Y1219192D03*
X186220Y1221062D03*
X189960D03*
X193700D03*
X197440D03*
X186220Y1206102D03*
Y1209842D03*
Y1213582D03*
X197440Y1209842D03*
X186220Y1224803D03*
X193700Y1228543D03*
X197440Y1224803D03*
X193700Y1232283D03*
X186220D03*
X189960Y1224803D03*
X193700Y1236023D03*
X186220D03*
Y1228543D03*
X193700Y1224803D03*
X197440Y1239763D03*
Y1243503D03*
X193700Y1239763D03*
X186220D03*
X189960Y1243503D03*
X197440Y1254724D03*
Y1250984D03*
X193700Y1247243D03*
Y1243503D03*
X189960Y1254724D03*
Y1250984D03*
X186220Y1247243D03*
Y1243503D03*
X189960Y1258465D03*
X197441D03*
X184032Y1348187D03*
X191912D03*
X196272D03*
X184032Y1360099D03*
X196272D03*
X191912D03*
X184032Y1384297D03*
Y1372385D03*
X196272Y1384297D03*
Y1372385D03*
X191912Y1384297D03*
Y1372385D03*
X184032Y1396583D03*
X191912D03*
X196272D03*
X184032Y1408495D03*
X191912D03*
X196272D03*
X204920Y1071455D03*
X212400D03*
X204921Y1090157D03*
X212401D03*
X208661D03*
X201181D03*
X204921Y1101377D03*
X208661Y1097637D03*
X201181D03*
X204921Y1105117D03*
X212401Y1101377D03*
Y1105117D03*
X201181Y1093897D03*
X208661D03*
X199311Y1118208D03*
Y1121948D03*
X206791Y1118208D03*
X203051D03*
Y1121948D03*
X206791D03*
X210531Y1118208D03*
X214271Y1110728D03*
X210531Y1121948D03*
X214271Y1118208D03*
Y1121948D03*
X201181Y1108858D03*
X204921D03*
X208661D03*
X212401D03*
X199311Y1140649D03*
X203051D03*
X206791D03*
X199311Y1125688D03*
X203051D03*
X206791D03*
Y1133169D03*
X203051D03*
X199311D03*
X210531D03*
Y1140649D03*
X214271D03*
Y1125688D03*
X210531D03*
X214271Y1133169D03*
X203051Y1148129D03*
X199311D03*
X206791D03*
X214271D03*
X210531D03*
X199311Y1155610D03*
X206791D03*
X214271D03*
X206791Y1166830D03*
X203051Y1159350D03*
X199311Y1166830D03*
X203051Y1170570D03*
X214271Y1166830D03*
X210531Y1159350D03*
Y1170570D03*
X206791Y1181791D03*
X203051D03*
X199311D03*
X206791Y1189271D03*
X203051D03*
X199311D03*
X214271Y1181791D03*
X210531D03*
X214271Y1189271D03*
X210531D03*
X199311Y1174310D03*
X206791D03*
X214271D03*
X206791Y1196751D03*
X203051D03*
X199311D03*
Y1204232D03*
X203051D03*
X206791D03*
X214271Y1196751D03*
X210531D03*
Y1204232D03*
X214271D03*
X206791Y1207972D03*
X203051D03*
X199311D03*
X210531D03*
X214271D03*
X212401Y1221062D03*
X208661D03*
X204921D03*
X201181D03*
Y1224803D03*
X208661Y1228543D03*
X212401Y1224803D03*
X208661Y1232283D03*
X201181D03*
X204921Y1224803D03*
X201181Y1236023D03*
X208661D03*
Y1224803D03*
X201181Y1228543D03*
X212401Y1243503D03*
X208661Y1239763D03*
X204921Y1243503D03*
X208661D03*
X204921Y1250984D03*
X208661Y1247243D03*
X212401Y1254724D03*
X201181Y1243503D03*
X212401Y1250984D03*
X201181Y1247243D03*
X204921Y1254724D03*
X212401Y1258465D03*
X204921D03*
X204152Y1348187D03*
Y1360099D03*
Y1384297D03*
Y1372385D03*
Y1396583D03*
Y1408495D03*
X219880Y1071455D03*
X227361D03*
X227362Y1090157D03*
X223622D03*
X219881D03*
X231102D03*
X216141D03*
X223622Y1093897D03*
X231102D03*
Y1097637D03*
X227362Y1101377D03*
Y1105117D03*
X219881Y1101377D03*
Y1105117D03*
X223622Y1097637D03*
X216141D03*
Y1093897D03*
X225492Y1118208D03*
Y1121948D03*
X218011Y1118208D03*
X221751D03*
X218011Y1121948D03*
X221751D03*
X229232D03*
Y1118208D03*
Y1114468D03*
X216141Y1108858D03*
X219881D03*
X223622D03*
X227362D03*
X231102D03*
X225492Y1133169D03*
Y1140649D03*
Y1125688D03*
X218011Y1140649D03*
X221751D03*
X218011Y1125688D03*
X221751D03*
Y1133169D03*
X218011D03*
X229330Y1132677D03*
X229232Y1140649D03*
Y1125688D03*
X225492Y1148129D03*
X221751D03*
X218011D03*
X229232D03*
X221751Y1155610D03*
X229232D03*
X225492Y1170570D03*
Y1159350D03*
X218011Y1170570D03*
X221752Y1166830D03*
X218011Y1159350D03*
X229232Y1166830D03*
X225492Y1181791D03*
Y1189271D03*
X221751Y1181791D03*
X218011D03*
X221751Y1189271D03*
X218011D03*
X229232Y1181791D03*
Y1189271D03*
X221751Y1174310D03*
X229232D03*
X218011Y1204232D03*
X229232Y1196751D03*
Y1204232D03*
X225492Y1196751D03*
Y1204232D03*
X221751D03*
Y1196751D03*
X218011D03*
X225492Y1207972D03*
X221751D03*
X218011D03*
X229232D03*
X231102Y1221062D03*
X227362D03*
X219881Y1217322D03*
X223622Y1221062D03*
X219881D03*
X216141D03*
X231102Y1224803D03*
X227362D03*
X223622Y1232283D03*
X219881Y1224803D03*
X223622Y1236023D03*
X231102Y1232283D03*
Y1236023D03*
X216141Y1232283D03*
Y1236023D03*
Y1224803D03*
X223622D03*
Y1228543D03*
X216141D03*
X223622Y1239763D03*
X231102D03*
X227362Y1243503D03*
X219881D03*
X216141Y1239763D03*
X231102Y1243503D03*
Y1247243D03*
X223622Y1243503D03*
X216141Y1247243D03*
X223622D03*
X216141Y1243503D03*
X219881Y1250984D03*
Y1254724D03*
X227362D03*
Y1250984D03*
X219882Y1258465D03*
X227363D03*
X246062Y1075196D03*
X234841Y1071454D03*
X242321Y1071455D03*
X238582Y1075196D03*
X234841Y1075195D03*
X242321Y1075196D03*
X234842Y1090157D03*
X246062D03*
Y1078936D03*
X238582Y1090157D03*
X242322Y1086417D03*
X234842Y1082677D03*
Y1086417D03*
X242322Y1090157D03*
X242321Y1078936D03*
X246061Y1082677D03*
X238581Y1082676D03*
X234841Y1078935D03*
X246061Y1086417D03*
X238581Y1086416D03*
X246062Y1097637D03*
Y1093897D03*
X242322Y1105117D03*
X234842Y1101377D03*
X238582Y1093897D03*
X242322Y1101377D03*
X234842Y1105117D03*
X236712Y1121948D03*
X240452D03*
X244192D03*
X234842Y1108858D03*
X238582D03*
X242322D03*
X246062D03*
X236712Y1133464D03*
X240452Y1133169D03*
X236712Y1140649D03*
X240452D03*
X236712Y1125688D03*
X240452D03*
X244192Y1133169D03*
Y1140649D03*
Y1125688D03*
X236712Y1148129D03*
X240452D03*
X244192D03*
X240452Y1155610D03*
Y1166830D03*
X236712Y1170570D03*
Y1159350D03*
X244192Y1170570D03*
Y1159350D03*
X240452Y1181791D03*
X236712D03*
Y1189271D03*
X240452D03*
X244192Y1181791D03*
Y1189271D03*
X240452Y1174310D03*
Y1204232D03*
X236712D03*
Y1196751D03*
X240452D03*
X244192Y1204232D03*
Y1196751D03*
X240452Y1207972D03*
Y1211712D03*
X242322Y1221062D03*
X244192Y1211712D03*
Y1207972D03*
X236712D03*
X234842Y1221062D03*
X238582D03*
X246062Y1232283D03*
Y1236023D03*
X238582Y1232283D03*
X234842Y1228543D03*
Y1224803D03*
X238582Y1236023D03*
X242322Y1228543D03*
Y1224803D03*
X246062Y1239763D03*
X238582D03*
Y1247243D03*
X246062Y1243503D03*
Y1247243D03*
X238582Y1243503D03*
X234842Y1258465D03*
X242322D03*
X239383Y1348187D03*
X247263D03*
Y1360099D03*
X239383D03*
X247263Y1384297D03*
Y1372385D03*
X239383Y1384297D03*
Y1372385D03*
X253543Y1075196D03*
X261023D03*
X249802Y1071455D03*
X257282D03*
X249802Y1075196D03*
X257282D03*
X253543Y1090157D03*
X249803D03*
Y1086417D03*
X253543Y1078936D03*
X257283Y1090157D03*
Y1086417D03*
X261023Y1090157D03*
Y1078936D03*
X249802D03*
X261022Y1086417D03*
X253542Y1082676D03*
X257282Y1078936D03*
X253542Y1086416D03*
X261022Y1082677D03*
X249803Y1105117D03*
X253543Y1093897D03*
Y1097637D03*
X257283Y1105117D03*
X261023Y1093897D03*
Y1097637D03*
X249802D03*
X257282D03*
X249802Y1093897D03*
X257282D03*
X255413Y1121948D03*
X251673D03*
X247933D03*
X262893D03*
X259153D03*
X249803Y1108858D03*
X253543D03*
X257283D03*
X261023D03*
X247933Y1133169D03*
X251673D03*
X255413D03*
X247933Y1140649D03*
X251673D03*
X255413D03*
X247933Y1125688D03*
X251673D03*
X255413D03*
X259153Y1133169D03*
X262893D03*
Y1140649D03*
X259153Y1125688D03*
X262893D03*
X259153Y1140649D03*
Y1148129D03*
X262893D03*
Y1155610D03*
X247933Y1148129D03*
X251673D03*
X255413D03*
X247933Y1155610D03*
X255413D03*
X262893Y1166830D03*
X251673Y1170570D03*
X255413Y1166830D03*
X247933D03*
X251673Y1159350D03*
X259153D03*
Y1170570D03*
X247933Y1181791D03*
X251673D03*
X255413D03*
X247933Y1189271D03*
X251673D03*
X255413D03*
X262893D03*
Y1174310D03*
X259153Y1181791D03*
X262893D03*
X259153Y1189271D03*
X255413Y1174310D03*
X247933D03*
Y1204232D03*
X255413D03*
X251673D03*
X247933Y1196751D03*
X251673D03*
X255413D03*
X259153Y1204232D03*
X262893D03*
X259153Y1196751D03*
X262893D03*
X247933Y1207972D03*
X251673D03*
X255413Y1211712D03*
Y1207972D03*
X262893D03*
X259153D03*
X262893Y1211712D03*
X259153D03*
X249803Y1228543D03*
X257283D03*
X249803Y1224803D03*
X253543Y1236023D03*
X257283Y1224803D03*
X261023Y1236023D03*
X253543Y1232283D03*
X261023D03*
X257283Y1239763D03*
X261023Y1243503D03*
Y1247243D03*
X253543D03*
Y1243503D03*
X249803Y1258465D03*
X257283D03*
X263863Y1348187D03*
X259503D03*
X251623D03*
X263863Y1360099D03*
X259503D03*
X251623D03*
X263863Y1384297D03*
Y1372385D03*
X259503Y1384297D03*
Y1372385D03*
X251623D03*
Y1384297D03*
X263863Y1396583D03*
X259503D03*
X251623D03*
X263863Y1408495D03*
X259503D03*
X251623D03*
X279723Y1071455D03*
X264762D03*
X272243D03*
X268503Y1075196D03*
X275984D03*
X279723D03*
X264762D03*
X272243D03*
X279724Y1090157D03*
X272244Y1082677D03*
X275984Y1090157D03*
X272244Y1086417D03*
X268503Y1078936D03*
Y1090157D03*
X264763Y1086417D03*
X272244Y1090157D03*
X264763D03*
X275982Y1082677D03*
Y1086417D03*
X268502Y1082676D03*
X272243Y1078936D03*
X268502Y1086416D03*
X279723Y1078936D03*
X264762D03*
X268503Y1093897D03*
Y1097637D03*
X272244Y1105117D03*
X279724D03*
X275984Y1093897D03*
X264763Y1105117D03*
X274114Y1118208D03*
X270373D03*
X266633Y1121948D03*
X270373D03*
X277854Y1118208D03*
X264763Y1108858D03*
X268503D03*
X272244D03*
X275984D03*
X279724D03*
X274114Y1125688D03*
X270373Y1136909D03*
X266633Y1133169D03*
X270373D03*
X266633Y1140649D03*
X270373Y1125688D03*
Y1129429D03*
X266633Y1125688D03*
X270373Y1140649D03*
X277854Y1136909D03*
Y1140649D03*
X274114Y1155610D03*
Y1151869D03*
Y1148129D03*
X266633D03*
X270373Y1144389D03*
Y1148129D03*
Y1151869D03*
X277854Y1144389D03*
Y1148129D03*
Y1151870D03*
X270373Y1155610D03*
X274114Y1166830D03*
Y1159350D03*
Y1170570D03*
X266633Y1181791D03*
X270373Y1189271D03*
X277854Y1178051D03*
Y1189271D03*
Y1185531D03*
X270373Y1174310D03*
X277854Y1181791D03*
X274114D03*
Y1174310D03*
X266633Y1189271D03*
X270373Y1178051D03*
Y1185531D03*
X274114Y1196751D03*
X270393Y1196732D03*
X270373Y1204232D03*
X266633D03*
X270373Y1200491D03*
X266633Y1196751D03*
X270373Y1193011D03*
X277854D03*
X274114Y1207972D03*
X270373Y1211712D03*
X266633Y1207972D03*
Y1211712D03*
X270373Y1207972D03*
X277854Y1211712D03*
X279724Y1221062D03*
X275984D03*
X272244D03*
X268503D03*
X279724Y1224803D03*
X272244D03*
X268503Y1236023D03*
Y1232283D03*
X272244Y1228543D03*
X264763Y1224803D03*
X275984Y1232283D03*
Y1236023D03*
X264763Y1228543D03*
X279724D03*
X268503Y1243503D03*
Y1247243D03*
X275984Y1243503D03*
Y1247243D03*
X268503Y1239763D03*
X279724Y1258465D03*
X264763D03*
X272244D03*
X276103Y1348187D03*
X271743D03*
X276103Y1360099D03*
X271743D03*
X276103Y1384297D03*
Y1372385D03*
X271743Y1384297D03*
Y1372385D03*
X276103Y1396583D03*
X271743D03*
Y1408495D03*
X276103D03*
X294684Y1071455D03*
X290944Y1075196D03*
X287203Y1071455D03*
X283464Y1075196D03*
X287203D03*
X294684D03*
X287204Y1090157D03*
X283464Y1078936D03*
Y1090157D03*
X290943D03*
Y1086417D03*
X287203Y1078936D03*
X290943Y1082677D03*
X283463Y1082676D03*
Y1086416D03*
X294684Y1078936D03*
X290944Y1093897D03*
X287204Y1101377D03*
Y1105117D03*
X294685D03*
X294684Y1120078D03*
Y1112598D03*
X283464Y1108858D03*
X287204D03*
X290944D03*
X294685D03*
X290944Y1112598D03*
Y1116338D03*
Y1120078D03*
Y1123818D03*
X281594Y1140649D03*
Y1136909D03*
X290944Y1127558D03*
Y1131299D03*
Y1135039D03*
Y1138779D03*
X281594Y1148129D03*
Y1155610D03*
Y1151869D03*
X285334D03*
X289074D03*
Y1155610D03*
X292814Y1151869D03*
Y1144389D03*
X281594Y1159350D03*
X289074Y1166830D03*
Y1170570D03*
Y1159350D03*
X281594Y1170570D03*
Y1166830D03*
X292814Y1159350D03*
Y1166830D03*
Y1181791D03*
X285334Y1185531D03*
X289074Y1174310D03*
Y1178051D03*
Y1185531D03*
X281594Y1189271D03*
Y1185531D03*
X285334Y1181791D03*
X281594Y1178051D03*
Y1174310D03*
X292814D03*
Y1189271D03*
X281594Y1196751D03*
Y1204232D03*
Y1193011D03*
X285334D03*
X290944Y1194881D03*
Y1198621D03*
Y1202362D03*
X294685Y1221062D03*
Y1217322D03*
X290944Y1221062D03*
X287204D03*
X283464D03*
X290944Y1206102D03*
Y1209842D03*
Y1213582D03*
Y1217322D03*
X294685Y1228543D03*
Y1224803D03*
X290944Y1232283D03*
Y1236023D03*
X283464Y1232283D03*
X287204Y1228543D03*
X283464Y1236023D03*
X287204Y1224803D03*
X283464Y1243503D03*
Y1239763D03*
X290944D03*
X283464Y1247243D03*
X294685Y1254724D03*
Y1250984D03*
X290944Y1247243D03*
Y1243503D03*
X294685Y1258465D03*
X287204D03*
X288343Y1348187D03*
X296223D03*
X283983D03*
X288343Y1360099D03*
X296223D03*
X283983D03*
X288343Y1384297D03*
Y1372385D03*
X296223Y1384297D03*
Y1372385D03*
X283983D03*
Y1384297D03*
X288343Y1396583D03*
X296223D03*
X283983D03*
X288343Y1408495D03*
X296223D03*
X283983D03*
X309645Y1071455D03*
X302165D03*
X298425Y1075196D03*
X305906D03*
X302164D03*
X309644D03*
X298424Y1090157D03*
X298426Y1078936D03*
X305906D03*
X305904Y1082677D03*
X302164Y1078936D03*
X305904Y1086417D03*
X309644Y1078936D03*
X298424Y1086416D03*
Y1082676D03*
X302165Y1105117D03*
X309645D03*
X298425Y1093897D03*
X305905D03*
X302165Y1123818D03*
X305904Y1108857D03*
X302165Y1116338D03*
X298425Y1108858D03*
X300295Y1140649D03*
X302165Y1131299D03*
X300295Y1148129D03*
Y1159350D03*
Y1166830D03*
X311515D03*
X307775Y1170570D03*
X300295Y1181791D03*
Y1174310D03*
Y1189271D03*
X311515Y1174310D03*
X307775Y1178051D03*
X311515Y1181791D03*
X307775Y1185531D03*
X311515Y1189271D03*
X298425Y1202362D03*
Y1194881D03*
X309645Y1198621D03*
X307775Y1193011D03*
X311515Y1196751D03*
X305905Y1198621D03*
X309645Y1202362D03*
X298425Y1209842D03*
X302165Y1221062D03*
X309645Y1217322D03*
Y1209842D03*
X305905Y1213582D03*
X309645D03*
Y1206102D03*
Y1221062D03*
X305905D03*
X298425Y1236023D03*
Y1232283D03*
X302165Y1228543D03*
Y1224803D03*
X305905Y1232283D03*
X309645Y1228543D03*
Y1224803D03*
X305905Y1236023D03*
X298425Y1239763D03*
X309645D03*
Y1254724D03*
X298425Y1247243D03*
X309645Y1250984D03*
X298425Y1243503D03*
X305905D03*
Y1247243D03*
X302165Y1254724D03*
Y1250984D03*
X309645Y1258465D03*
X302165D03*
X308463Y1348187D03*
X300583D03*
X308463Y1360099D03*
X300583D03*
X308463Y1372385D03*
X300583D03*
Y1384297D03*
X308463D03*
Y1396583D03*
X300583D03*
X308463Y1408495D03*
X300583D03*
X317125Y1071455D03*
X320866Y1075196D03*
X313386D03*
X317124D03*
X320866Y1078936D03*
X313384Y1090157D03*
X313386Y1078936D03*
X328347Y1082677D03*
Y1090158D03*
X324606Y1078936D03*
X317124D03*
X313384Y1082677D03*
Y1086417D03*
X313385Y1093897D03*
X328347Y1101378D03*
Y1116339D03*
Y1123819D03*
Y1108859D03*
X313385Y1108858D03*
X328347Y1131300D03*
X318996Y1140649D03*
Y1155610D03*
Y1148129D03*
X322736Y1170570D03*
X318996D03*
Y1185531D03*
Y1178051D03*
X322736D03*
Y1185531D03*
X328347Y1198621D03*
X322736Y1193011D03*
X320866Y1202362D03*
X318996Y1193011D03*
X326416D03*
X324606Y1202362D03*
X328347Y1206102D03*
Y1221062D03*
Y1213582D03*
X320866Y1209842D03*
X313385Y1221062D03*
X320866Y1206102D03*
Y1232283D03*
X313385D03*
X317125Y1228543D03*
Y1224803D03*
X313385Y1236023D03*
X328347Y1228543D03*
Y1239762D03*
Y1247243D03*
X324606Y1250984D03*
X317125Y1254724D03*
X324606Y1239763D03*
X313385Y1247243D03*
X317125Y1250984D03*
X320866Y1239763D03*
X313385Y1243503D03*
X317125Y1258465D03*
X320703Y1348187D03*
X312823D03*
X325063D03*
X320703Y1360099D03*
X312823D03*
X325063D03*
X320703Y1372385D03*
Y1384297D03*
X312823Y1372385D03*
Y1384297D03*
X325063Y1372385D03*
Y1384297D03*
Y1396583D03*
X320703D03*
X312823D03*
X320703Y1408495D03*
X312823D03*
X325063D03*
X318448Y1750941D03*
Y1760941D03*
X318348Y1796941D03*
Y1806941D03*
X337303Y1348187D03*
X332943D03*
Y1360099D03*
X337303D03*
X332943Y1384297D03*
Y1372385D03*
X337303D03*
Y1384297D03*
X332943Y1396583D03*
X337303D03*
X332943Y1408495D03*
X337303D03*
X349543Y1348187D03*
X357423D03*
X345183D03*
X349543Y1360099D03*
X357423D03*
X345183D03*
Y1372385D03*
Y1384297D03*
X349543D03*
Y1372385D03*
X357423D03*
Y1384297D03*
X345183Y1396583D03*
X349543D03*
X357423D03*
X345183Y1408495D03*
X349543D03*
X357423D03*
X369663Y1348187D03*
X361783D03*
X369663Y1360099D03*
X361783D03*
X369663Y1372385D03*
Y1384297D03*
X361783D03*
Y1372385D03*
X369663Y1396583D03*
X361783D03*
X369663Y1408495D03*
X361783D03*
X458282Y1348187D03*
X446042D03*
X458282Y1360099D03*
X446042D03*
X458282Y1372385D03*
X446042D03*
X458282Y1384297D03*
X446042D03*
X458282Y1396583D03*
Y1408495D03*
X470522Y1348187D03*
Y1360099D03*
Y1384297D03*
Y1372385D03*
Y1396583D03*
Y1408495D03*
X482762Y1348187D03*
Y1360099D03*
Y1384297D03*
Y1372385D03*
Y1396583D03*
Y1408495D03*
X507242Y1348187D03*
X495002D03*
X507242Y1360099D03*
X495002D03*
Y1384297D03*
X507242D03*
X495002Y1372385D03*
X507242D03*
Y1396583D03*
X495002D03*
X507242Y1408495D03*
X495002D03*
X519482Y1348187D03*
Y1360099D03*
Y1384297D03*
Y1372385D03*
Y1396583D03*
Y1408495D03*
X531722Y1348187D03*
Y1360099D03*
Y1384297D03*
Y1372385D03*
Y1396583D03*
Y1408495D03*
X556202Y1348187D03*
X543962D03*
X556202Y1360099D03*
X543962D03*
Y1372385D03*
Y1384297D03*
X556202D03*
Y1372385D03*
Y1396583D03*
X543962D03*
X556202Y1408495D03*
X543962D03*
X568442Y1348187D03*
Y1360099D03*
Y1384297D03*
Y1372385D03*
Y1396583D03*
Y1408495D03*
X604035Y1080806D03*
Y1103247D03*
X600295D03*
Y1125688D03*
Y1133169D03*
Y1140649D03*
X604035Y1125688D03*
Y1133169D03*
Y1140649D03*
X600295Y1144389D03*
Y1151870D03*
X604035Y1144389D03*
Y1151870D03*
X600295Y1159350D03*
X604035D03*
X597795Y1170570D03*
X604034Y1174310D03*
X597795Y1178050D03*
X602165Y1183661D03*
Y1187401D03*
Y1202362D03*
Y1194881D03*
X598424Y1198622D03*
Y1191142D03*
X602165Y1191141D03*
Y1198621D03*
Y1217322D03*
Y1209842D03*
X598424Y1221063D03*
Y1213583D03*
Y1206103D03*
X602165Y1221062D03*
Y1206102D03*
Y1213582D03*
Y1224803D03*
Y1236023D03*
Y1232283D03*
Y1247243D03*
Y1239763D03*
X605386Y1728583D03*
Y1738583D03*
X605312Y1774624D03*
Y1784624D03*
X607775Y1077066D03*
X615256Y1106988D03*
X618996D03*
X615256Y1118208D03*
Y1121948D03*
X611516D03*
X607776D03*
X618996Y1114468D03*
X615256Y1125688D03*
X611516Y1129429D03*
X607776D03*
Y1136909D03*
X615256Y1140649D03*
X611516D03*
X607776D03*
X618996D03*
Y1144389D03*
Y1148129D03*
Y1151870D03*
Y1155610D03*
X607776Y1144389D03*
Y1148129D03*
Y1151870D03*
X615256Y1155610D03*
X611516D03*
X607776D03*
Y1159350D03*
X615256Y1166830D03*
X607775D03*
X611516Y1170570D03*
X607775D03*
X618996Y1159350D03*
Y1174310D03*
Y1178051D03*
X607775Y1174310D03*
Y1178051D03*
X611516Y1174310D03*
X615256D03*
X613386Y1183661D03*
X617126Y1187401D03*
Y1183661D03*
X613386Y1179921D03*
X620866Y1183661D03*
X609646D03*
X605905D03*
Y1187401D03*
X613386D03*
X609646D03*
X620866D03*
X613386Y1198621D03*
X609646Y1191141D03*
X613386D03*
X617126Y1198621D03*
X620866D03*
X617126Y1191141D03*
X620866D03*
X605905Y1202362D03*
Y1194881D03*
X609646Y1198621D03*
X605905Y1191141D03*
X613386Y1194881D03*
X605905Y1198621D03*
X609646Y1194881D03*
Y1202362D03*
X613386D03*
X620866D03*
Y1194881D03*
X613386Y1221062D03*
X609646D03*
Y1213582D03*
X613386D03*
X620866Y1206102D03*
X617126D03*
X620866Y1221062D03*
X617126D03*
X613386Y1206102D03*
X605905Y1217322D03*
Y1209842D03*
X609646Y1206102D03*
X613386Y1217322D03*
X605905Y1221062D03*
X609646Y1217322D03*
Y1209842D03*
X605905Y1206102D03*
Y1213582D03*
X620866Y1209842D03*
X613386D03*
X620866Y1217322D03*
X605905Y1224803D03*
Y1232283D03*
Y1236023D03*
X620866D03*
Y1232283D03*
X617126Y1224803D03*
X609646D03*
Y1228543D03*
X613386Y1232283D03*
Y1236023D03*
X620866Y1228543D03*
Y1224803D03*
X613386Y1228543D03*
Y1224803D03*
X617126Y1243503D03*
Y1239763D03*
X620866D03*
X609646Y1243503D03*
Y1239763D03*
X605905Y1247243D03*
X617126Y1250984D03*
X620866Y1243503D03*
Y1247243D03*
X609646Y1254724D03*
X613386Y1247243D03*
X617126Y1254724D03*
X613386Y1243503D03*
X609646Y1250984D03*
X605905Y1239763D03*
X617126Y1258465D03*
X609646D03*
X632085Y1071455D03*
X626476Y1092027D03*
X635827Y1090157D03*
X628346D03*
X632086D03*
X630216Y1099507D03*
X626476Y1106988D03*
X622736D03*
X626476Y1095767D03*
X630216Y1103247D03*
X635827Y1093897D03*
X632086Y1101377D03*
Y1105117D03*
X628346Y1093897D03*
X635827Y1097637D03*
X633957Y1110728D03*
X630216D03*
X626476D03*
X622736Y1114468D03*
X630216Y1118208D03*
X626476D03*
X633957Y1114468D03*
Y1118208D03*
Y1121948D03*
X635827Y1108858D03*
X632086D03*
X633957Y1140649D03*
Y1125688D03*
Y1129429D03*
Y1133169D03*
Y1136909D03*
X630216Y1140649D03*
X626476D03*
X622736D03*
Y1129429D03*
X630216Y1144389D03*
X626476D03*
X630216Y1148129D03*
Y1155610D03*
Y1151870D03*
Y1159350D03*
Y1166830D03*
Y1170570D03*
X633957D03*
Y1185531D03*
X628346Y1183661D03*
X630216Y1174310D03*
Y1178051D03*
Y1181791D03*
X632086Y1187401D03*
X628346D03*
X624606Y1183661D03*
X635827Y1187401D03*
X624606D03*
Y1191141D03*
X632086Y1202362D03*
X628346D03*
X632086Y1194881D03*
X628346D03*
X635827Y1191141D03*
Y1194881D03*
Y1198621D03*
Y1202362D03*
X628346Y1191141D03*
X624606Y1194881D03*
X632086Y1191141D03*
X628346Y1198621D03*
X624606Y1202362D03*
X632086Y1198621D03*
X624606Y1206102D03*
X628346Y1209842D03*
Y1217322D03*
Y1221062D03*
X632086D03*
Y1217322D03*
X635827Y1221062D03*
Y1206102D03*
Y1209842D03*
Y1213582D03*
Y1217322D03*
X628346Y1206102D03*
X632086D03*
X624606Y1217322D03*
X628346Y1213582D03*
X632086D03*
X624606Y1209842D03*
X632086Y1224803D03*
X624606D03*
X628346Y1236023D03*
Y1232283D03*
X635827Y1236023D03*
Y1232283D03*
X628346Y1224803D03*
Y1228543D03*
X635827D03*
Y1224803D03*
X632086Y1247243D03*
Y1239763D03*
X628346D03*
Y1250984D03*
X624606Y1243503D03*
Y1239763D03*
Y1254724D03*
Y1250984D03*
X632086Y1254724D03*
X635827Y1243503D03*
X632086Y1250984D03*
X635827Y1247243D03*
X628346Y1243503D03*
Y1247243D03*
X632087Y1258465D03*
X624606D03*
X631928Y1396583D03*
Y1408495D03*
X647046Y1071455D03*
X639566D03*
X643307Y1090157D03*
X639567D03*
X650787D03*
X647047D03*
X639567Y1101377D03*
Y1105117D03*
X647047D03*
Y1101377D03*
X650787Y1097637D03*
X643307D03*
Y1093897D03*
X650787D03*
X647047D03*
X637697Y1114468D03*
X648917Y1118208D03*
X645177D03*
X641437D03*
X637697D03*
X648917Y1121948D03*
X645177D03*
X641437D03*
X637697D03*
Y1110728D03*
X652657Y1118208D03*
Y1121948D03*
X650787Y1108858D03*
X647047D03*
X643307D03*
X639567D03*
X641437Y1133169D03*
X637697D03*
X645177Y1136909D03*
X637697D03*
X645177Y1140649D03*
X641437D03*
X652657Y1133169D03*
Y1129429D03*
Y1125688D03*
Y1136909D03*
X637697Y1140649D03*
X648917Y1125688D03*
X645177D03*
X641437D03*
X637697D03*
X645177Y1129429D03*
X641437D03*
X637697D03*
X645177Y1133169D03*
X637697Y1155610D03*
Y1151870D03*
X645177Y1144389D03*
X637697D03*
Y1148129D03*
X645177Y1151870D03*
X648917Y1155610D03*
Y1148129D03*
X652657Y1151869D03*
Y1144389D03*
X645177Y1170570D03*
X637697Y1166830D03*
X645177Y1159350D03*
X637697D03*
X648917Y1166830D03*
X652657Y1159350D03*
Y1170570D03*
X637697Y1189271D03*
X645177Y1185531D03*
X637697D03*
Y1178051D03*
Y1174310D03*
Y1181791D03*
X652657Y1189271D03*
X648917Y1181791D03*
Y1174310D03*
X652657Y1185531D03*
Y1178051D03*
Y1193011D03*
Y1204232D03*
X637697Y1193011D03*
X645177Y1196751D03*
Y1200491D03*
X641437D03*
Y1204232D03*
X645177D03*
X648917D03*
Y1196751D03*
Y1200491D03*
X641437Y1193011D03*
Y1196751D03*
X652657Y1200491D03*
Y1196751D03*
Y1211712D03*
X648917Y1219192D03*
X641437D03*
Y1211712D03*
X645177D03*
X648917D03*
Y1207972D03*
X645177D03*
X641437D03*
X652657D03*
X639567Y1221062D03*
X647047D03*
X643307D03*
X650787D03*
X639567Y1224803D03*
X643307Y1236023D03*
Y1232283D03*
X650787Y1236023D03*
X647047Y1224803D03*
X650787Y1232283D03*
X643307Y1224803D03*
Y1228543D03*
X650787D03*
Y1224803D03*
X639567Y1243503D03*
X647047D03*
X650787Y1239763D03*
X643307D03*
X639567Y1250984D03*
Y1254724D03*
X650787Y1247243D03*
Y1243503D03*
X647047Y1254724D03*
Y1250984D03*
X643307Y1247243D03*
Y1243503D03*
X647047Y1258465D03*
X639567D03*
X644168Y1384297D03*
Y1372385D03*
Y1396583D03*
Y1408495D03*
X669487Y1071455D03*
X662007D03*
X654526D03*
X669488Y1090157D03*
X665748D03*
X654527D03*
X658268D03*
X662008D03*
Y1101377D03*
X665748Y1093897D03*
X658268D03*
X654527Y1105117D03*
Y1101377D03*
X662008Y1105117D03*
X658268Y1097637D03*
X669488Y1101377D03*
Y1105117D03*
X665748Y1097637D03*
X656398Y1118208D03*
Y1121948D03*
X663878Y1118208D03*
X660138D03*
Y1121948D03*
X663878D03*
X667618Y1118208D03*
Y1121948D03*
X669488Y1108858D03*
X665748D03*
X662008D03*
X658268D03*
X654527D03*
X656398Y1140649D03*
X660138D03*
X663878D03*
X656398Y1125688D03*
X660138D03*
X663878D03*
Y1133169D03*
X660138D03*
X656398D03*
X667618D03*
Y1140649D03*
Y1125688D03*
Y1148129D03*
X660138D03*
X656398D03*
X663878D03*
X656398Y1155610D03*
X663878D03*
Y1166830D03*
X660138Y1159350D03*
X656398Y1166830D03*
X660138Y1170570D03*
X667618Y1159350D03*
Y1170570D03*
X663878Y1181791D03*
X660138D03*
X656398D03*
X663878Y1189271D03*
X660138D03*
X656398D03*
X667618Y1181791D03*
Y1189271D03*
X656398Y1174310D03*
X663878D03*
Y1196751D03*
X660138D03*
X656398D03*
Y1204232D03*
X660138D03*
X663878D03*
X667618Y1196751D03*
Y1204232D03*
X663878Y1207972D03*
X660138D03*
X656398D03*
X667618D03*
X654527Y1221062D03*
X658268D03*
X662008D03*
X665748D03*
X669488D03*
X654527Y1224803D03*
X658268Y1236023D03*
Y1232283D03*
X662008Y1224803D03*
X665748Y1236023D03*
Y1232283D03*
X669488Y1224803D03*
X665748D03*
X658268D03*
X665748Y1228543D03*
X658268D03*
X654527Y1239763D03*
Y1243503D03*
X665748Y1239763D03*
X669488Y1243503D03*
X662008D03*
Y1254724D03*
X665748Y1247243D03*
X669488Y1250984D03*
X658268Y1247243D03*
X662008Y1250984D03*
X665748Y1243503D03*
X669488Y1254724D03*
X658268Y1243503D03*
X654527Y1254724D03*
Y1250984D03*
X662008Y1258465D03*
X669488D03*
X654528D03*
X668648Y1348187D03*
X656408D03*
X668648Y1360099D03*
X656408D03*
Y1384297D03*
Y1372385D03*
X668648D03*
Y1384297D03*
Y1396583D03*
X656408D03*
X668648Y1408495D03*
X656408D03*
X684448Y1071455D03*
X676967D03*
X680709Y1090157D03*
X676968D03*
X684449D03*
X673228D03*
X676968Y1105117D03*
X684449Y1101377D03*
Y1105117D03*
X680709Y1093897D03*
X676968Y1101377D03*
X680709Y1097637D03*
X673228D03*
Y1093897D03*
X682579Y1118208D03*
Y1121948D03*
X671358Y1118208D03*
X675098D03*
X678838D03*
X675098Y1121948D03*
X678838D03*
X671358D03*
X684449Y1108858D03*
X680709D03*
X676968D03*
X673228D03*
X682579Y1133169D03*
Y1140649D03*
Y1125688D03*
X671358Y1140649D03*
X675098D03*
X678838D03*
X675098Y1125688D03*
X671358D03*
X678838D03*
Y1133169D03*
X675098D03*
X671358D03*
X682579Y1148129D03*
X678838D03*
X675098D03*
X671358D03*
Y1155610D03*
X678838D03*
X682579Y1170570D03*
Y1159350D03*
X675098Y1170570D03*
X678839Y1166830D03*
X671358D03*
X675098Y1159350D03*
Y1181791D03*
X671358D03*
X678838Y1189271D03*
X675098D03*
X671358D03*
X682579Y1181791D03*
Y1189271D03*
X678838Y1181791D03*
X671358Y1174310D03*
X678838D03*
X682579Y1196751D03*
Y1204232D03*
X678838D03*
Y1196751D03*
X675098D03*
X671358D03*
Y1204232D03*
X675098D03*
X682579Y1207972D03*
X678838Y1219192D03*
Y1207972D03*
X675098D03*
X671358D03*
X673228Y1221062D03*
X676968D03*
X680709D03*
X684449D03*
X673228Y1236023D03*
Y1232283D03*
X676968Y1224803D03*
X680709Y1236023D03*
Y1232283D03*
X684449Y1224803D03*
X673228Y1228543D03*
X680709Y1224803D03*
X673228D03*
X680709Y1228543D03*
X673228Y1239763D03*
X680709D03*
X676968Y1243503D03*
X684449D03*
X673228D03*
X680709Y1247243D03*
X673228D03*
X684449Y1254724D03*
Y1250984D03*
X676968Y1254724D03*
Y1250984D03*
X680709Y1243503D03*
X684450Y1258465D03*
X676969D03*
X680888Y1348187D03*
Y1360099D03*
Y1372385D03*
Y1384297D03*
Y1396583D03*
Y1408495D03*
X695669Y1075196D03*
X699408Y1071455D03*
X691928Y1071454D03*
X699408Y1075196D03*
X691928Y1075195D03*
X688189Y1090157D03*
X691929Y1082677D03*
Y1086417D03*
X695669Y1090157D03*
X699409D03*
Y1086417D03*
X691929Y1090157D03*
X691928Y1078935D03*
X699408Y1078936D03*
X695668Y1086416D03*
Y1082676D03*
X688189Y1097637D03*
X695669Y1093897D03*
X688189D03*
X699409Y1105117D03*
X691929Y1101377D03*
X699409D03*
X691929Y1105117D03*
X693799Y1121948D03*
X697539D03*
X701279D03*
X686319D03*
Y1118208D03*
Y1114468D03*
X699409Y1108858D03*
X695669D03*
X691929D03*
X688189D03*
X693799Y1133464D03*
X697539Y1133169D03*
X686417Y1132677D03*
X693799Y1140649D03*
X697539D03*
X693799Y1125688D03*
X697539D03*
X701279D03*
Y1140649D03*
Y1133169D03*
X686319Y1140649D03*
Y1125688D03*
X697539Y1148129D03*
X701279D03*
X693799D03*
X697539Y1155610D03*
X686319Y1148129D03*
Y1155610D03*
X697539Y1166830D03*
X693799Y1170570D03*
Y1159350D03*
X701279D03*
Y1170570D03*
X686319Y1166830D03*
X693799Y1181791D03*
Y1189271D03*
X697539D03*
X701279D03*
Y1181791D03*
X697539D03*
Y1174310D03*
X686319Y1181791D03*
Y1189271D03*
Y1174310D03*
X697539Y1204232D03*
X693799D03*
Y1196751D03*
X697539D03*
X701279D03*
Y1204232D03*
X686319Y1196751D03*
Y1204232D03*
X693799Y1207972D03*
X697539D03*
Y1211712D03*
X701279Y1207972D03*
Y1211712D03*
X686319Y1207972D03*
X695669Y1221062D03*
X699409D03*
X691929D03*
X688189D03*
Y1236023D03*
Y1232283D03*
X691929Y1224803D03*
Y1228543D03*
X699409Y1224803D03*
Y1228543D03*
X695669Y1236023D03*
Y1232283D03*
X688189Y1224803D03*
Y1239763D03*
X695669D03*
X688189Y1247243D03*
Y1243503D03*
X695669Y1247243D03*
Y1243503D03*
X699409Y1258465D03*
X691929D03*
X693128Y1348187D03*
Y1360099D03*
Y1372385D03*
Y1384297D03*
Y1396583D03*
Y1408495D03*
X703149Y1075196D03*
X718110D03*
X710630D03*
X714369Y1071455D03*
X706889D03*
Y1075196D03*
X714369D03*
X710630Y1078936D03*
X706890Y1086417D03*
Y1090157D03*
X718110Y1078936D03*
X714370Y1086417D03*
Y1090157D03*
X710630D03*
X718110D03*
X703149Y1078936D03*
Y1090157D03*
X706889Y1078936D03*
X718109Y1086417D03*
X714369Y1078936D03*
X703148Y1082677D03*
X710629Y1086416D03*
X703148Y1086417D03*
X718109Y1082677D03*
X710629Y1082676D03*
X706890Y1105117D03*
X714370D03*
X710630Y1097637D03*
Y1093897D03*
X718110Y1097637D03*
Y1093897D03*
X703149D03*
Y1097637D03*
X714369D03*
X706889Y1093897D03*
X714369D03*
X706889Y1097637D03*
X716240Y1121948D03*
X705020D03*
X708760D03*
X712500D03*
X718110Y1108858D03*
X714370D03*
X710630D03*
X706890D03*
X703149D03*
X716240Y1140649D03*
Y1125688D03*
Y1133169D03*
X712500Y1125688D03*
X708760D03*
X705020D03*
X712500Y1140649D03*
X708760D03*
X705020D03*
X712500Y1133169D03*
X708760D03*
X705020D03*
X716240Y1148129D03*
X712500D03*
X708760D03*
X705020D03*
X712500Y1155610D03*
X705020D03*
X716240Y1170570D03*
Y1159350D03*
X708760D03*
X705020Y1166830D03*
X712500D03*
X708760Y1170570D03*
X716240Y1189271D03*
Y1181791D03*
X712500Y1189271D03*
X708760D03*
X705020D03*
X712500Y1181791D03*
X708760D03*
X705020D03*
Y1174310D03*
X712500D03*
X716240Y1196751D03*
Y1204232D03*
X712500Y1196751D03*
X708760D03*
X705020D03*
X708760Y1204232D03*
X712500D03*
X705020D03*
X716240Y1211712D03*
Y1207972D03*
X712500D03*
Y1211712D03*
X708760Y1207972D03*
X705020D03*
X703149Y1221062D03*
X706890D03*
X710630D03*
X714370D03*
X718110D03*
X703149Y1236023D03*
Y1232283D03*
X710630Y1236023D03*
X718110D03*
Y1232283D03*
X710630D03*
X714370Y1224803D03*
Y1228543D03*
X706890Y1224803D03*
Y1228543D03*
X703149Y1239763D03*
X714370D03*
X718110Y1243503D03*
Y1247243D03*
X703149Y1243503D03*
X710630Y1247243D03*
Y1243503D03*
X703149Y1247243D03*
X714370Y1258465D03*
X706890D03*
X705368Y1348187D03*
X717608D03*
X705368Y1360099D03*
X717608D03*
X705368Y1372385D03*
Y1384297D03*
X717608Y1372385D03*
Y1384297D03*
Y1396583D03*
X705368D03*
X717608Y1408495D03*
X705368D03*
X725590Y1075196D03*
X733071D03*
X729330Y1071455D03*
X721849D03*
Y1075196D03*
X729330D03*
X729331Y1086417D03*
Y1082677D03*
X733071Y1090157D03*
X729331D03*
X725590D03*
X721850D03*
X725590Y1078936D03*
X721850Y1086417D03*
X725589Y1086416D03*
X733069Y1086417D03*
X721849Y1078936D03*
X729330D03*
X733069Y1082677D03*
X725589Y1082676D03*
X725590Y1097637D03*
X721850Y1105117D03*
X725590Y1093897D03*
X729331Y1105117D03*
X733071Y1093897D03*
X734941Y1118208D03*
X727460Y1121948D03*
X719980D03*
X723720D03*
X727460Y1118208D03*
X731201D03*
X733071Y1108858D03*
X729331D03*
X725590D03*
X721850D03*
X734941Y1140649D03*
Y1136909D03*
X727460Y1140649D03*
X723720Y1125688D03*
X719980D03*
X727460Y1129429D03*
Y1125688D03*
X723720Y1140649D03*
X719980D03*
X727460Y1133169D03*
X723720D03*
X719980D03*
X727460Y1136909D03*
X731201Y1125688D03*
X727460Y1151869D03*
Y1148129D03*
Y1144389D03*
X723720Y1148129D03*
X719980D03*
X731201D03*
Y1151869D03*
Y1155610D03*
X734941Y1151870D03*
Y1148129D03*
Y1144389D03*
X719980Y1155610D03*
X727460D03*
X731201Y1170570D03*
X719980Y1166830D03*
X731201Y1159350D03*
Y1166830D03*
X727460Y1185531D03*
X734941Y1181791D03*
Y1185531D03*
Y1189271D03*
Y1178051D03*
X727460Y1189271D03*
X723720Y1181791D03*
X719980D03*
Y1174310D03*
X727460Y1178051D03*
X723720Y1189271D03*
X719980D03*
X731201Y1174310D03*
Y1181791D03*
X727460Y1174310D03*
X719980Y1204232D03*
X727460D03*
X727480Y1196732D03*
X731201Y1196751D03*
X734941Y1193011D03*
X727460D03*
X723720Y1196751D03*
X719980D03*
X727460Y1200491D03*
X723720Y1204232D03*
X734941Y1211712D03*
X727460Y1207972D03*
X723720Y1211712D03*
Y1207972D03*
X719980Y1211712D03*
Y1207972D03*
X727460Y1211712D03*
X731201Y1207972D03*
X733071Y1221062D03*
X721850D03*
X725590D03*
X729331D03*
Y1224803D03*
Y1228543D03*
X733071Y1236023D03*
Y1232283D03*
X725590Y1236023D03*
Y1232283D03*
X721850Y1224803D03*
Y1228543D03*
X725590Y1239763D03*
X733071Y1247243D03*
X725590Y1243503D03*
X733071D03*
X725590Y1247243D03*
X729331Y1258465D03*
X721850D03*
X729848Y1348187D03*
Y1360099D03*
Y1372385D03*
Y1384297D03*
Y1396489D03*
Y1408401D03*
X740551Y1075196D03*
X748031D03*
X744290Y1071455D03*
X736810D03*
Y1075196D03*
X744290D03*
X748030Y1090157D03*
X744291D03*
X740551Y1078936D03*
Y1090157D03*
X736811D03*
X744290Y1078936D03*
X748030Y1086417D03*
X740550Y1086416D03*
Y1082676D03*
X736810Y1078936D03*
X748030Y1082677D03*
X744291Y1101377D03*
X748031Y1093897D03*
X744291Y1105117D03*
X736811D03*
X748031Y1123818D03*
Y1120078D03*
Y1116338D03*
Y1112598D03*
Y1108858D03*
X744291D03*
X740551D03*
X736811D03*
X738681Y1136909D03*
Y1140649D03*
X748031Y1138779D03*
Y1135039D03*
Y1131299D03*
Y1127558D03*
X738681Y1155610D03*
Y1148129D03*
X749901Y1144389D03*
Y1151869D03*
X746161Y1155610D03*
Y1151869D03*
X742421D03*
X738681D03*
Y1166830D03*
X746161Y1170570D03*
Y1166830D03*
X738681Y1159350D03*
X749901Y1166830D03*
Y1159350D03*
X738681Y1170570D03*
X746161Y1159350D03*
X749901Y1181791D03*
Y1174310D03*
X738681D03*
Y1178051D03*
X742421Y1181791D03*
X738681Y1185531D03*
Y1189271D03*
X746161Y1185531D03*
Y1178051D03*
Y1174310D03*
X742421Y1185531D03*
X748031Y1191141D03*
X738681Y1204232D03*
Y1193011D03*
Y1196751D03*
X742421Y1193011D03*
X748031Y1202362D03*
Y1198621D03*
X736811Y1221062D03*
X740551D03*
X748031D03*
X744291D03*
X748031Y1217322D03*
Y1213582D03*
Y1209842D03*
Y1206102D03*
X736811Y1224803D03*
Y1228543D03*
X748031Y1236023D03*
Y1232283D03*
X740551Y1236023D03*
X744291Y1228543D03*
X740551Y1232283D03*
X744291Y1224803D03*
X748031Y1239763D03*
X740551D03*
Y1243503D03*
Y1247243D03*
X748031D03*
Y1243503D03*
X744291Y1258465D03*
X736811D03*
X742088Y1348187D03*
Y1360099D03*
Y1384297D03*
Y1372385D03*
Y1396489D03*
Y1408401D03*
X755512Y1075196D03*
X762993D03*
X766732Y1071455D03*
X759252D03*
X751771D03*
Y1075196D03*
X766731D03*
X759251D03*
X755511Y1090157D03*
X762993Y1078936D03*
X755513D03*
X762991Y1086417D03*
X766731Y1078936D03*
X755511Y1086416D03*
X759251Y1078936D03*
X755511Y1082676D03*
X762991Y1082677D03*
X751771Y1078936D03*
X751772Y1105117D03*
X762992Y1093897D03*
X759252Y1105117D03*
X766732D03*
X755512Y1093897D03*
X762991Y1108857D03*
X755512Y1108858D03*
X751772D03*
X759252Y1116338D03*
Y1123818D03*
X751771Y1112598D03*
Y1120078D03*
X757382Y1140649D03*
X759252Y1131299D03*
X757382Y1148129D03*
X764862Y1170570D03*
X757382Y1166830D03*
Y1159350D03*
Y1174310D03*
Y1181791D03*
X764862Y1185531D03*
Y1178051D03*
X755512Y1187401D03*
X764862Y1189271D03*
X766732Y1194881D03*
X751772D03*
X755512Y1202362D03*
X766732D03*
Y1198621D03*
X762992D03*
X766732Y1221062D03*
Y1217322D03*
X762992Y1221062D03*
X759252D03*
X762992Y1213582D03*
X766732D03*
Y1209842D03*
X755512D03*
X766732Y1206102D03*
X751772Y1221062D03*
Y1217322D03*
X759252Y1224803D03*
Y1228543D03*
X755512Y1232283D03*
Y1236023D03*
X766732Y1224803D03*
Y1228543D03*
X762992Y1232283D03*
Y1236023D03*
X751772Y1224803D03*
Y1228543D03*
X755512Y1239763D03*
X766732D03*
Y1250984D03*
X755512Y1243503D03*
X762992D03*
Y1247243D03*
X751772Y1250984D03*
Y1254724D03*
X759252D03*
X766732D03*
X759252Y1250984D03*
X755512Y1247243D03*
X766732Y1258465D03*
X759252D03*
X751772D03*
X766568Y1348187D03*
X754328D03*
X766568Y1360099D03*
X754328D03*
Y1372385D03*
Y1384297D03*
X766568Y1372385D03*
Y1384297D03*
X777953Y1075196D03*
X770473D03*
X774212Y1071455D03*
X774211Y1075196D03*
X777953Y1078936D03*
X781693D03*
X770473D03*
X770471Y1090157D03*
X774211Y1078936D03*
X770471Y1086417D03*
Y1082677D03*
X770472Y1093897D03*
Y1108858D03*
X776083Y1140649D03*
Y1148129D03*
Y1155610D03*
Y1170570D03*
X768602Y1166830D03*
X779823Y1170570D03*
X776083Y1178051D03*
Y1185531D03*
X779823D03*
Y1178051D03*
X768602Y1181791D03*
Y1174310D03*
X772342Y1189271D03*
X783503Y1193011D03*
X776083D03*
X779823D03*
X781693Y1202362D03*
X777953D03*
X770472Y1221062D03*
X777953Y1209842D03*
Y1206102D03*
X774212Y1224803D03*
Y1228543D03*
X770472Y1236023D03*
Y1232283D03*
X777953D03*
X781693Y1250984D03*
X777953Y1239763D03*
X781693D03*
X770472Y1243503D03*
Y1247243D03*
X774212Y1250984D03*
Y1254724D03*
Y1258465D03*
X778808Y1348187D03*
Y1360099D03*
X785434Y1090158D03*
Y1082677D03*
Y1101378D03*
Y1123819D03*
Y1116339D03*
Y1108859D03*
Y1131300D03*
Y1198621D03*
Y1221062D03*
Y1213582D03*
Y1206102D03*
Y1228543D03*
Y1247243D03*
Y1239762D03*
X892183Y1728286D03*
Y1738286D03*
X891761Y1775438D03*
Y1785438D03*
X1057381Y1103247D03*
Y1140649D03*
Y1133169D03*
Y1125688D03*
Y1151870D03*
Y1144389D03*
X1054881Y1170570D03*
X1057381Y1159350D03*
X1054881Y1178050D03*
X1059251Y1187401D03*
Y1183661D03*
Y1194881D03*
Y1202362D03*
X1055510Y1198622D03*
Y1191142D03*
X1059251Y1198621D03*
Y1191141D03*
Y1209842D03*
Y1217322D03*
X1055510Y1221063D03*
Y1213583D03*
Y1206103D03*
X1059251Y1221062D03*
Y1206102D03*
Y1213582D03*
Y1232283D03*
Y1236023D03*
Y1224803D03*
Y1247243D03*
Y1239763D03*
X1052473Y1348187D03*
Y1360099D03*
Y1384297D03*
Y1372385D03*
X1064861Y1077066D03*
X1061121Y1080806D03*
X1072342Y1106988D03*
X1061121Y1103247D03*
X1072342Y1121948D03*
Y1118208D03*
X1064862Y1121948D03*
X1068602D03*
X1072342Y1140649D03*
Y1125688D03*
X1061121D03*
Y1140649D03*
X1064862D03*
X1068602D03*
X1064862Y1136909D03*
X1061121Y1133169D03*
X1064862Y1129429D03*
X1068602D03*
X1072342Y1155610D03*
X1064862D03*
X1068602D03*
X1061121Y1151870D03*
X1064862D03*
Y1148129D03*
X1061121Y1144389D03*
X1064862D03*
X1072342Y1166830D03*
X1064861Y1170570D03*
X1068602D03*
X1064861Y1166830D03*
X1061121Y1159350D03*
X1064862D03*
X1072342Y1181791D03*
Y1174310D03*
X1061120Y1181791D03*
X1064861D03*
X1068602D03*
Y1174310D03*
X1064861Y1178051D03*
X1061120Y1174310D03*
X1064861D03*
X1074212Y1187401D03*
X1062991D03*
Y1183661D03*
X1066732D03*
X1070472D03*
X1074212D03*
X1070472Y1187401D03*
X1066732D03*
X1074212Y1191141D03*
Y1198621D03*
X1070472Y1191141D03*
X1066732D03*
X1070472Y1198621D03*
X1066732D03*
X1062991Y1194881D03*
Y1202362D03*
Y1198621D03*
X1066732Y1194881D03*
X1062991Y1191141D03*
X1070472Y1194881D03*
Y1202362D03*
X1066732D03*
X1074212Y1206102D03*
X1066732D03*
X1070472D03*
Y1213582D03*
X1066732D03*
X1062991Y1209842D03*
Y1217322D03*
X1074212Y1221062D03*
X1066732D03*
X1070472D03*
Y1217322D03*
X1066732D03*
X1062991Y1221062D03*
Y1206102D03*
X1070472Y1209842D03*
X1062991Y1213582D03*
X1066732Y1209842D03*
X1070472Y1236023D03*
Y1232283D03*
X1066732Y1228543D03*
Y1224803D03*
X1074212D03*
X1062991Y1236023D03*
Y1232283D03*
Y1224803D03*
X1070472Y1228543D03*
Y1224803D03*
X1066732Y1239763D03*
Y1243503D03*
X1074212Y1239763D03*
Y1243503D03*
Y1250984D03*
X1066732Y1254724D03*
X1070472Y1247243D03*
X1074212Y1254724D03*
X1062991Y1247243D03*
X1070472Y1243503D03*
X1062991Y1239763D03*
X1066732Y1250984D03*
X1074212Y1258465D03*
X1066732D03*
X1072593Y1348187D03*
X1064713D03*
X1060353D03*
X1072593Y1360099D03*
X1064713D03*
X1060353D03*
X1072593Y1384297D03*
Y1372385D03*
X1064713D03*
Y1384297D03*
X1060353D03*
Y1372385D03*
X1072593Y1396583D03*
X1064713D03*
X1072593Y1408495D03*
X1064713D03*
X1089171Y1071455D03*
X1083562Y1092027D03*
X1089172Y1090157D03*
X1083562Y1095767D03*
X1087302Y1106988D03*
X1079822D03*
X1083562D03*
X1076082D03*
X1089172Y1101377D03*
Y1105117D03*
X1083562Y1118208D03*
X1087302D03*
X1079822Y1114468D03*
X1083562Y1110728D03*
X1087302D03*
X1091043D03*
Y1121948D03*
Y1118208D03*
Y1114468D03*
X1076082D03*
X1089172Y1108858D03*
X1091043Y1125688D03*
Y1140649D03*
X1079822Y1129429D03*
Y1140649D03*
X1083562D03*
X1087302D03*
X1091043Y1136909D03*
Y1133169D03*
Y1129429D03*
X1076082Y1140649D03*
X1087302Y1151870D03*
Y1155610D03*
Y1148129D03*
X1083562Y1144389D03*
X1087302D03*
X1076082Y1155610D03*
Y1151870D03*
Y1148129D03*
Y1144389D03*
X1087302Y1170570D03*
Y1166830D03*
Y1159350D03*
X1091043Y1170570D03*
X1076082Y1159350D03*
X1081692Y1179921D03*
X1083562Y1181791D03*
X1087302D03*
Y1178051D03*
Y1174310D03*
X1076082Y1181791D03*
Y1178051D03*
Y1174310D03*
X1077952Y1183661D03*
X1081692D03*
X1085432D03*
X1089172Y1187401D03*
X1085432D03*
X1091043Y1185531D03*
X1077952Y1187401D03*
X1081692D03*
X1077952Y1191141D03*
Y1198621D03*
X1081692Y1191141D03*
X1085432Y1194881D03*
X1089172D03*
X1085432Y1202362D03*
X1089172D03*
X1077952Y1194881D03*
Y1202362D03*
X1089172Y1191141D03*
Y1198621D03*
X1081692Y1202362D03*
X1085432Y1198621D03*
X1081692Y1194881D03*
X1085432Y1191141D03*
X1077952Y1206102D03*
X1081692D03*
X1085432Y1209842D03*
X1077952Y1221062D03*
X1089172Y1217322D03*
Y1221062D03*
X1085432D03*
Y1217322D03*
X1089172Y1206102D03*
X1077952Y1209842D03*
X1081692D03*
Y1217322D03*
X1089172Y1213582D03*
X1077952Y1217322D03*
X1085432Y1206102D03*
Y1213582D03*
X1077952Y1232283D03*
Y1236023D03*
X1085432Y1232283D03*
Y1236023D03*
X1081692Y1224803D03*
X1089172D03*
X1077952D03*
Y1228543D03*
X1085432Y1224803D03*
Y1228543D03*
X1077952Y1239763D03*
X1081692D03*
Y1243503D03*
X1085432Y1250984D03*
Y1239763D03*
X1089172D03*
Y1247243D03*
X1077952Y1243503D03*
X1081692Y1250984D03*
X1077952Y1247243D03*
X1081692Y1254724D03*
X1085432Y1243503D03*
X1089172Y1254724D03*
Y1250984D03*
X1085432Y1247243D03*
X1089173Y1258465D03*
X1081692D03*
X1089193Y1348187D03*
X1084833D03*
X1076953D03*
X1089193Y1360099D03*
X1084833D03*
X1076953D03*
X1089193Y1384297D03*
Y1372385D03*
X1084833Y1384297D03*
Y1372385D03*
X1076953Y1384297D03*
Y1372385D03*
X1089193Y1396583D03*
X1084833D03*
X1076953D03*
X1089193Y1408495D03*
X1084833D03*
X1076953D03*
X1104132Y1071455D03*
X1096652D03*
X1092913Y1090157D03*
X1104133D03*
X1107873D03*
X1100393D03*
X1096653D03*
X1104133Y1093897D03*
X1092913D03*
Y1097637D03*
X1107873Y1093897D03*
Y1097637D03*
X1104133Y1101377D03*
X1100393Y1097637D03*
Y1093897D03*
X1096653Y1101377D03*
X1104133Y1105117D03*
X1096653D03*
X1094783Y1110728D03*
Y1121948D03*
X1098523D03*
X1102263D03*
X1106003D03*
X1094783Y1118208D03*
X1098523D03*
X1102263D03*
X1106003D03*
X1094783Y1114468D03*
X1107873Y1108858D03*
X1104133D03*
X1100393D03*
X1096653D03*
X1092913D03*
X1098523Y1140649D03*
X1102263D03*
X1094783Y1136909D03*
X1102263D03*
X1094783Y1133169D03*
X1098523D03*
X1102263D03*
X1094783Y1129429D03*
X1098523D03*
X1102263D03*
X1094783Y1125688D03*
X1098523D03*
X1102263D03*
X1106003D03*
X1094783Y1140649D03*
Y1151870D03*
Y1155610D03*
X1102263Y1151870D03*
X1094783Y1148129D03*
Y1144389D03*
X1102263D03*
X1106003Y1148129D03*
Y1155610D03*
X1102263Y1170570D03*
X1094783Y1159350D03*
X1102263D03*
X1094783Y1166830D03*
X1106003D03*
X1094783Y1181791D03*
X1102263Y1185531D03*
X1094783Y1174310D03*
Y1178051D03*
X1106003Y1181791D03*
Y1174310D03*
X1092913Y1187401D03*
X1098523Y1196751D03*
Y1193011D03*
X1106003Y1200491D03*
Y1196751D03*
Y1204232D03*
X1102263D03*
X1098523D03*
Y1200491D03*
X1102263D03*
Y1196751D03*
X1092913Y1191141D03*
Y1194881D03*
Y1198621D03*
Y1202362D03*
X1098523Y1207972D03*
X1102263D03*
X1106003D03*
Y1211712D03*
X1102263D03*
X1098523D03*
Y1219192D03*
X1106003D03*
X1092913Y1206102D03*
Y1209842D03*
Y1213582D03*
Y1217322D03*
X1107873Y1221062D03*
X1104133D03*
X1100393D03*
X1096653D03*
X1092913D03*
Y1232283D03*
Y1236023D03*
X1107873Y1232283D03*
X1104133Y1224803D03*
X1107873Y1236023D03*
X1100393Y1232283D03*
Y1236023D03*
X1096653Y1224803D03*
X1100393Y1228543D03*
X1092913Y1224803D03*
X1107873D03*
X1100393D03*
X1107873Y1228543D03*
X1092913D03*
X1100393Y1239763D03*
X1107873D03*
X1104133Y1243503D03*
X1096653D03*
Y1254724D03*
X1104133D03*
X1092913Y1247243D03*
X1096653Y1250984D03*
X1092913Y1243503D03*
X1107873D03*
X1100393D03*
X1107873Y1247243D03*
X1100393D03*
X1104133Y1250984D03*
Y1258465D03*
X1096653D03*
X1101433Y1348187D03*
X1097073D03*
X1101433Y1360099D03*
X1097073D03*
X1101433Y1384297D03*
Y1372385D03*
X1097073D03*
Y1384297D03*
X1101433Y1396583D03*
X1097073D03*
X1101433Y1408495D03*
X1097073D03*
X1119093Y1071455D03*
X1111612D03*
X1115354Y1090157D03*
X1119094D03*
X1122834D03*
X1111613D03*
X1122834Y1093897D03*
X1115354D03*
X1122834Y1097637D03*
X1115354D03*
X1119094Y1101377D03*
X1111613D03*
X1119094Y1105117D03*
X1111613D03*
X1117224Y1121948D03*
Y1118208D03*
X1120964D03*
X1109743Y1121948D03*
X1113484D03*
X1109743Y1118208D03*
X1113484D03*
X1124704Y1121948D03*
Y1118208D03*
X1120964Y1121948D03*
X1122834Y1108858D03*
X1119094D03*
X1115354D03*
X1111613D03*
X1109743Y1136909D03*
X1124704Y1125688D03*
Y1140649D03*
Y1133169D03*
X1113484D03*
X1117224D03*
X1120964D03*
X1109743Y1125688D03*
X1120964D03*
X1117224D03*
X1113484D03*
X1120964Y1140649D03*
X1117224D03*
X1113484D03*
X1109743Y1129429D03*
Y1133169D03*
X1113484Y1155610D03*
X1109743Y1144389D03*
X1120964Y1155610D03*
X1109743Y1151869D03*
X1120964Y1148129D03*
X1113484D03*
X1117224D03*
X1124704D03*
X1117224Y1170570D03*
X1109743D03*
X1113484Y1166830D03*
X1117224Y1159350D03*
X1120964Y1166830D03*
X1109743Y1159350D03*
X1124704Y1170570D03*
Y1159350D03*
X1109743Y1189271D03*
X1113484D03*
X1117224D03*
X1120964D03*
X1113484Y1181791D03*
X1117224D03*
X1120964D03*
X1124704Y1189271D03*
Y1181791D03*
X1109743Y1178051D03*
X1120964Y1174310D03*
X1109743Y1185531D03*
X1113484Y1174310D03*
X1124704Y1204232D03*
Y1196751D03*
X1120964Y1204232D03*
X1117224D03*
X1113484D03*
X1109743D03*
Y1193011D03*
Y1196751D03*
Y1200491D03*
X1113484Y1196751D03*
X1117224D03*
X1120964D03*
X1113484Y1207972D03*
X1117224D03*
X1120964D03*
X1109743Y1211712D03*
Y1207972D03*
X1124704D03*
X1122834Y1221062D03*
X1119094D03*
X1115354D03*
X1111613D03*
X1122834Y1224803D03*
Y1232283D03*
Y1236023D03*
X1119094Y1224803D03*
X1115354Y1232283D03*
Y1236023D03*
X1111613Y1224803D03*
X1115354Y1228543D03*
Y1224803D03*
X1122834Y1228543D03*
X1119094Y1243503D03*
X1122834Y1239763D03*
X1111613Y1243503D03*
Y1239763D03*
X1122834Y1243503D03*
X1119094Y1250984D03*
X1111613Y1254724D03*
X1119094D03*
X1122834Y1247243D03*
X1115354Y1243503D03*
Y1247243D03*
X1111613Y1250984D03*
X1119094Y1258465D03*
X1111614D03*
X1113673Y1348187D03*
X1121553D03*
X1109313D03*
X1113673Y1360099D03*
X1121553D03*
X1109313D03*
X1113673Y1372385D03*
Y1384297D03*
X1121553Y1372385D03*
Y1384297D03*
X1109313D03*
Y1372385D03*
X1113673Y1396583D03*
X1121553D03*
X1109313D03*
X1113673Y1408495D03*
X1121553D03*
X1109313D03*
X1134053Y1071455D03*
X1126573D03*
X1126574Y1090157D03*
X1130314D03*
X1134054D03*
X1137795D03*
X1126574Y1101377D03*
X1130314Y1097637D03*
Y1093897D03*
X1137795D03*
Y1097637D03*
X1134054Y1101377D03*
X1126574Y1105117D03*
X1134054D03*
X1139665Y1121948D03*
X1130314Y1112598D03*
X1128444Y1118208D03*
X1132184D03*
X1135924D03*
X1132184Y1121948D03*
X1135924D03*
X1128444D03*
X1139665Y1118208D03*
X1137795Y1108858D03*
X1134054D03*
X1130314D03*
X1126574D03*
X1139665Y1125688D03*
X1128444Y1140649D03*
X1132184D03*
X1135924D03*
X1132184Y1125688D03*
X1128444D03*
X1135924D03*
Y1133169D03*
X1132184D03*
X1128444D03*
X1139665D03*
Y1140649D03*
X1135924Y1148129D03*
X1132184D03*
X1128444D03*
X1139665D03*
X1128444Y1155610D03*
X1135924D03*
X1139665Y1170570D03*
Y1159350D03*
X1132184Y1170570D03*
X1135925Y1166830D03*
X1128444D03*
X1132184Y1159350D03*
X1135924Y1181791D03*
X1132184D03*
X1128444D03*
X1135924Y1189271D03*
X1132184D03*
X1128444D03*
Y1174310D03*
X1135924D03*
X1139665Y1181791D03*
Y1189271D03*
Y1196751D03*
Y1204232D03*
X1135924D03*
Y1196751D03*
X1132184D03*
X1128444D03*
Y1204232D03*
X1132184D03*
X1139665Y1207972D03*
X1134054Y1217322D03*
X1135924Y1207972D03*
X1132184D03*
X1128444D03*
X1137795Y1221062D03*
X1134054D03*
X1130314D03*
X1126574D03*
Y1224803D03*
X1137795Y1232283D03*
Y1236023D03*
X1134054Y1224803D03*
X1130314Y1232283D03*
Y1236023D03*
X1137795Y1228543D03*
Y1224803D03*
X1130314Y1228543D03*
Y1224803D03*
X1126574Y1243503D03*
X1134054D03*
X1137795Y1239763D03*
X1130314D03*
X1126574Y1254724D03*
X1137795Y1243503D03*
X1130314Y1247243D03*
X1126574Y1250984D03*
X1137795Y1247243D03*
X1130314Y1243503D03*
X1134054Y1250984D03*
Y1254724D03*
X1134055Y1258465D03*
X1126574D03*
X1138153Y1348187D03*
X1133793D03*
X1125913D03*
X1138153Y1360099D03*
X1133793D03*
X1125913D03*
X1138153Y1384297D03*
Y1372385D03*
X1133793Y1384297D03*
Y1372385D03*
X1125913Y1384297D03*
Y1372385D03*
X1138153Y1396583D03*
X1133793D03*
X1125913D03*
X1138153Y1408495D03*
X1133793D03*
X1125913D03*
X1152755Y1075196D03*
X1156494Y1071455D03*
X1149014Y1071454D03*
X1141534Y1071455D03*
X1156494Y1075196D03*
X1149014Y1075195D03*
X1141535Y1090157D03*
X1149015Y1082677D03*
Y1086417D03*
X1152755Y1090157D03*
X1156495D03*
Y1086417D03*
X1149015Y1090157D03*
X1145275D03*
X1149014Y1078935D03*
X1156494Y1078936D03*
X1152754Y1086416D03*
Y1082676D03*
X1141535Y1101377D03*
X1149015D03*
X1152755Y1093897D03*
X1156495Y1101377D03*
X1145275Y1093897D03*
Y1097637D03*
X1141535Y1105117D03*
X1149015D03*
X1156495D03*
X1150885Y1121948D03*
X1143405D03*
Y1118208D03*
Y1114468D03*
X1154625Y1121948D03*
X1156495Y1108858D03*
X1152755D03*
X1149015D03*
X1145275D03*
X1141535D03*
X1154625Y1125688D03*
X1150885Y1133464D03*
X1154625Y1133169D03*
X1143503Y1132677D03*
X1143405Y1140649D03*
Y1125688D03*
X1150885Y1140649D03*
X1154625D03*
X1150885Y1125688D03*
X1143405Y1148129D03*
X1150885D03*
X1154625D03*
X1143405Y1155610D03*
X1154625D03*
Y1166830D03*
X1150885Y1170570D03*
X1143405Y1166830D03*
X1150885Y1159350D03*
X1143405Y1181791D03*
X1154625D03*
X1150885D03*
Y1189271D03*
X1154625D03*
X1143405D03*
Y1174310D03*
X1154625D03*
X1150885Y1196751D03*
X1154625Y1204232D03*
X1150885D03*
X1154625Y1196751D03*
X1143405D03*
Y1204232D03*
X1150885Y1207972D03*
X1154625D03*
Y1211712D03*
X1143405Y1207972D03*
X1149015Y1221062D03*
X1156495D03*
X1152755D03*
X1145275D03*
X1141535D03*
X1145275Y1224803D03*
X1141535D03*
X1152755Y1232283D03*
Y1236023D03*
X1156495Y1228543D03*
Y1224803D03*
X1149015Y1228543D03*
Y1224803D03*
X1145275Y1232283D03*
Y1236023D03*
X1141535Y1243503D03*
X1152755Y1239763D03*
X1145275D03*
X1141535Y1254724D03*
Y1250984D03*
X1145275Y1247243D03*
X1152755Y1243503D03*
X1145275D03*
X1152755Y1247243D03*
X1156495Y1258465D03*
X1149015D03*
X1141536D03*
X1150393Y1348187D03*
X1146033D03*
X1150393Y1360099D03*
X1146033D03*
X1150393Y1384297D03*
Y1372385D03*
X1146033D03*
Y1384297D03*
X1150393Y1396583D03*
X1146033D03*
X1150393Y1408495D03*
X1146033D03*
X1167716Y1075196D03*
X1160235D03*
X1171455Y1071455D03*
X1163975D03*
Y1075196D03*
X1171455D03*
X1167716Y1078936D03*
X1163976Y1086417D03*
Y1090157D03*
X1171456Y1086417D03*
Y1090157D03*
X1167716D03*
X1160235Y1078936D03*
Y1090157D03*
X1160234Y1086417D03*
X1167715Y1086416D03*
X1163975Y1078936D03*
X1160234Y1082677D03*
X1171455Y1078936D03*
X1167715Y1082676D03*
X1167716Y1097637D03*
Y1093897D03*
X1160235D03*
Y1097637D03*
X1163976Y1105117D03*
X1171456D03*
X1171455Y1093897D03*
Y1097637D03*
X1163975Y1093897D03*
Y1097637D03*
X1169586Y1121948D03*
X1165846D03*
X1162106D03*
X1158365D03*
X1173326D03*
X1171456Y1108858D03*
X1167716D03*
X1163976D03*
X1160235D03*
X1162106Y1133169D03*
X1165846D03*
X1169586D03*
X1158365Y1140649D03*
X1162106D03*
X1165846D03*
X1169586D03*
X1158365Y1125688D03*
X1162106D03*
X1165846D03*
X1169586D03*
X1173326Y1133169D03*
Y1125688D03*
Y1140649D03*
X1158365Y1133169D03*
X1173326Y1148129D03*
X1158365D03*
X1162106D03*
X1165846D03*
X1169586D03*
X1162106Y1155610D03*
X1169586D03*
X1158365Y1170570D03*
X1165846D03*
X1169586Y1166830D03*
X1158365Y1159350D03*
X1162106Y1166830D03*
X1165846Y1159350D03*
X1173326D03*
Y1170570D03*
Y1189271D03*
X1158365Y1181791D03*
X1162106D03*
X1165846D03*
X1169586D03*
X1158365Y1189271D03*
X1162106D03*
X1165846D03*
X1169586D03*
X1173326Y1181791D03*
X1169586Y1174310D03*
X1162106D03*
Y1204232D03*
X1158365D03*
X1169586D03*
X1165846D03*
X1158365Y1196751D03*
X1162106D03*
X1165846D03*
X1169586D03*
X1173326Y1204232D03*
Y1196751D03*
X1158365Y1211712D03*
Y1207972D03*
X1173326D03*
Y1211712D03*
X1162106Y1207972D03*
X1165846D03*
X1169586Y1211712D03*
Y1207972D03*
X1171456Y1221062D03*
X1167716D03*
X1163976D03*
X1160235D03*
X1163976Y1228543D03*
Y1224803D03*
X1171456Y1228543D03*
Y1224803D03*
X1167716Y1232283D03*
Y1236023D03*
X1160235Y1232283D03*
Y1236023D03*
X1171456Y1239763D03*
X1160235D03*
X1167716Y1247243D03*
X1160235D03*
Y1243503D03*
X1167716D03*
X1171456Y1258465D03*
X1163976D03*
X1162633Y1348187D03*
X1170513D03*
X1158273D03*
X1162633Y1360099D03*
X1170513D03*
X1158273D03*
X1162633Y1372385D03*
Y1384297D03*
X1170513Y1372385D03*
Y1384297D03*
X1158273D03*
Y1372385D03*
X1162633Y1396583D03*
X1170513D03*
X1158273D03*
X1162633Y1408495D03*
X1170513D03*
X1158273D03*
X1175196Y1075196D03*
X1182676D03*
X1186416Y1071455D03*
X1178935D03*
Y1075196D03*
X1186416D03*
X1175196Y1078936D03*
Y1090157D03*
X1178936D03*
X1182676Y1078936D03*
X1178936Y1086417D03*
X1182676Y1090157D03*
X1186417D03*
Y1086417D03*
Y1082677D03*
X1175195Y1086417D03*
X1182675Y1086416D03*
X1175195Y1082677D03*
X1178935Y1078936D03*
X1182675Y1082676D03*
X1186416Y1078936D03*
X1175196Y1097637D03*
Y1093897D03*
X1182676Y1097637D03*
Y1093897D03*
X1178936Y1105117D03*
X1186417D03*
X1188287Y1118208D03*
X1184546D03*
X1180806Y1121948D03*
X1177066D03*
X1184546D03*
X1186417Y1108858D03*
X1182676D03*
X1178936D03*
X1175196D03*
X1188287Y1125688D03*
X1184546Y1136909D03*
X1177066Y1133169D03*
X1180806D03*
X1184546D03*
X1177066Y1140649D03*
X1180806D03*
X1184546Y1125688D03*
Y1129429D03*
X1177066Y1125688D03*
X1180806D03*
X1184546Y1140649D03*
X1188287Y1155610D03*
Y1151869D03*
Y1148129D03*
X1177066D03*
X1180806D03*
X1184546Y1144389D03*
Y1148129D03*
Y1151869D03*
X1177066Y1155610D03*
X1184546D03*
X1177066Y1166830D03*
X1188287D03*
Y1159350D03*
Y1170570D03*
Y1181791D03*
Y1174310D03*
X1177066Y1189271D03*
X1180806D03*
X1184546Y1178051D03*
X1177066Y1174310D03*
X1184546Y1185531D03*
X1177066Y1181791D03*
X1180806D03*
X1184546Y1189271D03*
Y1174310D03*
Y1204232D03*
X1177066D03*
X1180806D03*
X1184546Y1200491D03*
X1177066Y1196751D03*
X1180806D03*
X1184546Y1193011D03*
X1188287Y1196751D03*
X1184566Y1196732D03*
X1188287Y1207972D03*
X1184546Y1211712D03*
X1177066Y1207972D03*
Y1211712D03*
X1180806Y1207972D03*
Y1211712D03*
X1184546Y1207972D03*
X1186417Y1221062D03*
X1182676D03*
X1178936D03*
X1175196D03*
Y1232283D03*
Y1236023D03*
X1178936Y1228543D03*
Y1224803D03*
X1182676Y1232283D03*
Y1236023D03*
X1186417Y1228543D03*
Y1224803D03*
X1182676Y1239763D03*
X1175196Y1243503D03*
X1182676Y1247243D03*
Y1243503D03*
X1175196Y1247243D03*
X1186417Y1258465D03*
X1178936D03*
X1182753Y1348187D03*
X1174873D03*
X1182753Y1360099D03*
X1174873D03*
X1182753Y1384297D03*
Y1372385D03*
X1174873Y1384297D03*
Y1372385D03*
X1182753Y1396583D03*
X1174873D03*
X1182753Y1408495D03*
X1174873D03*
X1179329Y1728990D03*
Y1738990D03*
X1179123Y1776014D03*
Y1786014D03*
X1190157Y1075196D03*
X1197637D03*
X1205117D03*
X1201376Y1071455D03*
X1193896D03*
Y1075196D03*
X1201376D03*
X1190157Y1090157D03*
X1197637Y1078936D03*
Y1090157D03*
X1201377D03*
X1205116D03*
X1193897D03*
X1190155Y1086417D03*
X1205116Y1082677D03*
X1190155D03*
X1197636Y1082676D03*
X1193896Y1078936D03*
X1205116Y1086417D03*
X1201376Y1078936D03*
X1197636Y1086416D03*
X1190157Y1093897D03*
X1201377Y1101377D03*
X1205117Y1093897D03*
X1201377Y1105117D03*
X1193897D03*
X1192027Y1118208D03*
X1205117Y1123818D03*
Y1120078D03*
Y1116338D03*
Y1108858D03*
X1201377D03*
X1197637D03*
X1193897D03*
X1190157D03*
X1192027Y1136909D03*
X1195767Y1140649D03*
X1192027D03*
X1195767Y1136909D03*
X1205117Y1135039D03*
Y1131299D03*
Y1127558D03*
X1195767Y1148129D03*
X1192027Y1144389D03*
X1195767Y1155610D03*
X1192027Y1148129D03*
X1195767Y1151869D03*
X1199507D03*
X1203247D03*
Y1155610D03*
X1192027Y1151870D03*
X1195767Y1170570D03*
Y1159350D03*
X1203247Y1166830D03*
Y1170570D03*
Y1159350D03*
X1195767Y1166830D03*
X1192027Y1181791D03*
X1199507Y1185531D03*
X1203247Y1174310D03*
Y1178051D03*
Y1185531D03*
X1192027Y1178051D03*
Y1189271D03*
X1195767D03*
X1192027Y1185531D03*
X1195767D03*
X1199507Y1181791D03*
X1195767Y1178051D03*
Y1174310D03*
Y1204232D03*
X1199507Y1193011D03*
X1195767Y1196751D03*
Y1193011D03*
X1192027D03*
X1205117Y1198621D03*
Y1202362D03*
X1192027Y1211712D03*
X1205117Y1206102D03*
Y1209842D03*
Y1213582D03*
Y1217322D03*
Y1221062D03*
X1201377D03*
X1197637D03*
X1193897D03*
X1190157D03*
Y1232283D03*
Y1236023D03*
X1197637Y1232283D03*
X1201377Y1228543D03*
X1197637Y1236023D03*
X1201377Y1224803D03*
X1205117Y1232283D03*
Y1236023D03*
X1193897Y1228543D03*
Y1224803D03*
X1197637Y1239763D03*
X1205117D03*
X1190157Y1243503D03*
X1197637Y1247243D03*
Y1243503D03*
X1190157Y1247243D03*
X1205117Y1243503D03*
Y1247243D03*
X1201377Y1258465D03*
X1193897D03*
X1212598Y1075196D03*
X1220079D03*
X1216338Y1071455D03*
X1208857D03*
X1216337Y1075196D03*
X1208857D03*
X1220079Y1078936D03*
X1212599D03*
X1212597Y1090157D03*
Y1082676D03*
Y1086416D03*
X1220077Y1086417D03*
X1208857Y1078936D03*
X1216337D03*
X1220077Y1082677D03*
X1212598Y1093897D03*
X1220078D03*
X1216338Y1105117D03*
X1208858D03*
X1212598Y1108858D03*
X1216338Y1116338D03*
Y1123818D03*
X1208857Y1112598D03*
Y1120078D03*
X1220077Y1108857D03*
X1208858Y1108858D03*
X1214468Y1140649D03*
X1206987Y1136909D03*
X1216338Y1131299D03*
X1206987Y1151869D03*
X1214468Y1148129D03*
X1206987Y1144389D03*
Y1159350D03*
X1214468D03*
X1206987Y1166830D03*
X1214468D03*
X1221948Y1170570D03*
X1206987Y1181791D03*
X1214468Y1189271D03*
X1221948Y1178051D03*
Y1185531D03*
X1206987Y1174310D03*
Y1189271D03*
X1214468Y1181791D03*
Y1174310D03*
X1208858Y1194881D03*
X1221948Y1193011D03*
X1212598Y1202362D03*
X1220078Y1198621D03*
Y1221062D03*
X1216338D03*
X1220078Y1213582D03*
X1212598Y1209842D03*
X1208858Y1221062D03*
Y1217322D03*
X1216338Y1224803D03*
Y1228543D03*
X1212598Y1232283D03*
Y1236023D03*
X1220078Y1232283D03*
Y1236023D03*
X1208858Y1224803D03*
Y1228543D03*
X1212598Y1239763D03*
Y1243503D03*
X1220078Y1247243D03*
Y1243503D03*
X1212598Y1247243D03*
X1208858Y1254724D03*
Y1250984D03*
X1216338Y1254724D03*
Y1250984D03*
Y1258465D03*
X1208858D03*
X1227559Y1075196D03*
X1235039D03*
X1231298Y1071455D03*
X1223818D03*
X1231297Y1075196D03*
X1223817D03*
X1235039Y1078936D03*
X1227559D03*
X1227557Y1090157D03*
X1231297Y1078936D03*
X1227557Y1086417D03*
X1223817Y1078936D03*
X1227557Y1082677D03*
X1227558Y1093897D03*
X1223818Y1105117D03*
X1227558Y1108858D03*
X1233169Y1140649D03*
Y1155610D03*
Y1148129D03*
X1236909Y1170570D03*
X1225688Y1166830D03*
X1233169Y1170570D03*
X1236909Y1178051D03*
Y1185531D03*
X1233169D03*
Y1178051D03*
X1225688Y1174310D03*
Y1181791D03*
Y1189271D03*
X1233169Y1193011D03*
X1223818Y1194881D03*
X1236909Y1193011D03*
X1223818Y1202362D03*
Y1198621D03*
X1235039Y1202362D03*
X1223818Y1206102D03*
Y1221062D03*
Y1217322D03*
Y1213582D03*
Y1209842D03*
X1227558Y1221062D03*
X1235039Y1209842D03*
Y1206102D03*
X1223818Y1224803D03*
Y1228543D03*
X1231298Y1224803D03*
Y1228543D03*
X1227558Y1236023D03*
Y1232283D03*
X1235039D03*
X1225688Y1222932D03*
X1223818Y1239763D03*
X1227558Y1247243D03*
X1231298Y1254724D03*
X1223818D03*
Y1250984D03*
X1235039Y1239763D03*
X1227558Y1243503D03*
X1231298Y1250984D03*
Y1258465D03*
X1223818D03*
X1235966Y1348187D03*
X1228086D03*
X1235966Y1360099D03*
X1228086D03*
X1235966Y1372385D03*
Y1384297D03*
X1228086Y1372385D03*
Y1384297D03*
X1238779Y1078936D03*
X1242520Y1090158D03*
Y1082677D03*
Y1101378D03*
Y1123819D03*
Y1116339D03*
Y1108859D03*
Y1131300D03*
X1240589Y1193011D03*
X1238779Y1202362D03*
X1242520Y1198621D03*
Y1221062D03*
Y1213582D03*
Y1206102D03*
Y1228543D03*
X1238779Y1250984D03*
X1242520Y1247243D03*
Y1239762D03*
X1238779Y1239763D03*
X1252566Y1348187D03*
X1240326D03*
X1248206D03*
X1252566Y1360099D03*
X1240326D03*
X1248206D03*
X1252566Y1372385D03*
Y1384297D03*
X1240326D03*
Y1372385D03*
X1248206D03*
Y1384297D03*
X1252566Y1396583D03*
X1240326D03*
X1248206D03*
X1252566Y1408495D03*
X1240326D03*
X1248206D03*
X1264806Y1348187D03*
X1260446D03*
X1264806Y1360099D03*
X1260446D03*
X1264806Y1372385D03*
Y1384297D03*
X1260446Y1372385D03*
Y1384297D03*
X1264806Y1396583D03*
X1260446D03*
X1264806Y1408495D03*
X1260446D03*
X1284926Y1348187D03*
X1277046D03*
X1272686D03*
X1284926Y1360099D03*
X1277046D03*
X1272686D03*
X1284926Y1372385D03*
Y1384297D03*
X1277046Y1372385D03*
Y1384297D03*
X1272686D03*
Y1372385D03*
X1284926Y1396583D03*
X1277046D03*
X1272686D03*
X1284926Y1408495D03*
X1277046D03*
X1272686D03*
X1301526Y1348187D03*
X1289286D03*
X1297166D03*
X1301526Y1360099D03*
X1289286D03*
X1297166D03*
X1301526Y1372385D03*
Y1384297D03*
X1289286D03*
Y1372385D03*
X1297166Y1384297D03*
Y1372385D03*
X1301526Y1396583D03*
X1289286D03*
X1297166D03*
X1301526Y1408495D03*
X1289286D03*
X1297166D03*
X1313766Y1348187D03*
X1309406D03*
X1313766Y1360099D03*
X1309406D03*
X1313766Y1372385D03*
Y1384297D03*
X1309406Y1372385D03*
Y1384297D03*
X1313766Y1396583D03*
X1309406D03*
X1313766Y1408495D03*
X1309406D03*
X1333886Y1348187D03*
X1326006D03*
X1321646D03*
X1333886Y1360099D03*
X1326006D03*
X1321646D03*
X1333886Y1372385D03*
Y1384297D03*
X1326006Y1372385D03*
Y1384297D03*
X1321646D03*
Y1372385D03*
X1333886Y1396583D03*
X1326006D03*
X1321646D03*
X1333886Y1408495D03*
X1326006D03*
X1321646D03*
X1350486Y1348187D03*
X1338246D03*
X1346126D03*
X1350486Y1360099D03*
X1338246D03*
X1346126D03*
X1350486Y1372385D03*
Y1384297D03*
X1338246D03*
Y1372385D03*
X1346126Y1384297D03*
Y1372385D03*
X1350486Y1396583D03*
X1338246D03*
X1346126D03*
X1350486Y1408495D03*
X1338246D03*
X1346126D03*
X1358366Y1348187D03*
Y1360099D03*
Y1372385D03*
Y1384297D03*
Y1396583D03*
Y1408495D03*
X1459130Y1348187D03*
Y1360099D03*
Y1384297D03*
Y1372385D03*
X1479250Y1348187D03*
X1471370D03*
X1467010D03*
X1479250Y1360099D03*
X1471370D03*
X1467010D03*
X1479250Y1384297D03*
Y1372385D03*
X1471370D03*
Y1384297D03*
X1467010D03*
Y1372385D03*
X1479250Y1396583D03*
X1471370D03*
X1479250Y1408495D03*
X1471370D03*
X1495850Y1348187D03*
X1483610D03*
X1491490D03*
X1495850Y1360099D03*
X1483610D03*
X1491490D03*
X1483610Y1384297D03*
Y1372385D03*
X1491490Y1384297D03*
Y1372385D03*
X1495850Y1384297D03*
Y1372385D03*
Y1396583D03*
X1483610D03*
X1491490D03*
X1495850Y1408495D03*
X1483610D03*
X1491490D03*
X1514468Y1103247D03*
Y1125688D03*
Y1133169D03*
Y1140649D03*
Y1144389D03*
Y1151870D03*
Y1159350D03*
X1512597Y1198622D03*
Y1191142D03*
Y1221063D03*
Y1213583D03*
Y1206103D03*
X1508090Y1348187D03*
X1503730D03*
X1508090Y1360099D03*
X1503730D03*
X1508090Y1384297D03*
Y1372385D03*
X1503730D03*
Y1384297D03*
X1508090Y1396583D03*
X1503730D03*
X1508090Y1408495D03*
X1503730D03*
X1521948Y1077066D03*
X1518208Y1080806D03*
Y1103247D03*
X1529429Y1106988D03*
Y1118208D03*
Y1121948D03*
X1525689D03*
X1521949D03*
X1529429Y1125688D03*
X1518208D03*
X1525689Y1129429D03*
X1521949D03*
X1518208Y1133169D03*
X1521949Y1136909D03*
X1529429Y1140649D03*
X1525689D03*
X1521949D03*
X1518208D03*
X1521949Y1144389D03*
X1518208D03*
X1521949Y1148129D03*
Y1151870D03*
X1518208D03*
X1529429Y1155610D03*
X1525689D03*
X1521949D03*
Y1159350D03*
X1518208D03*
X1529429Y1166830D03*
X1521948D03*
X1525689Y1170570D03*
X1521948D03*
Y1174310D03*
X1518207D03*
X1521948Y1178051D03*
X1525689Y1174310D03*
X1529429D03*
X1527559Y1179921D03*
X1523819D03*
X1518207Y1181791D03*
X1516338Y1187401D03*
X1520078D03*
X1527559Y1183661D03*
X1523819D03*
X1520078D03*
X1516338D03*
X1523819Y1187401D03*
X1527559D03*
X1516338Y1194881D03*
Y1202362D03*
X1527559Y1191141D03*
X1523819D03*
X1527559Y1198621D03*
X1523819D03*
X1520078Y1194881D03*
Y1202362D03*
X1516338Y1198621D03*
X1523819Y1194881D03*
X1520078Y1198621D03*
X1523819Y1202362D03*
X1516338Y1191141D03*
X1527559Y1202362D03*
Y1194881D03*
X1520078Y1191141D03*
X1516338Y1209842D03*
Y1217322D03*
X1523819Y1206102D03*
X1527559D03*
Y1213582D03*
X1523819D03*
X1520078Y1209842D03*
Y1217322D03*
X1523819Y1221062D03*
X1527559D03*
X1520078D03*
X1516338Y1213582D03*
Y1206102D03*
X1520078D03*
X1527559Y1217322D03*
X1523819Y1209842D03*
X1516338Y1221062D03*
X1527559Y1209842D03*
X1523819Y1217322D03*
X1520078Y1213582D03*
X1527559Y1228543D03*
X1516338Y1232283D03*
Y1236023D03*
Y1224803D03*
X1527559Y1236023D03*
Y1232283D03*
X1523819Y1228543D03*
Y1224803D03*
X1520078Y1236023D03*
Y1232283D03*
Y1224803D03*
X1527559D03*
X1516338Y1239763D03*
X1523819D03*
Y1243503D03*
X1520078Y1239763D03*
Y1247243D03*
X1516338D03*
X1527559Y1243503D03*
Y1247243D03*
X1523819Y1250984D03*
Y1254724D03*
Y1258465D03*
X1528210Y1348187D03*
X1520330D03*
X1515970D03*
X1528210Y1360099D03*
X1520330D03*
X1515970D03*
X1528210Y1372385D03*
Y1384297D03*
X1520330Y1372385D03*
Y1384297D03*
X1515970D03*
Y1372385D03*
X1528210Y1396583D03*
X1520330D03*
X1515970D03*
X1528210Y1408495D03*
X1520330D03*
X1515970D03*
X1546258Y1071455D03*
X1540649Y1092027D03*
X1546259Y1090157D03*
X1544389Y1099507D03*
X1540649Y1106988D03*
X1536909D03*
X1533169D03*
X1544389D03*
X1540649Y1095767D03*
X1546259Y1101377D03*
Y1105117D03*
X1544389Y1118208D03*
X1540649D03*
X1544389Y1110728D03*
X1540649D03*
X1536909Y1114468D03*
X1533169D03*
X1544389Y1140649D03*
X1540649D03*
X1536909D03*
X1533169D03*
X1536909Y1129429D03*
X1544389Y1144389D03*
X1540649D03*
X1533169D03*
Y1148129D03*
Y1151870D03*
Y1155610D03*
X1544389Y1148129D03*
Y1155610D03*
Y1151870D03*
X1533169Y1159350D03*
X1544389D03*
Y1166830D03*
Y1170570D03*
X1535039Y1187401D03*
X1533169Y1174310D03*
Y1178051D03*
X1544389Y1174310D03*
Y1178051D03*
Y1181791D03*
X1540649D03*
X1538779Y1179921D03*
X1531299D03*
Y1187401D03*
X1546259D03*
X1542519D03*
Y1183661D03*
X1538779D03*
X1535039D03*
X1531299D03*
X1538779Y1187401D03*
X1542519Y1191141D03*
X1538779Y1202362D03*
X1535039Y1194881D03*
X1542519Y1198621D03*
X1535039Y1191141D03*
X1531299D03*
X1535039Y1198621D03*
X1531299D03*
X1538779Y1191141D03*
X1542519Y1194881D03*
X1546259D03*
X1542519Y1202362D03*
X1546259D03*
Y1198621D03*
Y1191141D03*
X1535039Y1202362D03*
X1538779Y1194881D03*
X1542519Y1213582D03*
Y1206102D03*
X1546259Y1213582D03*
X1535039Y1209842D03*
X1531299Y1206102D03*
X1535039D03*
X1538779D03*
X1542519Y1209842D03*
X1531299Y1221062D03*
X1535039D03*
X1546259Y1217322D03*
Y1221062D03*
X1542519D03*
Y1217322D03*
X1535039D03*
X1546259Y1206102D03*
X1538779Y1209842D03*
Y1217322D03*
X1535039Y1224803D03*
X1542519Y1228543D03*
X1535039D03*
X1531299Y1224803D03*
X1535039Y1232283D03*
Y1236023D03*
X1542519Y1232283D03*
Y1236023D03*
X1538779Y1224803D03*
X1546259D03*
X1542519D03*
X1535039Y1239763D03*
X1531299D03*
Y1243503D03*
X1538779Y1239763D03*
Y1243503D03*
X1542519Y1250984D03*
Y1239763D03*
X1546259D03*
Y1247243D03*
Y1250984D03*
X1542519Y1243503D03*
X1546259Y1254724D03*
X1542519Y1247243D03*
X1538779Y1250984D03*
Y1254724D03*
X1535039Y1243503D03*
X1531299Y1250984D03*
X1535039Y1247243D03*
X1531299Y1254724D03*
X1546260Y1258465D03*
X1538779D03*
X1531299D03*
X1544810Y1348187D03*
X1532570D03*
X1540450D03*
X1544810Y1360099D03*
X1532570D03*
X1540450D03*
X1544810Y1384297D03*
Y1372385D03*
X1532570Y1384297D03*
Y1372385D03*
X1540450Y1384297D03*
Y1372385D03*
X1544810Y1396583D03*
X1532570D03*
X1540450D03*
X1544810Y1408495D03*
X1532570D03*
X1540450D03*
X1561219Y1071455D03*
X1553739D03*
X1561220Y1090157D03*
X1557480D03*
X1553740D03*
X1550000D03*
X1561220Y1093897D03*
Y1105117D03*
X1553740D03*
X1561220Y1101377D03*
X1557480Y1097637D03*
Y1093897D03*
X1553740Y1101377D03*
X1550000Y1093897D03*
Y1097637D03*
X1551870Y1114468D03*
X1548130D03*
X1563090Y1118208D03*
X1559350D03*
X1555610D03*
X1551870D03*
X1548130D03*
X1563090Y1121948D03*
X1559350D03*
X1555610D03*
X1551870D03*
X1548130D03*
Y1110728D03*
X1561220Y1108858D03*
X1557480D03*
X1553740D03*
X1550000D03*
X1551870Y1110728D03*
X1548130Y1140649D03*
X1563090Y1125688D03*
X1559350D03*
X1555610D03*
X1551870D03*
X1548130D03*
X1559350Y1129429D03*
X1555610D03*
X1551870D03*
X1548130D03*
X1559350Y1133169D03*
X1555610D03*
X1551870D03*
X1548130D03*
X1559350Y1136909D03*
X1551870D03*
X1548130D03*
X1559350Y1140649D03*
X1555610D03*
X1551870D03*
Y1155610D03*
Y1151870D03*
X1559350Y1144389D03*
X1551870D03*
Y1148129D03*
X1559350Y1151870D03*
X1563090Y1155610D03*
Y1148129D03*
X1559350Y1170570D03*
X1551870Y1166830D03*
X1559350Y1159350D03*
X1551870D03*
X1548130Y1170570D03*
X1563090Y1166830D03*
X1551870Y1189271D03*
X1559350Y1185531D03*
X1551870D03*
Y1178051D03*
Y1174310D03*
Y1181791D03*
X1563090D03*
Y1174310D03*
X1550000Y1187401D03*
X1548130Y1185531D03*
X1551870Y1193011D03*
X1559350Y1196751D03*
Y1200491D03*
X1555610D03*
Y1204232D03*
X1559350D03*
X1563090D03*
Y1196751D03*
Y1200491D03*
X1555610Y1193011D03*
Y1196751D03*
X1550000Y1191141D03*
Y1194881D03*
Y1198621D03*
Y1202362D03*
X1555610Y1211712D03*
X1559350D03*
X1563090D03*
Y1207972D03*
X1559350D03*
X1555610D03*
X1563090Y1219192D03*
X1550000Y1221062D03*
X1553740D03*
X1557480D03*
X1561220D03*
X1550000Y1206102D03*
Y1209842D03*
Y1213582D03*
Y1217322D03*
X1553740D03*
X1550000Y1228543D03*
Y1224803D03*
X1557480Y1228543D03*
X1550000Y1232283D03*
Y1236023D03*
X1561220Y1224803D03*
X1557480Y1232283D03*
Y1236023D03*
X1553740Y1224803D03*
X1557480D03*
Y1239763D03*
X1561220Y1243503D03*
X1553740D03*
X1561220Y1250984D03*
Y1254724D03*
X1550000Y1243503D03*
X1557480Y1247243D03*
X1550000D03*
X1557480Y1243503D03*
X1553740Y1250984D03*
Y1254724D03*
X1561220Y1258465D03*
X1553740D03*
X1557050Y1348187D03*
X1552690D03*
Y1360099D03*
X1557050D03*
Y1384297D03*
Y1372385D03*
X1552690D03*
Y1384297D03*
X1557050Y1396583D03*
X1552690D03*
X1557050Y1408495D03*
X1552690D03*
X1576180Y1071455D03*
X1568699D03*
X1564960Y1090157D03*
X1572441D03*
X1576181D03*
X1568700D03*
X1576181Y1105117D03*
X1568700D03*
X1564960Y1093897D03*
Y1097637D03*
X1572441Y1093897D03*
Y1097637D03*
X1576181Y1101377D03*
X1568700D03*
X1566830Y1121948D03*
X1578051Y1118208D03*
X1574311D03*
Y1121948D03*
X1578051D03*
X1570571Y1118208D03*
X1566830D03*
X1570571Y1121948D03*
X1576181Y1108858D03*
X1572441D03*
X1568700D03*
X1564960D03*
X1566830Y1133169D03*
Y1129429D03*
X1570571Y1140649D03*
X1574311D03*
X1578051D03*
X1570571Y1125688D03*
X1574311D03*
X1578051D03*
X1566830D03*
X1578051Y1133169D03*
X1574311D03*
X1570571D03*
X1566830Y1136909D03*
X1574311Y1148129D03*
X1570571D03*
X1578051D03*
X1570571Y1155610D03*
X1566830Y1151869D03*
X1578051Y1155610D03*
X1566830Y1144389D03*
Y1159350D03*
X1578051Y1166830D03*
X1574311Y1159350D03*
X1570571Y1166830D03*
X1566830Y1170570D03*
X1574311D03*
X1578051Y1181791D03*
X1574311D03*
X1570571D03*
X1578051Y1189271D03*
X1574311D03*
X1570571D03*
X1566830D03*
Y1178051D03*
X1570571Y1174310D03*
X1566830Y1185531D03*
X1578051Y1174310D03*
X1574311Y1204232D03*
X1578051D03*
Y1196751D03*
X1574311D03*
X1570571D03*
X1566830Y1200491D03*
Y1196751D03*
Y1193011D03*
Y1204232D03*
X1570571D03*
X1566830Y1207972D03*
Y1211712D03*
X1578051Y1207972D03*
X1574311D03*
X1570571D03*
X1564960Y1221062D03*
X1568700D03*
X1572441D03*
X1576181D03*
X1572441Y1228543D03*
X1564960Y1224803D03*
Y1232283D03*
Y1236023D03*
X1576181Y1224803D03*
X1572441Y1232283D03*
Y1236023D03*
X1568700Y1224803D03*
X1572441D03*
X1564960Y1228543D03*
Y1239763D03*
X1576181Y1243503D03*
X1568700D03*
Y1239763D03*
Y1254724D03*
X1572441Y1247243D03*
X1576181Y1254724D03*
X1564960Y1243503D03*
Y1247243D03*
X1576181Y1250984D03*
X1572441Y1243503D03*
X1568700Y1250984D03*
X1576181Y1258465D03*
X1568701D03*
X1564930Y1348187D03*
X1569290D03*
X1577170D03*
X1569290Y1360099D03*
X1577170D03*
X1564930D03*
X1577170Y1372385D03*
Y1384297D03*
X1569290Y1372385D03*
Y1384297D03*
X1564930D03*
Y1372385D03*
X1577170Y1396583D03*
X1569290D03*
X1564930D03*
X1577170Y1408495D03*
X1569290D03*
X1564930D03*
X1591140Y1071455D03*
X1583660D03*
X1579921Y1090157D03*
X1583661D03*
X1587401D03*
X1591141D03*
X1594882D03*
X1583661Y1105117D03*
X1591141D03*
X1579921Y1093897D03*
Y1097637D03*
X1583661Y1101377D03*
X1587401Y1097637D03*
Y1093897D03*
X1594882D03*
Y1097637D03*
X1591141Y1101377D03*
X1581791Y1121948D03*
X1585531Y1118208D03*
X1589271D03*
X1593011D03*
X1589271Y1121948D03*
X1593011D03*
X1585531D03*
X1581791Y1118208D03*
X1594882Y1108858D03*
X1591141D03*
X1587401D03*
X1583661D03*
X1579921D03*
X1587401Y1112598D03*
X1581791Y1133169D03*
Y1140649D03*
X1585531D03*
X1589271D03*
X1593011D03*
X1589271Y1125688D03*
X1585531D03*
X1581791D03*
X1593011D03*
Y1133169D03*
X1589271D03*
X1585531D03*
X1593011Y1148129D03*
X1589271D03*
X1585531D03*
X1581791D03*
X1593011Y1155610D03*
X1585531D03*
X1589271Y1170570D03*
X1593012Y1166830D03*
X1585531D03*
X1581791Y1159350D03*
X1589271D03*
X1581791Y1170570D03*
X1593011Y1181791D03*
X1589271D03*
X1585531D03*
X1581791D03*
X1593011Y1189271D03*
X1589271D03*
X1585531D03*
X1581791D03*
X1585531Y1174310D03*
X1593011D03*
Y1204232D03*
Y1196751D03*
X1589271D03*
X1585531D03*
X1581791D03*
Y1204232D03*
X1585531D03*
X1589271D03*
X1593011Y1219192D03*
X1591141Y1217322D03*
X1593011Y1207972D03*
X1589271D03*
X1585531D03*
X1581791D03*
X1591141Y1221062D03*
X1587401D03*
X1579921D03*
X1583661D03*
X1594882D03*
Y1224803D03*
X1579921Y1228543D03*
X1594882D03*
X1583661Y1224803D03*
X1579921Y1232283D03*
Y1236023D03*
X1594882Y1232283D03*
Y1236023D03*
X1591141Y1224803D03*
X1587401Y1232283D03*
Y1236023D03*
X1579921Y1224803D03*
X1587401Y1228543D03*
Y1224803D03*
X1583661Y1243503D03*
X1579921Y1239763D03*
X1591141Y1243503D03*
X1594882Y1239763D03*
X1587401D03*
X1583661Y1254724D03*
X1579921Y1247243D03*
X1591141Y1254724D03*
X1587401Y1247243D03*
Y1243503D03*
X1594882D03*
X1579921D03*
X1594882Y1247243D03*
X1583661Y1250984D03*
X1591141D03*
X1591142Y1258465D03*
X1583661D03*
X1589410Y1348187D03*
X1581530D03*
X1589410Y1360099D03*
X1581530D03*
Y1384297D03*
Y1372385D03*
X1589410Y1384297D03*
Y1372385D03*
X1581530Y1396583D03*
X1589410D03*
X1581530Y1408495D03*
X1589410D03*
X1609842Y1075196D03*
X1606101Y1071454D03*
X1598621Y1071455D03*
X1606101Y1075195D03*
X1598622Y1090157D03*
X1606102Y1082677D03*
Y1086417D03*
X1609842Y1090157D03*
X1606102D03*
X1602362D03*
X1609841Y1086416D03*
X1606101Y1078935D03*
X1609841Y1082676D03*
X1598622Y1105117D03*
X1606102D03*
X1598622Y1101377D03*
X1606102D03*
X1609842Y1093897D03*
X1602362D03*
Y1097637D03*
X1596752Y1121948D03*
X1600492Y1118208D03*
Y1114468D03*
X1611712Y1121948D03*
X1607972D03*
X1596752Y1118208D03*
X1600492Y1121948D03*
X1609842Y1108858D03*
X1606102D03*
X1602362D03*
X1598622D03*
X1607972Y1125688D03*
X1611712D03*
X1607972Y1133464D03*
X1611712Y1133169D03*
X1600590Y1132677D03*
X1596752Y1133169D03*
Y1140649D03*
X1600492D03*
Y1125688D03*
X1596752D03*
X1607972Y1140649D03*
X1611712D03*
X1600492Y1148129D03*
X1596752D03*
X1607972D03*
X1611712D03*
X1600492Y1155610D03*
X1611712D03*
X1596752Y1170570D03*
Y1159350D03*
X1611712Y1166830D03*
X1607972Y1170570D03*
X1600492Y1166830D03*
X1607972Y1159350D03*
X1600492Y1181791D03*
X1611712D03*
X1607972D03*
Y1189271D03*
X1611712D03*
X1596752Y1181791D03*
X1600492Y1189271D03*
X1596752D03*
X1600492Y1174310D03*
X1611712D03*
Y1204232D03*
X1607972D03*
Y1196751D03*
X1611712D03*
X1600492D03*
X1596752D03*
Y1204232D03*
X1600492D03*
X1606102Y1221062D03*
X1596752Y1207972D03*
X1607972D03*
X1611712D03*
Y1211712D03*
X1596752Y1219192D03*
X1600492Y1207972D03*
X1598622Y1221062D03*
X1609842D03*
X1602362D03*
Y1224803D03*
X1598622D03*
X1609842Y1232283D03*
Y1236023D03*
X1606102Y1228543D03*
Y1224803D03*
X1602362Y1232283D03*
Y1236023D03*
X1598622Y1243503D03*
X1609842Y1239763D03*
X1602362D03*
X1598622Y1254724D03*
Y1250984D03*
X1609842Y1247243D03*
Y1243503D03*
X1602362Y1247243D03*
Y1243503D03*
X1606102Y1258465D03*
X1598623D03*
X1609158Y1348187D03*
Y1360099D03*
Y1384297D03*
Y1372385D03*
X1624803Y1075196D03*
X1617322D03*
X1621062Y1071455D03*
X1613581D03*
Y1075196D03*
X1621062D03*
X1617322Y1090157D03*
Y1078936D03*
X1613582Y1090157D03*
Y1086417D03*
X1624803Y1078936D03*
X1621063Y1086417D03*
Y1090157D03*
X1624803D03*
X1613581Y1078936D03*
X1624802Y1082676D03*
X1617321Y1082677D03*
X1621062Y1078936D03*
X1617321Y1086417D03*
X1624802Y1086416D03*
X1621062Y1093897D03*
X1617322D03*
Y1097637D03*
X1624803Y1093897D03*
Y1097637D03*
X1621063Y1105117D03*
X1613582D03*
Y1101377D03*
X1621062Y1097637D03*
X1626673Y1121948D03*
X1622933D03*
X1619193D03*
X1615452D03*
X1624803Y1108858D03*
X1621063D03*
X1617322D03*
X1613582D03*
X1615452Y1133169D03*
X1619193D03*
X1622933D03*
X1626673D03*
X1615452Y1140649D03*
X1619193D03*
X1622933D03*
X1626673D03*
X1615452Y1125688D03*
X1619193D03*
X1622933D03*
X1626673D03*
X1615452Y1148129D03*
X1619193D03*
X1622933D03*
X1626673D03*
X1619193Y1155610D03*
X1626673D03*
X1615452Y1170570D03*
X1622933D03*
X1626673Y1166830D03*
X1615452Y1159350D03*
X1619193Y1166830D03*
X1622933Y1159350D03*
X1615452Y1181791D03*
X1619193D03*
X1622933D03*
X1626673D03*
X1615452Y1189271D03*
X1619193D03*
X1622933D03*
X1626673D03*
Y1174310D03*
X1619193D03*
Y1204232D03*
X1615452D03*
X1626673D03*
X1622933D03*
X1615452Y1196751D03*
X1619193D03*
X1622933D03*
X1626673D03*
X1617322Y1221062D03*
X1619193Y1207972D03*
X1622933D03*
X1626673Y1211712D03*
Y1207972D03*
X1615452Y1211712D03*
Y1207972D03*
X1621063Y1221062D03*
X1613582D03*
X1624803D03*
X1613582Y1228543D03*
Y1224803D03*
X1621063Y1228543D03*
Y1224803D03*
X1624803Y1232283D03*
Y1236023D03*
X1617322Y1232283D03*
Y1236023D03*
Y1239763D03*
X1624803Y1247243D03*
Y1243503D03*
X1617322D03*
Y1247243D03*
X1621063Y1258465D03*
X1613582D03*
X1617038Y1348187D03*
X1621398D03*
X1617038Y1360099D03*
X1621398D03*
X1617038Y1384297D03*
Y1372385D03*
X1621398D03*
Y1384297D03*
Y1396583D03*
Y1408495D03*
X1639763Y1075196D03*
X1632283D03*
X1643503Y1071455D03*
X1636022D03*
X1628542D03*
X1636022Y1075196D03*
X1643503D03*
X1628542D03*
X1636023Y1090157D03*
X1643504Y1082677D03*
X1636023Y1086417D03*
X1643504Y1090157D03*
Y1086417D03*
X1639763Y1090157D03*
Y1078936D03*
X1632283D03*
X1628543Y1086417D03*
Y1090157D03*
X1632283D03*
X1632282Y1082677D03*
X1643503Y1078936D03*
X1628542D03*
X1639762Y1086416D03*
X1632282Y1086417D03*
X1636022Y1078936D03*
X1639762Y1082676D03*
X1628542Y1093897D03*
X1632283D03*
Y1097637D03*
X1639763Y1093897D03*
Y1097637D03*
X1628543Y1105117D03*
X1636023D03*
X1643504D03*
X1628542Y1097637D03*
X1641633Y1118208D03*
X1637893Y1121948D03*
X1634153D03*
X1630413D03*
X1641633D03*
X1643504Y1108858D03*
X1639763D03*
X1636023D03*
X1632283D03*
X1628543D03*
X1641633Y1136909D03*
X1630413Y1133169D03*
X1634153D03*
X1637893D03*
X1641633D03*
X1634153Y1140649D03*
X1637893D03*
X1641633Y1125688D03*
Y1129429D03*
X1630413Y1125688D03*
X1634153D03*
X1637893D03*
X1641633Y1140649D03*
X1630413D03*
Y1148129D03*
X1634153D03*
X1637893D03*
X1641633Y1144389D03*
Y1148129D03*
Y1151869D03*
X1634153Y1155610D03*
X1641633D03*
X1634153Y1166830D03*
X1630413Y1159350D03*
Y1170570D03*
X1634153Y1189271D03*
X1637893D03*
X1641633Y1178051D03*
X1634153Y1174310D03*
X1641633Y1185531D03*
X1630413Y1181791D03*
X1634153D03*
X1637893D03*
X1641633Y1189271D03*
X1630413D03*
X1641633Y1174310D03*
X1641653Y1196732D03*
X1641633Y1204232D03*
X1630413D03*
X1634153D03*
X1637893D03*
X1641633Y1200491D03*
X1630413Y1196751D03*
X1634153D03*
X1637893D03*
X1641633Y1193011D03*
Y1211712D03*
X1634153Y1207972D03*
X1630413D03*
X1634153Y1211712D03*
X1637893Y1207972D03*
Y1211712D03*
X1630413D03*
X1641633Y1207972D03*
X1628543Y1221062D03*
X1632283D03*
X1636023D03*
X1639763D03*
X1643504D03*
X1628543Y1228543D03*
Y1224803D03*
X1632283Y1232283D03*
Y1236023D03*
X1636023Y1228543D03*
Y1224803D03*
X1639763Y1232283D03*
Y1236023D03*
X1643504Y1228543D03*
Y1224803D03*
X1628543Y1239763D03*
X1639763D03*
X1632283Y1243503D03*
X1639763D03*
X1632283Y1247243D03*
X1639763D03*
X1643504Y1258465D03*
X1636023D03*
X1628543D03*
X1629278Y1348187D03*
X1641518D03*
X1633638D03*
X1629278Y1360099D03*
X1641518D03*
X1633638D03*
X1629278Y1384297D03*
Y1372385D03*
X1641518Y1384297D03*
Y1372385D03*
X1633638Y1384297D03*
Y1372385D03*
X1629278Y1396583D03*
X1641518D03*
X1633638D03*
Y1408495D03*
X1629278D03*
X1641518D03*
X1647244Y1075196D03*
X1654724D03*
X1658463Y1071455D03*
X1650983D03*
Y1075196D03*
X1658463D03*
X1654724Y1078936D03*
Y1090157D03*
X1658464D03*
X1650984D03*
X1647244D03*
X1654723Y1086416D03*
Y1082676D03*
X1650983Y1078936D03*
X1647242Y1082677D03*
Y1086417D03*
X1658463Y1078936D03*
X1647244Y1093897D03*
X1658464Y1101377D03*
Y1105117D03*
X1650984D03*
X1645374Y1118208D03*
X1649114D03*
X1658464Y1108858D03*
X1654724D03*
X1650984D03*
X1647244D03*
X1649114Y1140649D03*
X1652854Y1136909D03*
X1645374Y1125688D03*
X1649114Y1136909D03*
X1652854Y1140649D03*
X1645374Y1155610D03*
Y1151869D03*
Y1148129D03*
X1652854D03*
X1649114Y1144389D03*
X1652854Y1155610D03*
X1649114Y1148129D03*
X1652854Y1151869D03*
X1656594D03*
X1660334D03*
Y1155610D03*
X1649114Y1151870D03*
X1645374Y1166830D03*
X1652854Y1159350D03*
X1660334Y1166830D03*
Y1170570D03*
X1645374Y1159350D03*
X1660334D03*
X1645374Y1170570D03*
X1652854D03*
Y1166830D03*
Y1185531D03*
X1656594Y1181791D03*
X1652854Y1178051D03*
Y1174310D03*
X1649114Y1181791D03*
X1656594Y1185531D03*
X1660334Y1174310D03*
Y1178051D03*
Y1185531D03*
X1645374Y1181791D03*
Y1174310D03*
X1649114Y1178051D03*
Y1189271D03*
X1652854D03*
X1649114Y1185531D03*
X1656594Y1193011D03*
X1652854Y1204232D03*
Y1196751D03*
Y1193011D03*
X1649114D03*
X1645374Y1196751D03*
X1649114Y1211712D03*
X1645374Y1207972D03*
X1660334Y1215452D03*
Y1211712D03*
X1654724Y1221062D03*
X1658464D03*
X1650984D03*
X1647244D03*
Y1232283D03*
Y1236023D03*
X1654724Y1232283D03*
X1658464Y1228543D03*
X1654724Y1236023D03*
X1658464Y1224803D03*
X1650984Y1228543D03*
Y1224803D03*
X1654724Y1239763D03*
Y1243503D03*
X1647244Y1247243D03*
X1654724D03*
X1647244Y1243503D03*
X1658464Y1258465D03*
X1650984D03*
X1645878Y1348187D03*
X1653758D03*
X1658118D03*
X1645878Y1360099D03*
X1653758D03*
X1658118D03*
X1645878Y1384297D03*
Y1372385D03*
X1653758D03*
Y1384297D03*
X1658118D03*
Y1372385D03*
X1645878Y1396583D03*
X1653758D03*
X1658118D03*
X1645878Y1408495D03*
X1653758D03*
X1658118D03*
X1662204Y1075196D03*
X1669685D03*
X1673425Y1071455D03*
X1665944D03*
X1673424Y1075196D03*
X1665944D03*
X1662203Y1090157D03*
X1669686Y1078936D03*
X1669684Y1090157D03*
X1662203Y1086417D03*
Y1082677D03*
X1669684Y1086416D03*
X1665944Y1078936D03*
X1673424D03*
X1669684Y1082676D03*
X1662204Y1093897D03*
X1669685D03*
X1673425Y1105117D03*
X1665945D03*
X1669685Y1108858D03*
X1673425Y1116338D03*
Y1123818D03*
X1665944Y1112598D03*
Y1120078D03*
X1665945Y1108858D03*
X1662204Y1123818D03*
Y1120078D03*
Y1116338D03*
Y1108858D03*
X1671555Y1140649D03*
X1673425Y1131299D03*
X1662204Y1135039D03*
Y1131299D03*
Y1127558D03*
Y1138779D03*
X1664074Y1151869D03*
X1671555Y1148129D03*
X1664074Y1144389D03*
Y1159350D03*
X1671555D03*
X1664074Y1166830D03*
X1671555D03*
X1664074Y1189271D03*
Y1174310D03*
X1671555Y1181791D03*
Y1174310D03*
X1664074Y1181791D03*
X1671555Y1189271D03*
X1665945Y1194881D03*
X1664074Y1204232D03*
X1669685Y1202362D03*
X1673425Y1221062D03*
X1669685Y1209842D03*
X1665945Y1221062D03*
Y1217322D03*
X1662204Y1221062D03*
Y1232283D03*
Y1236023D03*
X1673425Y1224803D03*
Y1228543D03*
X1669685Y1232283D03*
Y1236023D03*
X1665945Y1224803D03*
Y1228543D03*
X1662204Y1239763D03*
X1669685D03*
X1673425Y1250984D03*
X1662204Y1247243D03*
X1665945Y1254724D03*
X1673425D03*
X1662204Y1243503D03*
X1665945Y1250984D03*
X1669685Y1247243D03*
Y1243503D03*
X1673425Y1258465D03*
X1665945D03*
X1665998Y1348187D03*
X1670358D03*
X1665998Y1360099D03*
X1670358D03*
X1665998Y1384297D03*
Y1372385D03*
X1670358D03*
Y1384297D03*
X1665998Y1396583D03*
X1670358D03*
X1665998Y1408495D03*
X1670358D03*
X1677166Y1075196D03*
X1684646D03*
X1692126D03*
X1688385Y1071455D03*
X1680905D03*
X1680904Y1075196D03*
X1688384D03*
X1677166Y1078936D03*
X1692126D03*
X1684646D03*
X1684644Y1090157D03*
Y1082677D03*
Y1086417D03*
X1680904Y1078936D03*
X1688384D03*
X1677164Y1086417D03*
Y1082677D03*
X1677165Y1093897D03*
X1684645D03*
X1680905Y1105117D03*
X1677164Y1108857D03*
X1684645Y1108858D03*
X1690256Y1140649D03*
Y1155610D03*
Y1148129D03*
X1682775Y1166830D03*
X1679035Y1170570D03*
X1690256D03*
Y1178051D03*
X1682775Y1174310D03*
X1679035Y1178051D03*
X1682775Y1181791D03*
X1679035Y1185531D03*
X1682775Y1189271D03*
X1690256Y1185531D03*
X1680905Y1194881D03*
X1690256Y1193011D03*
X1679035D03*
X1692126Y1202362D03*
X1680905D03*
Y1198621D03*
X1677165D03*
X1684645Y1221062D03*
X1692126Y1209842D03*
X1680905Y1221062D03*
Y1217322D03*
X1677165Y1221062D03*
Y1213582D03*
X1680905D03*
Y1209842D03*
Y1206102D03*
X1692126D03*
X1688385Y1224803D03*
Y1228543D03*
X1684645Y1236023D03*
Y1232283D03*
X1692126D03*
X1680905Y1224803D03*
Y1228543D03*
X1677165Y1232283D03*
Y1236023D03*
X1680905Y1239763D03*
X1684645Y1243503D03*
X1677165D03*
X1684645Y1247243D03*
X1677165D03*
X1688385Y1254724D03*
Y1250984D03*
X1692126Y1239763D03*
X1680905Y1254724D03*
Y1250984D03*
X1688385Y1258465D03*
X1680905D03*
X1678238Y1348187D03*
X1690478D03*
X1682598D03*
X1678238Y1360099D03*
X1690478D03*
X1682598D03*
X1678238Y1372385D03*
Y1384297D03*
X1690478D03*
Y1372385D03*
X1682598Y1384297D03*
Y1372385D03*
X1678238Y1396583D03*
X1690478D03*
X1682598D03*
X1678238Y1408495D03*
X1690478D03*
X1682598D03*
X1695866Y1078936D03*
X1699607Y1090158D03*
Y1082677D03*
Y1101378D03*
Y1123819D03*
Y1116339D03*
Y1108859D03*
Y1131300D03*
X1693996Y1170570D03*
Y1178051D03*
Y1185531D03*
Y1193011D03*
X1697676D03*
X1695866Y1202362D03*
X1699607Y1198621D03*
Y1221062D03*
Y1213582D03*
Y1206102D03*
Y1228543D03*
X1695866Y1250984D03*
X1699607Y1247243D03*
Y1239762D03*
X1695866Y1239763D03*
X1694838Y1348187D03*
X1702718D03*
X1707078D03*
X1702718Y1360099D03*
X1707078D03*
X1694838D03*
Y1384297D03*
Y1372385D03*
X1702718D03*
Y1384297D03*
X1707078D03*
Y1372385D03*
X1694838Y1396583D03*
X1702718D03*
X1707078D03*
X1694838Y1408495D03*
X1702718D03*
X1707078D03*
X1714958Y1348187D03*
X1719318D03*
X1714958Y1360099D03*
X1719318D03*
X1714958Y1384297D03*
Y1372385D03*
X1719318D03*
Y1384297D03*
X1714958Y1396583D03*
X1719318D03*
X1714958Y1408495D03*
X1719318D03*
X1727198Y1348187D03*
X1739438D03*
X1731558D03*
X1727198Y1360099D03*
X1739438D03*
X1731558D03*
X1739438Y1372385D03*
X1731558Y1384297D03*
Y1372385D03*
X1727198D03*
Y1384297D03*
X1739438D03*
X1727198Y1396583D03*
X1739438D03*
X1731558D03*
X1727198Y1408495D03*
X1739438D03*
X1731558D03*
G54D49*
X956448Y-30304D03*
Y-33204D03*
X953192Y-25085D03*
X956445Y-25099D03*
X950167Y-26405D03*
X953207Y-27600D03*
X956460Y-27614D03*
X978036Y-64265D03*
X975011Y-65585D03*
X978051Y-66780D03*
X981289Y-64279D03*
X981292Y-69484D03*
Y-72384D03*
X981304Y-66794D03*
X1231351Y-77080D03*
X1234592Y-79984D03*
X1234604Y-77094D03*
X1234592Y-82584D03*
Y-71970D03*
X1231336Y-74565D03*
X1234589Y-74579D03*
X1231336Y-64265D03*
X1234589D03*
X1234592Y-69470D03*
X1231351Y-66780D03*
X1234604D03*
X1228311Y-65585D03*
Y-75885D03*
X1236692Y-35515D03*
X1236707Y-38030D03*
X1233667Y-36835D03*
X1236692Y-25215D03*
X1236707Y-27730D03*
X1233667Y-26535D03*
X1239948Y-32920D03*
X1239945Y-35529D03*
X1239948Y-30420D03*
Y-40934D03*
X1239960Y-38044D03*
X1239948Y-43534D03*
X1239945Y-25215D03*
X1239960Y-27730D03*
X1487851Y-77080D03*
X1491092Y-79984D03*
X1491104Y-77094D03*
X1491092Y-82584D03*
Y-71970D03*
X1487836Y-74565D03*
X1491089Y-74579D03*
X1487836Y-64265D03*
X1491089D03*
X1491092Y-69470D03*
X1487851Y-66780D03*
X1491104D03*
X1484811Y-65585D03*
Y-75885D03*
X1526448Y-33050D03*
X1523192Y-35645D03*
X1526445Y-35659D03*
X1526448Y-30550D03*
X1523207Y-38160D03*
X1526448Y-41064D03*
X1526460Y-38174D03*
X1526448Y-43664D03*
X1520167Y-36965D03*
X1523192Y-25345D03*
X1526445D03*
X1523207Y-27860D03*
X1526460D03*
X1520167Y-26665D03*
X1742336Y-74565D03*
Y-64265D03*
X1739311Y-65585D03*
Y-75885D03*
X1742351Y-77080D03*
X1745592Y-79984D03*
X1745604Y-77094D03*
X1745592Y-82584D03*
Y-71970D03*
X1745589Y-74579D03*
Y-64265D03*
X1745592Y-69470D03*
X1742351Y-66780D03*
X1745604D03*
X1804667Y-37095D03*
Y-26795D03*
X1810948Y-33180D03*
X1807692Y-35775D03*
X1810945Y-35789D03*
X1810948Y-30680D03*
X1807707Y-38290D03*
X1810948Y-41194D03*
X1810960Y-38304D03*
X1810948Y-43794D03*
X1807692Y-25475D03*
X1810945D03*
X1807707Y-27990D03*
X1810960D03*
G54D23*
X46348Y1727941D03*
Y1737941D03*
Y1773941D03*
Y1783941D03*
X333112Y1751624D03*
Y1761624D03*
X333212Y1797624D03*
Y1807624D03*
X619861Y1751765D03*
Y1761765D03*
X619475Y1798845D03*
Y1808845D03*
X907163Y1752566D03*
Y1762566D03*
X907166Y1800435D03*
Y1810435D03*
G54D38*
X266841Y421555D03*
Y550020D03*
X295856Y421555D03*
Y550020D03*
X723927Y421555D03*
Y550020D03*
X752942Y421555D03*
Y550020D03*
X1181014Y421555D03*
Y550020D03*
X1210029Y421555D03*
Y550020D03*
X1638101Y421555D03*
Y550020D03*
X1667116Y421555D03*
Y550020D03*
G54D54*
X1236871Y1715189D03*
X1236864Y1773377D03*
X1235371Y1802909D03*
G54D55*
X1236871Y1744208D03*
%LPC*%
G75*
G54D62*
G01X-20602Y-468335D02*
Y-543335D01*
X479398D01*
Y-468335D01*
X-20602D01*
G01X-8602Y-533335D02*
Y-538335D01*
G01X-10059Y-533335D02*
X-7145D01*
G01X-2235Y-538335D02*
X-4769D01*
Y-533335D01*
X-2235D01*
G01X-3249Y-535752D02*
X-4769D01*
G01X331Y-533335D02*
Y-538335D01*
X2865D01*
G01X6698Y-538502D02*
X6571Y-538418D01*
Y-538252D01*
X6698Y-538168D01*
X6825Y-538252D01*
Y-538418D01*
X6698Y-538502D01*
G01Y-536252D02*
X6571Y-536168D01*
Y-536002D01*
X6698Y-535918D01*
X6825Y-536002D01*
Y-536168D01*
X6698Y-536252D01*
G01X11481Y-540002D02*
X10848Y-539168D01*
X10531Y-538335D01*
Y-535002D01*
X10848Y-534168D01*
X11481Y-533335D01*
G01X16898D02*
X16391Y-533502D01*
X16011Y-533918D01*
X15758Y-534418D01*
X15568Y-535085D01*
X15505Y-535835D01*
X15568Y-536585D01*
X15758Y-537252D01*
X16011Y-537752D01*
X16391Y-538168D01*
X16898Y-538335D01*
X17405Y-538168D01*
X17785Y-537752D01*
X18038Y-537252D01*
X18228Y-536585D01*
X18291Y-535835D01*
X18228Y-535085D01*
X18038Y-534418D01*
X17785Y-533918D01*
X17405Y-533502D01*
X16898Y-533335D01*
G01X20605Y-537335D02*
X20985Y-537918D01*
X21491Y-538252D01*
X22061Y-538335D01*
X22568Y-538252D01*
X23075Y-537835D01*
X23391Y-537335D01*
X23455Y-536835D01*
X23328Y-536252D01*
X22885Y-535835D01*
X22441Y-535668D01*
X21871D01*
G01X22441D02*
X22821Y-535418D01*
X23138Y-535002D01*
X23265Y-534502D01*
X23138Y-534002D01*
X22821Y-533585D01*
X22251Y-533335D01*
X21681Y-533418D01*
X21111Y-533752D01*
G01X27415Y-540002D02*
X28048Y-539168D01*
X28365Y-538335D01*
Y-535002D01*
X28048Y-534168D01*
X27415Y-533335D01*
G01X30805Y-537335D02*
X31185Y-537918D01*
X31691Y-538252D01*
X32261Y-538335D01*
X32768Y-538252D01*
X33275Y-537835D01*
X33591Y-537335D01*
X33655Y-536835D01*
X33528Y-536252D01*
X33085Y-535835D01*
X32641Y-535668D01*
X32071D01*
G01X32641D02*
X33021Y-535418D01*
X33338Y-535002D01*
X33465Y-534502D01*
X33338Y-534002D01*
X33021Y-533585D01*
X32451Y-533335D01*
X31881Y-533418D01*
X31311Y-533752D01*
G01X36095Y-534168D02*
X36475Y-533668D01*
X36918Y-533418D01*
X37425Y-533335D01*
X38058Y-533502D01*
X38501Y-533918D01*
X38628Y-534418D01*
X38565Y-534918D01*
X38311Y-535335D01*
X37045Y-536168D01*
X36475Y-536752D01*
X36095Y-537585D01*
X35968Y-538335D01*
X38628D01*
G01X42271D02*
X42398Y-537252D01*
X42588Y-536335D01*
X42841Y-535502D01*
X43158Y-534585D01*
X43665Y-533335D01*
X41131D01*
G01X46675Y-536668D02*
X48321D01*
G01X51395Y-534168D02*
X51775Y-533668D01*
X52218Y-533418D01*
X52725Y-533335D01*
X53358Y-533502D01*
X53801Y-533918D01*
X53928Y-534418D01*
X53865Y-534918D01*
X53611Y-535335D01*
X52345Y-536168D01*
X51775Y-536752D01*
X51395Y-537585D01*
X51268Y-538335D01*
X53928D01*
G01X56305Y-537335D02*
X56685Y-537918D01*
X57191Y-538252D01*
X57761Y-538335D01*
X58268Y-538252D01*
X58775Y-537835D01*
X59091Y-537335D01*
X59155Y-536835D01*
X59028Y-536252D01*
X58585Y-535835D01*
X58141Y-535668D01*
X57571D01*
G01X58141D02*
X58521Y-535418D01*
X58838Y-535002D01*
X58965Y-534502D01*
X58838Y-534002D01*
X58521Y-533585D01*
X57951Y-533335D01*
X57381Y-533418D01*
X56811Y-533752D01*
G01X63558Y-538335D02*
Y-533335D01*
X61215Y-536918D01*
X64381D01*
G01X66505Y-537585D02*
X66885Y-538002D01*
X67328Y-538252D01*
X67898Y-538335D01*
X68468Y-538168D01*
X68911Y-537835D01*
X69228Y-537252D01*
X69291Y-536585D01*
X69165Y-535918D01*
X68848Y-535502D01*
X68405Y-535168D01*
X67961Y-535085D01*
X67518Y-535168D01*
X66948Y-535502D01*
X67138Y-533335D01*
X68848D01*
G01X76895Y-538335D02*
Y-533335D01*
X79301D01*
G01X78415Y-535752D02*
X76895D01*
G01X81615Y-538335D02*
X83198Y-533335D01*
X84781Y-538335D01*
G01X84211Y-536585D02*
X82185D01*
G01X86968Y-538335D02*
X89628Y-533335D01*
G01X86968D02*
X89628Y-538335D01*
G01X93398Y-538502D02*
X93271Y-538418D01*
Y-538252D01*
X93398Y-538168D01*
X93525Y-538252D01*
Y-538418D01*
X93398Y-538502D01*
G01Y-536252D02*
X93271Y-536168D01*
Y-536002D01*
X93398Y-535918D01*
X93525Y-536002D01*
Y-536168D01*
X93398Y-536252D01*
G01X98181Y-540002D02*
X97548Y-539168D01*
X97231Y-538335D01*
Y-535002D01*
X97548Y-534168D01*
X98181Y-533335D01*
G01X103598D02*
X103091Y-533502D01*
X102711Y-533918D01*
X102458Y-534418D01*
X102268Y-535085D01*
X102205Y-535835D01*
X102268Y-536585D01*
X102458Y-537252D01*
X102711Y-537752D01*
X103091Y-538168D01*
X103598Y-538335D01*
X104105Y-538168D01*
X104485Y-537752D01*
X104738Y-537252D01*
X104928Y-536585D01*
X104991Y-535835D01*
X104928Y-535085D01*
X104738Y-534418D01*
X104485Y-533918D01*
X104105Y-533502D01*
X103598Y-533335D01*
G01X107305Y-537335D02*
X107685Y-537918D01*
X108191Y-538252D01*
X108761Y-538335D01*
X109268Y-538252D01*
X109775Y-537835D01*
X110091Y-537335D01*
X110155Y-536835D01*
X110028Y-536252D01*
X109585Y-535835D01*
X109141Y-535668D01*
X108571D01*
G01X109141D02*
X109521Y-535418D01*
X109838Y-535002D01*
X109965Y-534502D01*
X109838Y-534002D01*
X109521Y-533585D01*
X108951Y-533335D01*
X108381Y-533418D01*
X107811Y-533752D01*
G01X114115Y-540002D02*
X114748Y-539168D01*
X115065Y-538335D01*
Y-535002D01*
X114748Y-534168D01*
X114115Y-533335D01*
G01X117505Y-537335D02*
X117885Y-537918D01*
X118391Y-538252D01*
X118961Y-538335D01*
X119468Y-538252D01*
X119975Y-537835D01*
X120291Y-537335D01*
X120355Y-536835D01*
X120228Y-536252D01*
X119785Y-535835D01*
X119341Y-535668D01*
X118771D01*
G01X119341D02*
X119721Y-535418D01*
X120038Y-535002D01*
X120165Y-534502D01*
X120038Y-534002D01*
X119721Y-533585D01*
X119151Y-533335D01*
X118581Y-533418D01*
X118011Y-533752D01*
G01X122921Y-537752D02*
X123365Y-538168D01*
X123871Y-538335D01*
X124378Y-538168D01*
X124821Y-537668D01*
X125138Y-536918D01*
X125265Y-536168D01*
Y-535252D01*
X125138Y-534502D01*
X124821Y-533835D01*
X124441Y-533502D01*
X123998Y-533335D01*
X123491Y-533502D01*
X123111Y-533835D01*
X122858Y-534335D01*
X122731Y-535002D01*
X122858Y-535585D01*
X123175Y-536168D01*
X123555Y-536502D01*
X123998Y-536585D01*
X124505Y-536418D01*
X124885Y-536002D01*
X125265Y-535252D01*
G01X128971Y-538335D02*
X129098Y-537252D01*
X129288Y-536335D01*
X129541Y-535502D01*
X129858Y-534585D01*
X130365Y-533335D01*
X127831D01*
G01X133375Y-536668D02*
X135021D01*
G01X137905Y-537335D02*
X138285Y-537918D01*
X138791Y-538252D01*
X139361Y-538335D01*
X139868Y-538252D01*
X140375Y-537835D01*
X140691Y-537335D01*
X140755Y-536835D01*
X140628Y-536252D01*
X140185Y-535835D01*
X139741Y-535668D01*
X139171D01*
G01X139741D02*
X140121Y-535418D01*
X140438Y-535002D01*
X140565Y-534502D01*
X140438Y-534002D01*
X140121Y-533585D01*
X139551Y-533335D01*
X138981Y-533418D01*
X138411Y-533752D01*
G01X143195Y-536252D02*
X143638Y-535668D01*
X144018Y-535335D01*
X144525Y-535168D01*
X144968Y-535335D01*
X145285Y-535668D01*
X145538Y-536168D01*
X145601Y-536752D01*
X145538Y-537252D01*
X145285Y-537752D01*
X144905Y-538168D01*
X144461Y-538335D01*
X143955Y-538168D01*
X143511Y-537668D01*
X143258Y-536918D01*
X143195Y-536085D01*
X143321Y-535002D01*
X143511Y-534418D01*
X143828Y-533835D01*
X144271Y-533418D01*
X144715Y-533335D01*
X145158Y-533502D01*
X145475Y-533918D01*
G01X149498Y-538335D02*
Y-533335D01*
X148738Y-534335D01*
G01Y-538335D02*
X150258D01*
G01X155358D02*
Y-533335D01*
X153015Y-536918D01*
X156181D01*
G01X174398Y-468335D02*
Y-543335D01*
G01Y-518335D02*
X277398D01*
Y-493335D01*
G01X174398D02*
X277398D01*
G01Y-468335D02*
Y-543335D01*
G01X279398Y-468335D02*
Y-543335D01*
G01X284905Y-528335D02*
Y-523335D01*
X286171D01*
X286678Y-523585D01*
X287058Y-523918D01*
X287375Y-524418D01*
X287628Y-525002D01*
X287691Y-525835D01*
X287628Y-526668D01*
X287375Y-527252D01*
X287058Y-527752D01*
X286678Y-528085D01*
X286171Y-528335D01*
X284905D01*
G01X289815D02*
X291398Y-523335D01*
X292981Y-528335D01*
G01X292411Y-526585D02*
X290385D01*
G01X296498Y-523335D02*
Y-528335D01*
G01X295041Y-523335D02*
X297955D01*
G01X302865Y-528335D02*
X300331D01*
Y-523335D01*
X302865D01*
G01X301851Y-525752D02*
X300331D01*
G01X306698Y-528502D02*
X306571Y-528418D01*
Y-528252D01*
X306698Y-528168D01*
X306825Y-528252D01*
Y-528418D01*
X306698Y-528502D01*
G01Y-526252D02*
X306571Y-526168D01*
Y-526002D01*
X306698Y-525918D01*
X306825Y-526002D01*
Y-526168D01*
X306698Y-526252D01*
G01X279398Y-518335D02*
X479398D01*
G01X285031Y-503335D02*
Y-498335D01*
X286551D01*
X287058Y-498585D01*
X287438Y-499168D01*
X287565Y-499835D01*
X287438Y-500502D01*
X287121Y-501002D01*
X286551Y-501252D01*
X285031D01*
G01X290258Y-503502D02*
X292538Y-498335D01*
G01X295041Y-503335D02*
Y-498335D01*
X297955Y-503335D01*
Y-498335D01*
G01X301598Y-503502D02*
X301471Y-503418D01*
Y-503252D01*
X301598Y-503168D01*
X301725Y-503252D01*
Y-503418D01*
X301598Y-503502D01*
G01Y-501252D02*
X301471Y-501168D01*
Y-501002D01*
X301598Y-500918D01*
X301725Y-501002D01*
Y-501168D01*
X301598Y-501252D01*
G01X279398Y-493335D02*
X479398D01*
G01X285031Y-478335D02*
Y-473335D01*
X286551D01*
X287058Y-473585D01*
X287438Y-474168D01*
X287565Y-474835D01*
X287438Y-475502D01*
X287121Y-476002D01*
X286551Y-476252D01*
X285031D01*
G01X290131Y-478335D02*
Y-473335D01*
X291715D01*
X292221Y-473585D01*
X292538Y-473918D01*
X292665Y-474585D01*
X292538Y-475252D01*
X292158Y-475668D01*
X291715Y-475918D01*
X290131D01*
G01X291715D02*
X292665Y-478335D01*
G01X296498D02*
X295991Y-478252D01*
X295548Y-477918D01*
X295168Y-477418D01*
X294915Y-476835D01*
X294788Y-476168D01*
Y-475502D01*
X294915Y-474835D01*
X295168Y-474252D01*
X295548Y-473752D01*
X295991Y-473418D01*
X296498Y-473335D01*
X297005Y-473418D01*
X297448Y-473752D01*
X297828Y-474252D01*
X298081Y-474835D01*
X298208Y-475502D01*
Y-476168D01*
X298081Y-476835D01*
X297828Y-477418D01*
X297448Y-477918D01*
X297005Y-478252D01*
X296498Y-478335D01*
G01X300331Y-477335D02*
X300648Y-477835D01*
X301028Y-478168D01*
X301471Y-478335D01*
X301978Y-478168D01*
X302358Y-477835D01*
X302738Y-477335D01*
X302865Y-476668D01*
Y-473335D01*
G01X307965Y-478335D02*
X305431D01*
Y-473335D01*
X307965D01*
G01X306951Y-475752D02*
X305431D01*
G01X313191Y-473752D02*
X312811Y-473502D01*
X312368Y-473335D01*
X311861D01*
X311291Y-473585D01*
X310848Y-474002D01*
X310531Y-474502D01*
X310278Y-475335D01*
X310215Y-476085D01*
X310341Y-476835D01*
X310531Y-477335D01*
X310911Y-477835D01*
X311355Y-478168D01*
X311798Y-478335D01*
X312241D01*
X312685Y-478168D01*
X313065Y-477918D01*
X313381Y-477585D01*
G01X316898Y-473335D02*
Y-478335D01*
G01X315441Y-473335D02*
X318355D01*
G01X321998Y-478502D02*
X321871Y-478418D01*
Y-478252D01*
X321998Y-478168D01*
X322125Y-478252D01*
Y-478418D01*
X321998Y-478502D01*
G01Y-476252D02*
X321871Y-476168D01*
Y-476002D01*
X321998Y-475918D01*
X322125Y-476002D01*
Y-476168D01*
X321998Y-476252D01*
G01X394258Y-543563D02*
Y-518563D01*
G01X397031Y-520835D02*
Y-525835D01*
X399565D01*
G01X402638Y-520835D02*
X404158D01*
G01X403398D02*
Y-525835D01*
G01X402638D02*
X404158D01*
G01X409005Y-523168D02*
X409258Y-522918D01*
X409448Y-522502D01*
X409575Y-521918D01*
X409448Y-521418D01*
X409195Y-521085D01*
X408751Y-520835D01*
X407041D01*
Y-525835D01*
X409131D01*
X409575Y-525502D01*
X409828Y-525002D01*
X409955Y-524418D01*
X409828Y-523835D01*
X409448Y-523335D01*
X409005Y-523168D01*
X407041D01*
G01X413598Y-526002D02*
X413471Y-525918D01*
Y-525752D01*
X413598Y-525668D01*
X413725Y-525752D01*
Y-525918D01*
X413598Y-526002D01*
G01Y-523752D02*
X413471Y-523668D01*
Y-523502D01*
X413598Y-523418D01*
X413725Y-523502D01*
Y-523668D01*
X413598Y-523752D01*
G01X437258Y-518563D02*
Y-543563D01*
G01X437398Y-518335D02*
Y-543335D01*
G01X441298Y-520835D02*
Y-525835D01*
G01X439841Y-520835D02*
X442755D01*
G01X446398Y-525835D02*
X446018Y-525752D01*
X445638Y-525418D01*
X445385Y-524835D01*
X445258Y-524168D01*
X445385Y-523502D01*
X445638Y-522918D01*
X446018Y-522585D01*
X446398Y-522502D01*
X446778Y-522585D01*
X447158Y-522918D01*
X447411Y-523502D01*
X447475Y-524168D01*
X447411Y-524835D01*
X447158Y-525418D01*
X446778Y-525752D01*
X446398Y-525835D01*
G01X451498D02*
X451118Y-525752D01*
X450738Y-525418D01*
X450485Y-524835D01*
X450358Y-524168D01*
X450485Y-523502D01*
X450738Y-522918D01*
X451118Y-522585D01*
X451498Y-522502D01*
X451878Y-522585D01*
X452258Y-522918D01*
X452511Y-523502D01*
X452575Y-524168D01*
X452511Y-524835D01*
X452258Y-525418D01*
X451878Y-525752D01*
X451498Y-525835D01*
G01X456598D02*
Y-520835D01*
G01X461698Y-526002D02*
X461571Y-525918D01*
Y-525752D01*
X461698Y-525668D01*
X461825Y-525752D01*
Y-525918D01*
X461698Y-526002D01*
G01Y-523752D02*
X461571Y-523668D01*
Y-523502D01*
X461698Y-523418D01*
X461825Y-523502D01*
Y-523668D01*
X461698Y-523752D01*
G01X437398Y-493335D02*
Y-518335D01*
G01X440031Y-500835D02*
Y-495835D01*
X441615D01*
X442121Y-496085D01*
X442438Y-496418D01*
X442565Y-497085D01*
X442438Y-497752D01*
X442058Y-498168D01*
X441615Y-498418D01*
X440031D01*
G01X441615D02*
X442565Y-500835D01*
G01X447665D02*
X445131D01*
Y-495835D01*
X447665D01*
G01X446651Y-498252D02*
X445131D01*
G01X449915Y-495835D02*
X451498Y-500835D01*
X453081Y-495835D01*
G01X456598Y-501002D02*
X456471Y-500918D01*
Y-500752D01*
X456598Y-500668D01*
X456725Y-500752D01*
Y-500918D01*
X456598Y-501002D01*
G01Y-498752D02*
X456471Y-498668D01*
Y-498502D01*
X456598Y-498418D01*
X456725Y-498502D01*
Y-498668D01*
X456598Y-498752D01*
G01X445411Y-546502D02*
X445518Y-546377D01*
X445598Y-546168D01*
X445651Y-545877D01*
X445598Y-545627D01*
X445491Y-545460D01*
X445305Y-545335D01*
X444585D01*
Y-547835D01*
X445465D01*
X445651Y-547668D01*
X445758Y-547418D01*
X445811Y-547127D01*
X445758Y-546835D01*
X445598Y-546585D01*
X445411Y-546502D01*
X444585D01*
G01X447878Y-547835D02*
Y-546168D01*
G01Y-546460D02*
X447771Y-546293D01*
X447611Y-546210D01*
X447425Y-546168D01*
X447238Y-546252D01*
X447078Y-546418D01*
X446971Y-546668D01*
X446918Y-547002D01*
X446971Y-547335D01*
X447078Y-547585D01*
X447238Y-547752D01*
X447425Y-547835D01*
X447611Y-547793D01*
X447771Y-547668D01*
X447878Y-547502D01*
G01X449198Y-547543D02*
X449331Y-547710D01*
X449518Y-547835D01*
X449678D01*
X449838Y-547752D01*
X449945Y-547627D01*
X449998Y-547460D01*
X449971Y-547210D01*
X449865Y-547085D01*
X449385Y-546835D01*
X449278Y-546543D01*
X449331Y-546335D01*
X449438Y-546210D01*
X449598Y-546168D01*
X449758Y-546210D01*
X449918Y-546335D01*
G01X451398Y-546710D02*
X452251D01*
X452171Y-546418D01*
X452038Y-546252D01*
X451851Y-546168D01*
X451665Y-546210D01*
X451505Y-546335D01*
X451398Y-546627D01*
X451345Y-546877D01*
Y-547127D01*
X451398Y-547377D01*
X451531Y-547627D01*
X451691Y-547793D01*
X451878Y-547835D01*
X452065Y-547752D01*
X452251Y-547502D01*
G01X453518Y-547835D02*
Y-545335D01*
G01Y-546585D02*
X453651Y-546335D01*
X453811Y-546210D01*
X453971Y-546168D01*
X454211Y-546252D01*
X454371Y-546418D01*
X454478Y-546710D01*
Y-547043D01*
X454425Y-547377D01*
X454318Y-547627D01*
X454131Y-547793D01*
X453971Y-547835D01*
X453811Y-547793D01*
X453651Y-547668D01*
X453518Y-547460D01*
G01X456198Y-547835D02*
X456038Y-547793D01*
X455878Y-547627D01*
X455771Y-547335D01*
X455718Y-547002D01*
X455771Y-546668D01*
X455878Y-546377D01*
X456038Y-546210D01*
X456198Y-546168D01*
X456358Y-546210D01*
X456518Y-546377D01*
X456625Y-546668D01*
X456651Y-547002D01*
X456625Y-547335D01*
X456518Y-547627D01*
X456358Y-547793D01*
X456198Y-547835D01*
G01X458878D02*
Y-546168D01*
G01Y-546460D02*
X458771Y-546293D01*
X458611Y-546210D01*
X458425Y-546168D01*
X458238Y-546252D01*
X458078Y-546418D01*
X457971Y-546668D01*
X457918Y-547002D01*
X457971Y-547335D01*
X458078Y-547585D01*
X458238Y-547752D01*
X458425Y-547835D01*
X458611Y-547793D01*
X458771Y-547668D01*
X458878Y-547502D01*
G01X460225Y-547835D02*
Y-546168D01*
G01Y-546502D02*
X460358Y-546335D01*
X460491Y-546210D01*
X460678Y-546168D01*
X460811Y-546210D01*
X460971Y-546335D01*
G01X463278Y-545335D02*
Y-547835D01*
G01Y-547460D02*
X463171Y-547668D01*
X463011Y-547793D01*
X462825Y-547835D01*
X462611Y-547752D01*
X462451Y-547543D01*
X462345Y-547293D01*
X462318Y-547002D01*
X462345Y-546710D01*
X462451Y-546460D01*
X462611Y-546252D01*
X462825Y-546168D01*
X463011Y-546210D01*
X463145Y-546293D01*
X463278Y-546460D01*
G01X466665Y-547835D02*
Y-545335D01*
X467331D01*
X467545Y-545460D01*
X467678Y-545627D01*
X467731Y-545960D01*
X467678Y-546293D01*
X467518Y-546502D01*
X467331Y-546627D01*
X466665D01*
G01X467331D02*
X467731Y-547835D01*
G01X468998Y-546710D02*
X469851D01*
X469771Y-546418D01*
X469638Y-546252D01*
X469451Y-546168D01*
X469265Y-546210D01*
X469105Y-546335D01*
X468998Y-546627D01*
X468945Y-546877D01*
Y-547127D01*
X468998Y-547377D01*
X469131Y-547627D01*
X469291Y-547793D01*
X469478Y-547835D01*
X469665Y-547752D01*
X469851Y-547502D01*
G01X471118Y-546168D02*
X471598Y-547835D01*
X472078Y-546168D01*
G01X473798Y-547918D02*
X473745Y-547877D01*
Y-547793D01*
X473798Y-547752D01*
X473851Y-547793D01*
Y-547877D01*
X473798Y-547918D01*
G01X475545Y-547543D02*
X475731Y-547752D01*
X475945Y-547835D01*
X476158Y-547752D01*
X476345Y-547502D01*
X476478Y-547127D01*
X476531Y-546752D01*
Y-546293D01*
X476478Y-545918D01*
X476345Y-545585D01*
X476185Y-545418D01*
X475998Y-545335D01*
X475785Y-545418D01*
X475625Y-545585D01*
X475518Y-545835D01*
X475465Y-546168D01*
X475518Y-546460D01*
X475651Y-546752D01*
X475811Y-546918D01*
X475998Y-546960D01*
X476211Y-546877D01*
X476371Y-546668D01*
X476531Y-546293D01*
G01X478411Y-546502D02*
X478518Y-546377D01*
X478598Y-546168D01*
X478651Y-545877D01*
X478598Y-545627D01*
X478491Y-545460D01*
X478305Y-545335D01*
X477585D01*
Y-547835D01*
X478465D01*
X478651Y-547668D01*
X478758Y-547418D01*
X478811Y-547127D01*
X478758Y-546835D01*
X478598Y-546585D01*
X478411Y-546502D01*
X477585D01*
G01X-1490433Y-1677216D02*
Y3837819D01*
X4496476D01*
Y-1677216D01*
X-1490433D01*
G01X-7782Y-515685D02*
X-6215D01*
Y-517575D01*
X-6685Y-518205D01*
X-7234Y-518625D01*
X-8017Y-518835D01*
X-8800Y-518625D01*
X-9349Y-518205D01*
X-9819Y-517575D01*
X-10132Y-516840D01*
X-10289Y-516000D01*
Y-515265D01*
X-10132Y-514635D01*
X-9819Y-513900D01*
X-9349Y-513270D01*
X-8879Y-512850D01*
X-8252Y-512535D01*
X-7704D01*
X-7077Y-512745D01*
X-6607Y-513165D01*
G01X-3675Y-512535D02*
Y-517050D01*
X-3362Y-517995D01*
X-2735Y-518625D01*
X-1952Y-518835D01*
X-1169Y-518625D01*
X-542Y-517995D01*
X-229Y-517050D01*
Y-512535D01*
G01X3408D02*
X5288D01*
G01X4348D02*
Y-518835D01*
G01X3408D02*
X5288D01*
G01X9003Y-517995D02*
X9630Y-518520D01*
X10335Y-518835D01*
X10961D01*
X11588Y-518520D01*
X12058Y-517995D01*
X12293Y-517260D01*
X12136Y-516525D01*
X11745Y-515895D01*
X11040Y-515475D01*
X10100Y-515265D01*
X9551Y-514845D01*
X9316Y-514110D01*
X9473Y-513375D01*
X9865Y-512850D01*
X10413Y-512535D01*
X10961D01*
X11510Y-512745D01*
X11980Y-513270D01*
G01X15303Y-518835D02*
Y-512535D01*
G01X18593D02*
Y-518835D01*
G01Y-515685D02*
X15303D01*
G01X21290Y-518835D02*
X23248Y-512535D01*
X25206Y-518835D01*
G01X24501Y-516630D02*
X21995D01*
G01X27746Y-518835D02*
Y-512535D01*
X31350Y-518835D01*
Y-512535D01*
G01X40425Y-518835D02*
Y-512535D01*
X41991D01*
X42618Y-512850D01*
X43088Y-513270D01*
X43480Y-513900D01*
X43793Y-514635D01*
X43871Y-515685D01*
X43793Y-516735D01*
X43480Y-517470D01*
X43088Y-518100D01*
X42618Y-518520D01*
X41991Y-518835D01*
X40425D01*
G01X47508Y-512535D02*
X49388D01*
G01X48448D02*
Y-518835D01*
G01X47508D02*
X49388D01*
G01X53103Y-517995D02*
X53730Y-518520D01*
X54435Y-518835D01*
X55061D01*
X55688Y-518520D01*
X56158Y-517995D01*
X56393Y-517260D01*
X56236Y-516525D01*
X55845Y-515895D01*
X55140Y-515475D01*
X54200Y-515265D01*
X53651Y-514845D01*
X53416Y-514110D01*
X53573Y-513375D01*
X53965Y-512850D01*
X54513Y-512535D01*
X55061D01*
X55610Y-512745D01*
X56080Y-513270D01*
G01X61048Y-512535D02*
Y-518835D01*
G01X59246Y-512535D02*
X62850D01*
G01X67348Y-519045D02*
X67191Y-518940D01*
Y-518730D01*
X67348Y-518625D01*
X67505Y-518730D01*
Y-518940D01*
X67348Y-519045D01*
G01X73491Y-519990D02*
X73805Y-518625D01*
G01X79948Y-512535D02*
Y-518835D01*
G01X78146Y-512535D02*
X81750D01*
G01X84290Y-518835D02*
X86248Y-512535D01*
X88206Y-518835D01*
G01X87501Y-516630D02*
X84995D01*
G01X92548Y-518835D02*
X91921Y-518730D01*
X91373Y-518310D01*
X90903Y-517680D01*
X90590Y-516945D01*
X90433Y-516105D01*
Y-515265D01*
X90590Y-514425D01*
X90903Y-513690D01*
X91373Y-513060D01*
X91921Y-512640D01*
X92548Y-512535D01*
X93175Y-512640D01*
X93723Y-513060D01*
X94193Y-513690D01*
X94506Y-514425D01*
X94663Y-515265D01*
Y-516105D01*
X94506Y-516945D01*
X94193Y-517680D01*
X93723Y-518310D01*
X93175Y-518730D01*
X92548Y-518835D01*
G01X98848D02*
Y-516000D01*
X97281Y-512535D01*
G01X100415D02*
X98848Y-516000D01*
G01X103425Y-512535D02*
Y-517050D01*
X103738Y-517995D01*
X104365Y-518625D01*
X105148Y-518835D01*
X105931Y-518625D01*
X106558Y-517995D01*
X106871Y-517050D01*
Y-512535D01*
G01X109490Y-518835D02*
X111448Y-512535D01*
X113406Y-518835D01*
G01X112701Y-516630D02*
X110195D01*
G01X115946Y-518835D02*
Y-512535D01*
X119550Y-518835D01*
Y-512535D01*
G01X-6529Y-523060D02*
X-6999Y-522745D01*
X-7547Y-522535D01*
X-8174D01*
X-8879Y-522850D01*
X-9427Y-523375D01*
X-9819Y-524005D01*
X-10132Y-525055D01*
X-10210Y-526000D01*
X-10054Y-526945D01*
X-9819Y-527575D01*
X-9349Y-528205D01*
X-8800Y-528625D01*
X-8252Y-528835D01*
X-7704D01*
X-7155Y-528625D01*
X-6685Y-528310D01*
X-6294Y-527890D01*
G01X-2892Y-522535D02*
X-1012D01*
G01X-1952D02*
Y-528835D01*
G01X-2892D02*
X-1012D01*
G01X4348Y-522535D02*
Y-528835D01*
G01X2546Y-522535D02*
X6150D01*
G01X10648Y-528835D02*
Y-526000D01*
X9081Y-522535D01*
G01X12215D02*
X10648Y-526000D01*
G01X21525Y-527575D02*
X21995Y-528310D01*
X22621Y-528730D01*
X23326Y-528835D01*
X23953Y-528730D01*
X24580Y-528205D01*
X24971Y-527575D01*
X25050Y-526945D01*
X24893Y-526210D01*
X24345Y-525685D01*
X23796Y-525475D01*
X23091D01*
G01X23796D02*
X24266Y-525160D01*
X24658Y-524635D01*
X24815Y-524005D01*
X24658Y-523375D01*
X24266Y-522850D01*
X23561Y-522535D01*
X22856Y-522640D01*
X22151Y-523060D01*
G01X27825Y-527575D02*
X28295Y-528310D01*
X28921Y-528730D01*
X29626Y-528835D01*
X30253Y-528730D01*
X30880Y-528205D01*
X31271Y-527575D01*
X31350Y-526945D01*
X31193Y-526210D01*
X30645Y-525685D01*
X30096Y-525475D01*
X29391D01*
G01X30096D02*
X30566Y-525160D01*
X30958Y-524635D01*
X31115Y-524005D01*
X30958Y-523375D01*
X30566Y-522850D01*
X29861Y-522535D01*
X29156Y-522640D01*
X28451Y-523060D01*
G01X34125Y-527575D02*
X34595Y-528310D01*
X35221Y-528730D01*
X35926Y-528835D01*
X36553Y-528730D01*
X37180Y-528205D01*
X37571Y-527575D01*
X37650Y-526945D01*
X37493Y-526210D01*
X36945Y-525685D01*
X36396Y-525475D01*
X35691D01*
G01X36396D02*
X36866Y-525160D01*
X37258Y-524635D01*
X37415Y-524005D01*
X37258Y-523375D01*
X36866Y-522850D01*
X36161Y-522535D01*
X35456Y-522640D01*
X34751Y-523060D01*
G01X41991Y-528835D02*
X42148Y-527470D01*
X42383Y-526315D01*
X42696Y-525265D01*
X43088Y-524110D01*
X43715Y-522535D01*
X40581D01*
G01X48291Y-528835D02*
X48448Y-527470D01*
X48683Y-526315D01*
X48996Y-525265D01*
X49388Y-524110D01*
X50015Y-522535D01*
X46881D01*
G01X54591Y-529990D02*
X54905Y-528625D01*
G01X61048Y-522535D02*
Y-528835D01*
G01X59246Y-522535D02*
X62850D01*
G01X65390Y-528835D02*
X67348Y-522535D01*
X69306Y-528835D01*
G01X68601Y-526630D02*
X66095D01*
G01X72708Y-522535D02*
X74588D01*
G01X73648D02*
Y-528835D01*
G01X72708D02*
X74588D01*
G01X77598Y-522535D02*
X78695Y-528835D01*
X79948Y-522535D01*
X81201Y-528835D01*
X82298Y-522535D01*
G01X84290Y-528835D02*
X86248Y-522535D01*
X88206Y-528835D01*
G01X87501Y-526630D02*
X84995D01*
G01X90746Y-528835D02*
Y-522535D01*
X94350Y-528835D01*
Y-522535D01*
G01X104756Y-530935D02*
X103973Y-529885D01*
X103581Y-528835D01*
Y-524635D01*
X103973Y-523585D01*
X104756Y-522535D01*
G01X116181Y-528835D02*
Y-522535D01*
X118140D01*
X118766Y-522850D01*
X119158Y-523270D01*
X119315Y-524110D01*
X119158Y-524950D01*
X118688Y-525475D01*
X118140Y-525790D01*
X116181D01*
G01X118140D02*
X119315Y-528835D01*
G01X124048Y-529045D02*
X123891Y-528940D01*
Y-528730D01*
X124048Y-528625D01*
X124205Y-528730D01*
Y-528940D01*
X124048Y-529045D01*
G01X130348Y-528835D02*
X129721Y-528730D01*
X129173Y-528310D01*
X128703Y-527680D01*
X128390Y-526945D01*
X128233Y-526105D01*
Y-525265D01*
X128390Y-524425D01*
X128703Y-523690D01*
X129173Y-523060D01*
X129721Y-522640D01*
X130348Y-522535D01*
X130975Y-522640D01*
X131523Y-523060D01*
X131993Y-523690D01*
X132306Y-524425D01*
X132463Y-525265D01*
Y-526105D01*
X132306Y-526945D01*
X131993Y-527680D01*
X131523Y-528310D01*
X130975Y-528730D01*
X130348Y-528835D01*
G01X136648Y-529045D02*
X136491Y-528940D01*
Y-528730D01*
X136648Y-528625D01*
X136805Y-528730D01*
Y-528940D01*
X136648Y-529045D01*
G01X144671Y-523060D02*
X144201Y-522745D01*
X143653Y-522535D01*
X143026D01*
X142321Y-522850D01*
X141773Y-523375D01*
X141381Y-524005D01*
X141068Y-525055D01*
X140990Y-526000D01*
X141146Y-526945D01*
X141381Y-527575D01*
X141851Y-528205D01*
X142400Y-528625D01*
X142948Y-528835D01*
X143496D01*
X144045Y-528625D01*
X144515Y-528310D01*
X144906Y-527890D01*
G01X149248Y-529045D02*
X149091Y-528940D01*
Y-528730D01*
X149248Y-528625D01*
X149405Y-528730D01*
Y-528940D01*
X149248Y-529045D01*
G01X155940Y-530935D02*
X156723Y-529885D01*
X157115Y-528835D01*
Y-524635D01*
X156723Y-523585D01*
X155940Y-522535D01*
G01X-10054Y-508835D02*
Y-502535D01*
X-6450Y-508835D01*
Y-502535D01*
G01X-1952Y-508835D02*
X-2579Y-508730D01*
X-3127Y-508310D01*
X-3597Y-507680D01*
X-3910Y-506945D01*
X-4067Y-506105D01*
Y-505265D01*
X-3910Y-504425D01*
X-3597Y-503690D01*
X-3127Y-503060D01*
X-2579Y-502640D01*
X-1952Y-502535D01*
X-1325Y-502640D01*
X-777Y-503060D01*
X-307Y-503690D01*
X6Y-504425D01*
X163Y-505265D01*
Y-506105D01*
X6Y-506945D01*
X-307Y-507680D01*
X-777Y-508310D01*
X-1325Y-508730D01*
X-1952Y-508835D01*
G01X4348Y-509045D02*
X4191Y-508940D01*
Y-508730D01*
X4348Y-508625D01*
X4505Y-508730D01*
Y-508940D01*
X4348Y-509045D01*
G01X9160Y-503585D02*
X9630Y-502955D01*
X10178Y-502640D01*
X10805Y-502535D01*
X11588Y-502745D01*
X12136Y-503270D01*
X12293Y-503900D01*
X12215Y-504530D01*
X11901Y-505055D01*
X10335Y-506105D01*
X9630Y-506840D01*
X9160Y-507890D01*
X9003Y-508835D01*
X12293D01*
G01X16948D02*
Y-502535D01*
X16008Y-503795D01*
G01Y-508835D02*
X17888D01*
G01X23248D02*
Y-502535D01*
X22308Y-503795D01*
G01Y-508835D02*
X24188D01*
G01X29391Y-509990D02*
X29705Y-508625D01*
G01X33498Y-502535D02*
X34595Y-508835D01*
X35848Y-502535D01*
X37101Y-508835D01*
X38198Y-502535D01*
G01X43715Y-508835D02*
X40581D01*
Y-502535D01*
X43715D01*
G01X42461Y-505580D02*
X40581D01*
G01X46646Y-508835D02*
Y-502535D01*
X50250Y-508835D01*
Y-502535D01*
G01X53103Y-508835D02*
Y-502535D01*
G01X56393D02*
Y-508835D01*
G01Y-505685D02*
X53103D01*
G01X59325Y-502535D02*
Y-507050D01*
X59638Y-507995D01*
X60265Y-508625D01*
X61048Y-508835D01*
X61831Y-508625D01*
X62458Y-507995D01*
X62771Y-507050D01*
Y-502535D01*
G01X65390Y-508835D02*
X67348Y-502535D01*
X69306Y-508835D01*
G01X68601Y-506630D02*
X66095D01*
G01X78460Y-503585D02*
X78930Y-502955D01*
X79478Y-502640D01*
X80105Y-502535D01*
X80888Y-502745D01*
X81436Y-503270D01*
X81593Y-503900D01*
X81515Y-504530D01*
X81201Y-505055D01*
X79635Y-506105D01*
X78930Y-506840D01*
X78460Y-507890D01*
X78303Y-508835D01*
X81593D01*
G01X84446D02*
Y-502535D01*
X88050Y-508835D01*
Y-502535D01*
G01X90825Y-508835D02*
Y-502535D01*
X92391D01*
X93018Y-502850D01*
X93488Y-503270D01*
X93880Y-503900D01*
X94193Y-504635D01*
X94271Y-505685D01*
X94193Y-506735D01*
X93880Y-507470D01*
X93488Y-508100D01*
X93018Y-508520D01*
X92391Y-508835D01*
X90825D01*
G01X103581D02*
Y-502535D01*
X105540D01*
X106166Y-502850D01*
X106558Y-503270D01*
X106715Y-504110D01*
X106558Y-504950D01*
X106088Y-505475D01*
X105540Y-505790D01*
X103581D01*
G01X105540D02*
X106715Y-508835D01*
G01X109725D02*
Y-502535D01*
X111291D01*
X111918Y-502850D01*
X112388Y-503270D01*
X112780Y-503900D01*
X113093Y-504635D01*
X113171Y-505685D01*
X113093Y-506735D01*
X112780Y-507470D01*
X112388Y-508100D01*
X111918Y-508520D01*
X111291Y-508835D01*
X109725D01*
G01X117748Y-509045D02*
X117591Y-508940D01*
Y-508730D01*
X117748Y-508625D01*
X117905Y-508730D01*
Y-508940D01*
X117748Y-509045D01*
G01X14048Y-498135D02*
X11528Y-497718D01*
X9323Y-496052D01*
X7433Y-493552D01*
X6173Y-490635D01*
X5543Y-487302D01*
Y-483968D01*
X6173Y-480635D01*
X7433Y-477718D01*
X9323Y-475219D01*
X11528Y-473552D01*
X14048Y-473135D01*
X16568Y-473552D01*
X18773Y-475219D01*
X20663Y-477718D01*
X21923Y-480635D01*
X22553Y-483968D01*
Y-487302D01*
X21923Y-490635D01*
X20663Y-493552D01*
X18773Y-496052D01*
X16568Y-497718D01*
X14048Y-498135D01*
G01X16568Y-491468D02*
X20348Y-498135D01*
G01X33893Y-481469D02*
Y-493135D01*
X35153Y-496052D01*
X37043Y-497718D01*
X39248Y-498135D01*
X41453Y-497718D01*
X43343Y-496052D01*
X44603Y-493135D01*
G01Y-498135D02*
Y-481469D01*
G01X70118Y-498135D02*
Y-481469D01*
G01Y-484385D02*
X68858Y-482719D01*
X66968Y-481885D01*
X64763Y-481469D01*
X62558Y-482302D01*
X60668Y-483968D01*
X59408Y-486469D01*
X58778Y-489802D01*
X59408Y-493135D01*
X60668Y-495636D01*
X62558Y-497302D01*
X64763Y-498135D01*
X66968Y-497718D01*
X68858Y-496469D01*
X70118Y-494802D01*
G01X84293Y-498135D02*
Y-481469D01*
G01Y-485635D02*
X85553Y-483552D01*
X87443Y-481885D01*
X89963Y-481469D01*
X92168Y-481885D01*
X94058Y-483552D01*
X95003Y-486469D01*
Y-498135D01*
G01X114848Y-473135D02*
Y-498135D01*
G01X110438Y-481469D02*
X119258D01*
G01X145718Y-498135D02*
Y-481469D01*
G01Y-484385D02*
X144458Y-482719D01*
X142568Y-481885D01*
X140363Y-481469D01*
X138158Y-482302D01*
X136268Y-483968D01*
X135008Y-486469D01*
X134378Y-489802D01*
X135008Y-493135D01*
X136268Y-495636D01*
X138158Y-497302D01*
X140363Y-498135D01*
X142568Y-497718D01*
X144458Y-496469D01*
X145718Y-494802D01*
G01X185398Y-477835D02*
Y-485835D01*
X189398D01*
G01X197198D02*
Y-480502D01*
G01Y-481435D02*
X196798Y-480902D01*
X196198Y-480635D01*
X195498Y-480502D01*
X194798Y-480768D01*
X194198Y-481302D01*
X193798Y-482102D01*
X193598Y-483168D01*
X193798Y-484235D01*
X194198Y-485035D01*
X194798Y-485568D01*
X195498Y-485835D01*
X196198Y-485702D01*
X196798Y-485302D01*
X197198Y-484769D01*
G01X201298Y-488235D02*
X201898Y-488502D01*
X202698Y-488235D01*
X203198Y-487702D01*
X203598Y-487035D01*
X204198Y-484902D01*
X205498Y-480502D01*
G01X202298D02*
X204198Y-484902D01*
G01X209898Y-482235D02*
X213098D01*
X212798Y-481302D01*
X212298Y-480768D01*
X211598Y-480502D01*
X210898Y-480635D01*
X210298Y-481035D01*
X209898Y-481968D01*
X209698Y-482769D01*
Y-483568D01*
X209898Y-484368D01*
X210398Y-485168D01*
X210998Y-485702D01*
X211698Y-485835D01*
X212398Y-485568D01*
X213098Y-484769D01*
G01X217998Y-485835D02*
Y-480502D01*
G01Y-481568D02*
X218498Y-481035D01*
X218998Y-480635D01*
X219698Y-480502D01*
X220198Y-480635D01*
X220798Y-481035D01*
G01X211398Y-535835D02*
Y-532235D01*
X209398Y-527835D01*
G01X213398D02*
X211398Y-532235D01*
G01X217698Y-530502D02*
Y-534235D01*
X218098Y-535168D01*
X218698Y-535702D01*
X219398Y-535835D01*
X220098Y-535702D01*
X220698Y-535168D01*
X221098Y-534235D01*
G01Y-535835D02*
Y-530502D01*
G01X225698Y-535835D02*
Y-530502D01*
G01Y-531835D02*
X226098Y-531168D01*
X226698Y-530635D01*
X227498Y-530502D01*
X228198Y-530635D01*
X228798Y-531168D01*
X229098Y-532102D01*
Y-535835D01*
G01X237198D02*
Y-530502D01*
G01Y-531435D02*
X236798Y-530902D01*
X236198Y-530635D01*
X235498Y-530502D01*
X234798Y-530768D01*
X234198Y-531302D01*
X233798Y-532102D01*
X233598Y-533168D01*
X233798Y-534235D01*
X234198Y-535035D01*
X234798Y-535568D01*
X235498Y-535835D01*
X236198Y-535702D01*
X236798Y-535302D01*
X237198Y-534769D01*
G01X214498Y-506835D02*
X216498D01*
Y-509235D01*
X215898Y-510035D01*
X215198Y-510568D01*
X214198Y-510835D01*
X213198Y-510568D01*
X212498Y-510035D01*
X211898Y-509235D01*
X211498Y-508302D01*
X211298Y-507235D01*
Y-506302D01*
X211498Y-505502D01*
X211898Y-504568D01*
X212498Y-503768D01*
X213098Y-503235D01*
X213898Y-502835D01*
X214598D01*
X215398Y-503102D01*
X215998Y-503635D01*
G01X219598Y-510835D02*
Y-502835D01*
X224198Y-510835D01*
Y-502835D01*
G01X227698Y-510835D02*
Y-502835D01*
X229698D01*
X230498Y-503235D01*
X231098Y-503768D01*
X231598Y-504568D01*
X231998Y-505502D01*
X232098Y-506835D01*
X231998Y-508168D01*
X231598Y-509102D01*
X231098Y-509902D01*
X230498Y-510435D01*
X229698Y-510835D01*
X227698D01*
G01X236998Y-479168D02*
X237598Y-478368D01*
X238298Y-477968D01*
X239098Y-477835D01*
X240098Y-478102D01*
X240798Y-478768D01*
X240998Y-479568D01*
X240898Y-480369D01*
X240498Y-481035D01*
X238498Y-482368D01*
X237598Y-483302D01*
X236998Y-484635D01*
X236798Y-485835D01*
X240998D01*
G01X311998Y-529168D02*
X312598Y-528368D01*
X313298Y-527968D01*
X314098Y-527835D01*
X315098Y-528102D01*
X315798Y-528768D01*
X315998Y-529568D01*
X315898Y-530369D01*
X315498Y-531035D01*
X313498Y-532368D01*
X312598Y-533302D01*
X311998Y-534635D01*
X311798Y-535835D01*
X315998D01*
G01X321898Y-527835D02*
X321098Y-528102D01*
X320498Y-528768D01*
X320098Y-529568D01*
X319798Y-530635D01*
X319698Y-531835D01*
X319798Y-533035D01*
X320098Y-534102D01*
X320498Y-534902D01*
X321098Y-535568D01*
X321898Y-535835D01*
X322698Y-535568D01*
X323298Y-534902D01*
X323698Y-534102D01*
X323998Y-533035D01*
X324098Y-531835D01*
X323998Y-530635D01*
X323698Y-529568D01*
X323298Y-528768D01*
X322698Y-528102D01*
X321898Y-527835D01*
G01X327998Y-529168D02*
X328598Y-528368D01*
X329298Y-527968D01*
X330098Y-527835D01*
X331098Y-528102D01*
X331798Y-528768D01*
X331998Y-529568D01*
X331898Y-530369D01*
X331498Y-531035D01*
X329498Y-532368D01*
X328598Y-533302D01*
X327998Y-534635D01*
X327798Y-535835D01*
X331998D01*
G01X335698Y-534235D02*
X336298Y-535168D01*
X337098Y-535702D01*
X337998Y-535835D01*
X338798Y-535702D01*
X339598Y-535035D01*
X340098Y-534235D01*
X340198Y-533435D01*
X339998Y-532502D01*
X339298Y-531835D01*
X338598Y-531568D01*
X337698D01*
G01X338598D02*
X339198Y-531168D01*
X339698Y-530502D01*
X339898Y-529702D01*
X339698Y-528902D01*
X339198Y-528235D01*
X338298Y-527835D01*
X337398Y-527968D01*
X336498Y-528502D01*
G01X344098Y-536102D02*
X347698Y-527835D01*
G01X353898D02*
X353098Y-528102D01*
X352498Y-528768D01*
X352098Y-529568D01*
X351798Y-530635D01*
X351698Y-531835D01*
X351798Y-533035D01*
X352098Y-534102D01*
X352498Y-534902D01*
X353098Y-535568D01*
X353898Y-535835D01*
X354698Y-535568D01*
X355298Y-534902D01*
X355698Y-534102D01*
X355998Y-533035D01*
X356098Y-531835D01*
X355998Y-530635D01*
X355698Y-529568D01*
X355298Y-528768D01*
X354698Y-528102D01*
X353898Y-527835D01*
G01X361898Y-535835D02*
Y-527835D01*
X360698Y-529435D01*
G01Y-535835D02*
X363098D01*
G01X368098Y-536102D02*
X371698Y-527835D01*
G01X377898D02*
X377098Y-528102D01*
X376498Y-528768D01*
X376098Y-529568D01*
X375798Y-530635D01*
X375698Y-531835D01*
X375798Y-533035D01*
X376098Y-534102D01*
X376498Y-534902D01*
X377098Y-535568D01*
X377898Y-535835D01*
X378698Y-535568D01*
X379298Y-534902D01*
X379698Y-534102D01*
X379998Y-533035D01*
X380098Y-531835D01*
X379998Y-530635D01*
X379698Y-529568D01*
X379298Y-528768D01*
X378698Y-528102D01*
X377898Y-527835D01*
G01X384198Y-534902D02*
X384898Y-535568D01*
X385698Y-535835D01*
X386498Y-535568D01*
X387198Y-534769D01*
X387698Y-533568D01*
X387898Y-532368D01*
Y-530902D01*
X387698Y-529702D01*
X387198Y-528635D01*
X386598Y-528102D01*
X385898Y-527835D01*
X385098Y-528102D01*
X384498Y-528635D01*
X384098Y-529435D01*
X383898Y-530502D01*
X384098Y-531435D01*
X384598Y-532368D01*
X385198Y-532902D01*
X385898Y-533035D01*
X386698Y-532769D01*
X387298Y-532102D01*
X387898Y-530902D01*
G01X311698Y-510835D02*
Y-502835D01*
X313698D01*
X314498Y-503235D01*
X315098Y-503768D01*
X315598Y-504568D01*
X315998Y-505502D01*
X316098Y-506835D01*
X315998Y-508168D01*
X315598Y-509102D01*
X315098Y-509902D01*
X314498Y-510435D01*
X313698Y-510835D01*
X311698D01*
G01X319398D02*
X321898Y-502835D01*
X324398Y-510835D01*
G01X323498Y-508035D02*
X320298D01*
G01X329898Y-502835D02*
X329098Y-503102D01*
X328498Y-503768D01*
X328098Y-504568D01*
X327798Y-505635D01*
X327698Y-506835D01*
X327798Y-508035D01*
X328098Y-509102D01*
X328498Y-509902D01*
X329098Y-510568D01*
X329898Y-510835D01*
X330698Y-510568D01*
X331298Y-509902D01*
X331698Y-509102D01*
X331998Y-508035D01*
X332098Y-506835D01*
X331998Y-505635D01*
X331698Y-504568D01*
X331298Y-503768D01*
X330698Y-503102D01*
X329898Y-502835D01*
G01X335998Y-510835D02*
Y-502835D01*
X339798D01*
G01X338398Y-506702D02*
X335998D01*
G01X345898Y-502835D02*
X345098Y-503102D01*
X344498Y-503768D01*
X344098Y-504568D01*
X343798Y-505635D01*
X343698Y-506835D01*
X343798Y-508035D01*
X344098Y-509102D01*
X344498Y-509902D01*
X345098Y-510568D01*
X345898Y-510835D01*
X346698Y-510568D01*
X347298Y-509902D01*
X347698Y-509102D01*
X347998Y-508035D01*
X348098Y-506835D01*
X347998Y-505635D01*
X347698Y-504568D01*
X347298Y-503768D01*
X346698Y-503102D01*
X345898Y-502835D01*
G01X353898D02*
Y-510835D01*
G01X351598Y-502835D02*
X356198D01*
G01X363898Y-510835D02*
X359898D01*
Y-502835D01*
X363898D01*
G01X362298Y-506702D02*
X359898D01*
G01X370698Y-506568D02*
X371098Y-506168D01*
X371398Y-505502D01*
X371598Y-504568D01*
X371398Y-503768D01*
X370998Y-503235D01*
X370298Y-502835D01*
X367598D01*
Y-510835D01*
X370898D01*
X371598Y-510302D01*
X371998Y-509502D01*
X372198Y-508568D01*
X371998Y-507635D01*
X371398Y-506835D01*
X370698Y-506568D01*
X367598D01*
G01X376698Y-502835D02*
X379098D01*
G01X377898D02*
Y-510835D01*
G01X376698D02*
X379098D01*
G01X383998D02*
Y-502835D01*
X387798D01*
G01X386398Y-506702D02*
X383998D01*
G01X393898Y-502835D02*
X393098Y-503102D01*
X392498Y-503768D01*
X392098Y-504568D01*
X391798Y-505635D01*
X391698Y-506835D01*
X391798Y-508035D01*
X392098Y-509102D01*
X392498Y-509902D01*
X393098Y-510568D01*
X393898Y-510835D01*
X394698Y-510568D01*
X395298Y-509902D01*
X395698Y-509102D01*
X395998Y-508035D01*
X396098Y-506835D01*
X395998Y-505635D01*
X395698Y-504568D01*
X395298Y-503768D01*
X394698Y-503102D01*
X393898Y-502835D01*
G01X329498Y-485835D02*
Y-477835D01*
X333298D01*
G01X331898Y-481702D02*
X329498D01*
G01X339398Y-477835D02*
X338598Y-478102D01*
X337998Y-478768D01*
X337598Y-479568D01*
X337298Y-480635D01*
X337198Y-481835D01*
X337298Y-483035D01*
X337598Y-484102D01*
X337998Y-484902D01*
X338598Y-485568D01*
X339398Y-485835D01*
X340198Y-485568D01*
X340798Y-484902D01*
X341198Y-484102D01*
X341498Y-483035D01*
X341598Y-481835D01*
X341498Y-480635D01*
X341198Y-479568D01*
X340798Y-478768D01*
X340198Y-478102D01*
X339398Y-477835D01*
G01X347398D02*
Y-485835D01*
G01X345098Y-477835D02*
X349698D01*
G01X352398Y-488502D02*
X358398D01*
G01X361898Y-482235D02*
X365098D01*
X364798Y-481302D01*
X364298Y-480768D01*
X363598Y-480502D01*
X362898Y-480635D01*
X362298Y-481035D01*
X361898Y-481968D01*
X361698Y-482769D01*
Y-483568D01*
X361898Y-484368D01*
X362398Y-485168D01*
X362998Y-485702D01*
X363698Y-485835D01*
X364398Y-485568D01*
X365098Y-484769D01*
G01X369898Y-480502D02*
X372898Y-485835D01*
G01Y-480502D02*
X369898Y-485835D01*
G01X377598Y-488502D02*
Y-480502D01*
G01Y-481702D02*
X378098Y-481035D01*
X378598Y-480635D01*
X379398Y-480502D01*
X380098Y-480635D01*
X380798Y-481302D01*
X381098Y-482235D01*
X381198Y-483168D01*
X381098Y-484102D01*
X380798Y-485035D01*
X380198Y-485568D01*
X379398Y-485835D01*
X378698Y-485702D01*
X377998Y-485302D01*
X377598Y-484769D01*
G01X389198Y-485835D02*
Y-480502D01*
G01Y-481435D02*
X388798Y-480902D01*
X388198Y-480635D01*
X387498Y-480502D01*
X386798Y-480768D01*
X386198Y-481302D01*
X385798Y-482102D01*
X385598Y-483168D01*
X385798Y-484235D01*
X386198Y-485035D01*
X386798Y-485568D01*
X387498Y-485835D01*
X388198Y-485702D01*
X388798Y-485302D01*
X389198Y-484769D01*
G01X393698Y-485835D02*
Y-480502D01*
G01Y-481835D02*
X394098Y-481168D01*
X394698Y-480635D01*
X395498Y-480502D01*
X396198Y-480635D01*
X396798Y-481168D01*
X397098Y-482102D01*
Y-485835D01*
G01X405198Y-477835D02*
Y-485835D01*
G01Y-484635D02*
X404798Y-485302D01*
X404198Y-485702D01*
X403498Y-485835D01*
X402698Y-485568D01*
X402098Y-484902D01*
X401698Y-484102D01*
X401598Y-483168D01*
X401698Y-482235D01*
X402098Y-481435D01*
X402698Y-480768D01*
X403498Y-480502D01*
X404198Y-480635D01*
X404698Y-480902D01*
X405198Y-481435D01*
G01X409898Y-482235D02*
X413098D01*
X412798Y-481302D01*
X412298Y-480768D01*
X411598Y-480502D01*
X410898Y-480635D01*
X410298Y-481035D01*
X409898Y-481968D01*
X409698Y-482769D01*
Y-483568D01*
X409898Y-484368D01*
X410398Y-485168D01*
X410998Y-485702D01*
X411698Y-485835D01*
X412398Y-485568D01*
X413098Y-484769D01*
G01X417998Y-485835D02*
Y-480502D01*
G01Y-481568D02*
X418498Y-481035D01*
X418998Y-480635D01*
X419698Y-480502D01*
X420198Y-480635D01*
X420798Y-481035D01*
G01X424398Y-488502D02*
X430398D01*
G01X433598Y-485835D02*
Y-477835D01*
G01Y-481835D02*
X434098Y-481035D01*
X434698Y-480635D01*
X435298Y-480502D01*
X436198Y-480768D01*
X436798Y-481302D01*
X437198Y-482235D01*
Y-483302D01*
X436998Y-484368D01*
X436598Y-485168D01*
X435898Y-485702D01*
X435298Y-485835D01*
X434698Y-485702D01*
X434098Y-485302D01*
X433598Y-484635D01*
G01X445198Y-477835D02*
Y-485835D01*
G01Y-484635D02*
X444798Y-485302D01*
X444198Y-485702D01*
X443498Y-485835D01*
X442698Y-485568D01*
X442098Y-484902D01*
X441698Y-484102D01*
X441598Y-483168D01*
X441698Y-482235D01*
X442098Y-481435D01*
X442698Y-480768D01*
X443498Y-480502D01*
X444198Y-480635D01*
X444698Y-480902D01*
X445198Y-481435D01*
G01X400398Y-538835D02*
Y-530835D01*
X399198Y-532435D01*
G01Y-538835D02*
X401598D01*
G01X406498Y-535502D02*
X407198Y-534568D01*
X407798Y-534035D01*
X408598Y-533768D01*
X409298Y-534035D01*
X409798Y-534568D01*
X410198Y-535368D01*
X410298Y-536302D01*
X410198Y-537102D01*
X409798Y-537902D01*
X409198Y-538568D01*
X408498Y-538835D01*
X407698Y-538568D01*
X406998Y-537769D01*
X406598Y-536568D01*
X406498Y-535235D01*
X406698Y-533502D01*
X406998Y-532568D01*
X407498Y-531635D01*
X408198Y-530968D01*
X408898Y-530835D01*
X409598Y-531102D01*
X410098Y-531768D01*
G01X416398Y-539102D02*
X416198Y-538968D01*
Y-538702D01*
X416398Y-538568D01*
X416598Y-538702D01*
Y-538968D01*
X416398Y-539102D01*
G01X422498Y-535502D02*
X423198Y-534568D01*
X423798Y-534035D01*
X424598Y-533768D01*
X425298Y-534035D01*
X425798Y-534568D01*
X426198Y-535368D01*
X426298Y-536302D01*
X426198Y-537102D01*
X425798Y-537902D01*
X425198Y-538568D01*
X424498Y-538835D01*
X423698Y-538568D01*
X422998Y-537769D01*
X422598Y-536568D01*
X422498Y-535235D01*
X422698Y-533502D01*
X422998Y-532568D01*
X423498Y-531635D01*
X424198Y-530968D01*
X424898Y-530835D01*
X425598Y-531102D01*
X426098Y-531768D01*
G01X445398Y-538835D02*
Y-530835D01*
X444198Y-532435D01*
G01Y-538835D02*
X446598D01*
G01X453198D02*
X453398Y-537102D01*
X453698Y-535635D01*
X454098Y-534302D01*
X454598Y-532835D01*
X455398Y-530835D01*
X451398D01*
G01X461398Y-539102D02*
X461198Y-538968D01*
Y-538702D01*
X461398Y-538568D01*
X461598Y-538702D01*
Y-538968D01*
X461398Y-539102D01*
G01X467498Y-532168D02*
X468098Y-531368D01*
X468798Y-530968D01*
X469598Y-530835D01*
X470598Y-531102D01*
X471298Y-531768D01*
X471498Y-532568D01*
X471398Y-533369D01*
X470998Y-534035D01*
X468998Y-535368D01*
X468098Y-536302D01*
X467498Y-537635D01*
X467298Y-538835D01*
X471498D01*
G01X465498Y-513835D02*
Y-505835D01*
X469298D01*
G01X467898Y-509702D02*
X465498D01*
M02*
